G04 ================== begin FILE IDENTIFICATION RECORD ==================*
G04 Layout Name:  17301-sa.brd*
G04 Film Name:    17301-sa_X_Y*
G04 File Format:  Gerber RS274X*
G04 File Origin:  Cadence Allegro 16.6-2015-S079*
G04 Origin Date:  Thu Jun 22 17:49:45 2017*
G04 *
G04 Layer:  BOARD GEOMETRY/PANEL_DRAWING*
G04 *
G04 Offset:    (0.00 0.00)*
G04 Mirror:    No*
G04 Mode:      Positive*
G04 Rotation:  0*
G04 FullContactRelief:  No*
G04 UndefLineWidth:     6.00*
G04 ================== end FILE IDENTIFICATION RECORD ====================*
%FSLAX35Y35*MOIN*%
%IR0*IPPOS*OFA0.00000B0.00000*MIA0B0*SFA1.00000B1.00000*%
%ADD10C,.006*%
G75*
%LPD*%
G75*
G54D10*
G01X-257603Y-331509D02*
Y-325209D01*
X-254627D01*
G01X-255723Y-328254D02*
X-257603D01*
G01X-254548Y-95288D02*
X-257682D01*
Y-88988D01*
X-254548D01*
G01X-255802Y-92033D02*
X-257682D01*
G01X-257838Y140932D02*
Y147232D01*
X-256272D01*
X-255645Y146917D01*
X-255175Y146497D01*
X-254783Y145867D01*
X-254470Y145132D01*
X-254392Y144082D01*
X-254470Y143032D01*
X-254783Y142297D01*
X-255175Y141667D01*
X-255645Y141247D01*
X-256272Y140932D01*
X-257838D01*
G01X-254392Y382928D02*
X-254862Y383243D01*
X-255410Y383453D01*
X-256037D01*
X-256742Y383138D01*
X-257290Y382613D01*
X-257682Y381983D01*
X-257995Y380933D01*
X-258073Y379988D01*
X-257917Y379043D01*
X-257682Y378413D01*
X-257212Y377783D01*
X-256663Y377363D01*
X-256115Y377153D01*
X-255567D01*
X-255018Y377363D01*
X-254548Y377678D01*
X-254157Y378098D01*
G01X-255488Y616733D02*
X-255175Y617048D01*
X-254940Y617573D01*
X-254783Y618308D01*
X-254940Y618938D01*
X-255253Y619358D01*
X-255802Y619673D01*
X-257917D01*
Y613373D01*
X-255332D01*
X-254783Y613793D01*
X-254470Y614423D01*
X-254313Y615158D01*
X-254470Y615893D01*
X-254940Y616523D01*
X-255488Y616733D01*
X-257917D01*
G01X-258073Y849595D02*
X-256115Y855895D01*
X-254157Y849595D01*
G01X-254862Y851800D02*
X-257368D01*
G01X-178162Y-401587D02*
Y-395287D01*
X-179102Y-396547D01*
G01Y-401587D02*
X-177222D01*
G01X-178162Y959043D02*
Y965343D01*
X-179102Y964083D01*
G01Y959043D02*
X-177222D01*
G01X-109896Y470866D02*
Y478740D01*
X-111077Y477165D01*
G01Y470866D02*
X-108715D01*
G01X-103891Y477428D02*
X-103301Y478215D01*
X-102612Y478609D01*
X-101824Y478740D01*
X-100840Y478478D01*
X-100151Y477821D01*
X-99954Y477034D01*
X-100052Y476246D01*
X-100446Y475590D01*
X-102415Y474278D01*
X-103301Y473359D01*
X-103891Y472047D01*
X-104088Y470866D01*
X-99954D01*
G01X-94146Y478740D02*
X-94934Y478478D01*
X-95524Y477821D01*
X-95918Y477034D01*
X-96213Y475984D01*
X-96312Y474803D01*
X-96213Y473622D01*
X-95918Y472572D01*
X-95524Y471784D01*
X-94934Y471128D01*
X-94146Y470866D01*
X-93359Y471128D01*
X-92768Y471784D01*
X-92374Y472572D01*
X-92079Y473622D01*
X-91980Y474803D01*
X-92079Y475984D01*
X-92374Y477034D01*
X-92768Y477821D01*
X-93359Y478478D01*
X-94146Y478740D01*
G01X-86271Y470604D02*
X-86468Y470735D01*
Y470997D01*
X-86271Y471128D01*
X-86074Y470997D01*
Y470735D01*
X-86271Y470604D01*
G01X-80266Y474147D02*
X-79577Y475066D01*
X-78987Y475590D01*
X-78199Y475853D01*
X-77510Y475590D01*
X-77018Y475066D01*
X-76624Y474278D01*
X-76526Y473359D01*
X-76624Y472572D01*
X-77018Y471784D01*
X-77609Y471128D01*
X-78297Y470866D01*
X-79085Y471128D01*
X-79774Y471916D01*
X-80168Y473097D01*
X-80266Y474409D01*
X-80069Y476115D01*
X-79774Y477034D01*
X-79282Y477953D01*
X-78593Y478609D01*
X-77904Y478740D01*
X-77215Y478478D01*
X-76723Y477821D01*
G01X-70521Y478740D02*
X-71309Y478478D01*
X-71899Y477821D01*
X-72293Y477034D01*
X-72588Y475984D01*
X-72687Y474803D01*
X-72588Y473622D01*
X-72293Y472572D01*
X-71899Y471784D01*
X-71309Y471128D01*
X-70521Y470866D01*
X-69734Y471128D01*
X-69143Y471784D01*
X-68749Y472572D01*
X-68454Y473622D01*
X-68355Y474803D01*
X-68454Y475984D01*
X-68749Y477034D01*
X-69143Y477821D01*
X-69734Y478478D01*
X-70521Y478740D01*
G01X-108714Y622441D02*
Y630315D01*
X-109895Y628740D01*
G01Y622441D02*
X-107533D01*
G01X-103005Y623622D02*
X-102414Y622966D01*
X-101725Y622572D01*
X-100839Y622441D01*
X-99953Y622703D01*
X-99264Y623228D01*
X-98772Y624147D01*
X-98673Y625197D01*
X-98870Y626247D01*
X-99363Y626903D01*
X-100052Y627428D01*
X-100740Y627559D01*
X-101430Y627428D01*
X-102315Y626903D01*
X-102020Y630315D01*
X-99363D01*
G01X-94637Y623359D02*
X-93948Y622703D01*
X-93161Y622441D01*
X-92373Y622703D01*
X-91684Y623491D01*
X-91192Y624672D01*
X-90995Y625853D01*
Y627297D01*
X-91192Y628478D01*
X-91684Y629528D01*
X-92275Y630053D01*
X-92964Y630315D01*
X-93752Y630053D01*
X-94342Y629528D01*
X-94736Y628740D01*
X-94933Y627690D01*
X-94736Y626772D01*
X-94244Y625853D01*
X-93653Y625328D01*
X-92964Y625197D01*
X-92177Y625459D01*
X-91586Y626115D01*
X-90995Y627297D01*
G01X-85089Y622179D02*
X-85286Y622310D01*
Y622572D01*
X-85089Y622703D01*
X-84892Y622572D01*
Y622310D01*
X-85089Y622179D01*
G01X-77214Y622441D02*
Y630315D01*
X-78395Y628740D01*
G01Y622441D02*
X-76033D01*
G01X-69339Y630315D02*
X-70127Y630053D01*
X-70717Y629396D01*
X-71111Y628609D01*
X-71406Y627559D01*
X-71505Y626378D01*
X-71406Y625197D01*
X-71111Y624147D01*
X-70717Y623359D01*
X-70127Y622703D01*
X-69339Y622441D01*
X-68552Y622703D01*
X-67961Y623359D01*
X-67567Y624147D01*
X-67272Y625197D01*
X-67173Y626378D01*
X-67272Y627559D01*
X-67567Y628609D01*
X-67961Y629396D01*
X-68552Y630053D01*
X-69339Y630315D01*
G01X-111077Y727559D02*
Y735433D01*
X-112258Y733858D01*
G01Y727559D02*
X-109896D01*
G01X-103202D02*
X-102513Y727690D01*
X-101726Y728084D01*
X-101233Y728740D01*
X-101036Y729659D01*
X-101233Y730577D01*
X-101824Y731365D01*
X-102710Y731759D01*
X-103694D01*
X-104285Y732021D01*
X-104777Y732677D01*
X-104974Y733596D01*
X-104678Y734514D01*
X-103990Y735171D01*
X-103202Y735433D01*
X-102415Y735171D01*
X-101726Y734514D01*
X-101430Y733596D01*
X-101627Y732677D01*
X-102119Y732021D01*
X-102710Y731759D01*
X-103694D01*
X-104580Y731365D01*
X-105171Y730577D01*
X-105368Y729659D01*
X-105171Y728740D01*
X-104678Y728084D01*
X-103891Y727690D01*
X-103202Y727559D01*
G01X-97493Y728740D02*
X-96902Y728084D01*
X-96213Y727690D01*
X-95327Y727559D01*
X-94441Y727821D01*
X-93752Y728346D01*
X-93260Y729265D01*
X-93161Y730315D01*
X-93358Y731365D01*
X-93851Y732021D01*
X-94540Y732546D01*
X-95228Y732677D01*
X-95918Y732546D01*
X-96803Y732021D01*
X-96508Y735433D01*
X-93851D01*
G01X-87452Y727297D02*
X-87649Y727428D01*
Y727690D01*
X-87452Y727821D01*
X-87255Y727690D01*
Y727428D01*
X-87452Y727297D01*
G01X-79577Y727559D02*
X-78888Y727690D01*
X-78101Y728084D01*
X-77608Y728740D01*
X-77411Y729659D01*
X-77608Y730577D01*
X-78199Y731365D01*
X-79085Y731759D01*
X-80069D01*
X-80660Y732021D01*
X-81152Y732677D01*
X-81349Y733596D01*
X-81053Y734514D01*
X-80365Y735171D01*
X-79577Y735433D01*
X-78790Y735171D01*
X-78101Y734514D01*
X-77805Y733596D01*
X-78002Y732677D01*
X-78494Y732021D01*
X-79085Y731759D01*
X-80069D01*
X-80955Y731365D01*
X-81546Y730577D01*
X-81743Y729659D01*
X-81546Y728740D01*
X-81053Y728084D01*
X-80266Y727690D01*
X-79577Y727559D01*
G01X-71702Y735433D02*
X-72490Y735171D01*
X-73080Y734514D01*
X-73474Y733727D01*
X-73769Y732677D01*
X-73868Y731496D01*
X-73769Y730315D01*
X-73474Y729265D01*
X-73080Y728477D01*
X-72490Y727821D01*
X-71702Y727559D01*
X-70915Y727821D01*
X-70324Y728477D01*
X-69930Y729265D01*
X-69635Y730315D01*
X-69536Y731496D01*
X-69635Y732677D01*
X-69930Y733727D01*
X-70324Y734514D01*
X-70915Y735171D01*
X-71702Y735433D01*
G01X-96903Y3937D02*
X-97691Y3675D01*
X-98281Y3018D01*
X-98675Y2231D01*
X-98970Y1181D01*
X-99069Y0D01*
X-98970Y-1181D01*
X-98675Y-2231D01*
X-98281Y-3019D01*
X-97691Y-3675D01*
X-96903Y-3937D01*
X-96116Y-3675D01*
X-95525Y-3019D01*
X-95131Y-2231D01*
X-94836Y-1181D01*
X-94737Y0D01*
X-94836Y1181D01*
X-95131Y2231D01*
X-95525Y3018D01*
X-96116Y3675D01*
X-96903Y3937D01*
G01X-89028Y-4199D02*
X-89225Y-4068D01*
Y-3806D01*
X-89028Y-3675D01*
X-88831Y-3806D01*
Y-4068D01*
X-89028Y-4199D01*
G01X-81153Y3937D02*
X-81941Y3675D01*
X-82531Y3018D01*
X-82925Y2231D01*
X-83220Y1181D01*
X-83319Y0D01*
X-83220Y-1181D01*
X-82925Y-2231D01*
X-82531Y-3019D01*
X-81941Y-3675D01*
X-81153Y-3937D01*
X-80366Y-3675D01*
X-79775Y-3019D01*
X-79381Y-2231D01*
X-79086Y-1181D01*
X-78987Y0D01*
X-79086Y1181D01*
X-79381Y2231D01*
X-79775Y3018D01*
X-80366Y3675D01*
X-81153Y3937D01*
G01X-73278D02*
X-74066Y3675D01*
X-74656Y3018D01*
X-75050Y2231D01*
X-75345Y1181D01*
X-75444Y0D01*
X-75345Y-1181D01*
X-75050Y-2231D01*
X-74656Y-3019D01*
X-74066Y-3675D01*
X-73278Y-3937D01*
X-72491Y-3675D01*
X-71900Y-3019D01*
X-71506Y-2231D01*
X-71211Y-1181D01*
X-71112Y0D01*
X-71211Y1181D01*
X-71506Y2231D01*
X-71900Y3018D01*
X-72491Y3675D01*
X-73278Y3937D01*
G01X-108222Y107743D02*
X-107632Y108530D01*
X-106943Y108924D01*
X-106155Y109055D01*
X-105171Y108793D01*
X-104482Y108136D01*
X-104285Y107349D01*
X-104383Y106561D01*
X-104777Y105905D01*
X-106746Y104593D01*
X-107632Y103674D01*
X-108222Y102362D01*
X-108419Y101181D01*
X-104285D01*
G01X-100347Y104462D02*
X-99658Y105381D01*
X-99068Y105905D01*
X-98280Y106168D01*
X-97591Y105905D01*
X-97099Y105381D01*
X-96705Y104593D01*
X-96607Y103674D01*
X-96705Y102887D01*
X-97099Y102099D01*
X-97690Y101443D01*
X-98378Y101181D01*
X-99166Y101443D01*
X-99855Y102231D01*
X-100249Y103412D01*
X-100347Y104724D01*
X-100150Y106430D01*
X-99855Y107349D01*
X-99363Y108268D01*
X-98674Y108924D01*
X-97985Y109055D01*
X-97296Y108793D01*
X-96804Y108136D01*
G01X-90602Y100919D02*
X-90799Y101050D01*
Y101312D01*
X-90602Y101443D01*
X-90405Y101312D01*
Y101050D01*
X-90602Y100919D01*
G01X-82924Y101181D02*
X-82727Y102887D01*
X-82432Y104330D01*
X-82038Y105643D01*
X-81546Y107086D01*
X-80758Y109055D01*
X-84696D01*
G01X-74852D02*
X-75640Y108793D01*
X-76230Y108136D01*
X-76624Y107349D01*
X-76919Y106299D01*
X-77018Y105118D01*
X-76919Y103937D01*
X-76624Y102887D01*
X-76230Y102099D01*
X-75640Y101443D01*
X-74852Y101181D01*
X-74065Y101443D01*
X-73474Y102099D01*
X-73080Y102887D01*
X-72785Y103937D01*
X-72686Y105118D01*
X-72785Y106299D01*
X-73080Y107349D01*
X-73474Y108136D01*
X-74065Y108793D01*
X-74852Y109055D01*
G01X-108222Y256037D02*
X-107533Y256956D01*
X-106943Y257480D01*
X-106155Y257743D01*
X-105466Y257480D01*
X-104974Y256956D01*
X-104580Y256168D01*
X-104482Y255249D01*
X-104580Y254462D01*
X-104974Y253674D01*
X-105565Y253018D01*
X-106253Y252756D01*
X-107041Y253018D01*
X-107730Y253806D01*
X-108124Y254987D01*
X-108222Y256299D01*
X-108025Y258005D01*
X-107730Y258924D01*
X-107238Y259843D01*
X-106549Y260499D01*
X-105860Y260630D01*
X-105171Y260368D01*
X-104679Y259711D01*
G01X-100643Y253937D02*
X-100052Y253281D01*
X-99363Y252887D01*
X-98477Y252756D01*
X-97591Y253018D01*
X-96902Y253543D01*
X-96410Y254462D01*
X-96311Y255512D01*
X-96508Y256562D01*
X-97001Y257218D01*
X-97690Y257743D01*
X-98378Y257874D01*
X-99068Y257743D01*
X-99953Y257218D01*
X-99658Y260630D01*
X-97001D01*
G01X-90602Y252494D02*
X-90799Y252625D01*
Y252887D01*
X-90602Y253018D01*
X-90405Y252887D01*
Y252625D01*
X-90602Y252494D01*
G01X-84597Y259318D02*
X-84007Y260105D01*
X-83318Y260499D01*
X-82530Y260630D01*
X-81546Y260368D01*
X-80857Y259711D01*
X-80660Y258924D01*
X-80758Y258136D01*
X-81152Y257480D01*
X-83121Y256168D01*
X-84007Y255249D01*
X-84597Y253937D01*
X-84794Y252756D01*
X-80660D01*
G01X-74852Y260630D02*
X-75640Y260368D01*
X-76230Y259711D01*
X-76624Y258924D01*
X-76919Y257874D01*
X-77018Y256693D01*
X-76919Y255512D01*
X-76624Y254462D01*
X-76230Y253674D01*
X-75640Y253018D01*
X-74852Y252756D01*
X-74065Y253018D01*
X-73474Y253674D01*
X-73080Y254462D01*
X-72785Y255512D01*
X-72686Y256693D01*
X-72785Y257874D01*
X-73080Y258924D01*
X-73474Y259711D01*
X-74065Y260368D01*
X-74852Y260630D01*
G01X-106344Y369252D02*
X-105655Y368596D01*
X-104868Y368334D01*
X-104080Y368596D01*
X-103391Y369384D01*
X-102899Y370565D01*
X-102702Y371746D01*
Y373190D01*
X-102899Y374371D01*
X-103391Y375421D01*
X-103982Y375946D01*
X-104671Y376208D01*
X-105459Y375946D01*
X-106049Y375421D01*
X-106443Y374633D01*
X-106640Y373583D01*
X-106443Y372665D01*
X-105951Y371746D01*
X-105360Y371221D01*
X-104671Y371090D01*
X-103884Y371352D01*
X-103293Y372008D01*
X-102702Y373190D01*
G01X-98962Y369909D02*
X-98371Y368990D01*
X-97584Y368465D01*
X-96697Y368334D01*
X-95910Y368465D01*
X-95123Y369121D01*
X-94630Y369909D01*
X-94532Y370696D01*
X-94729Y371615D01*
X-95418Y372271D01*
X-96107Y372534D01*
X-96993D01*
G01X-96107D02*
X-95516Y372927D01*
X-95024Y373583D01*
X-94827Y374371D01*
X-95024Y375158D01*
X-95516Y375814D01*
X-96402Y376208D01*
X-97288Y376077D01*
X-98174Y375552D01*
G01X-88921Y368072D02*
X-89118Y368203D01*
Y368465D01*
X-88921Y368596D01*
X-88724Y368465D01*
Y368203D01*
X-88921Y368072D01*
G01X-82719Y369252D02*
X-82030Y368596D01*
X-81243Y368334D01*
X-80455Y368596D01*
X-79766Y369384D01*
X-79274Y370565D01*
X-79077Y371746D01*
Y373190D01*
X-79274Y374371D01*
X-79766Y375421D01*
X-80357Y375946D01*
X-81046Y376208D01*
X-81834Y375946D01*
X-82424Y375421D01*
X-82818Y374633D01*
X-83015Y373583D01*
X-82818Y372665D01*
X-82326Y371746D01*
X-81735Y371221D01*
X-81046Y371090D01*
X-80259Y371352D01*
X-79668Y372008D01*
X-79077Y373190D01*
G01X-73171Y376208D02*
X-73959Y375946D01*
X-74549Y375289D01*
X-74943Y374502D01*
X-75238Y373452D01*
X-75337Y372271D01*
X-75238Y371090D01*
X-74943Y370040D01*
X-74549Y369252D01*
X-73959Y368596D01*
X-73171Y368334D01*
X-72384Y368596D01*
X-71793Y369252D01*
X-71399Y370040D01*
X-71104Y371090D01*
X-71005Y372271D01*
X-71104Y373452D01*
X-71399Y374502D01*
X-71793Y375289D01*
X-72384Y375946D01*
X-73171Y376208D01*
G01X-106135Y358169D02*
X-105446Y357513D01*
X-104659Y357251D01*
X-103871Y357513D01*
X-103182Y358301D01*
X-102690Y359482D01*
X-102493Y360663D01*
Y362107D01*
X-102690Y363288D01*
X-103182Y364338D01*
X-103773Y364863D01*
X-104462Y365125D01*
X-105250Y364863D01*
X-105840Y364338D01*
X-106234Y363550D01*
X-106431Y362500D01*
X-106234Y361582D01*
X-105742Y360663D01*
X-105151Y360138D01*
X-104462Y360007D01*
X-103675Y360269D01*
X-103084Y360925D01*
X-102493Y362107D01*
G01X-96587Y357251D02*
Y365125D01*
X-97768Y363550D01*
G01Y357251D02*
X-95406D01*
G01X-88712Y356989D02*
X-88909Y357120D01*
Y357382D01*
X-88712Y357513D01*
X-88515Y357382D01*
Y357120D01*
X-88712Y356989D01*
G01X-82510Y358169D02*
X-81821Y357513D01*
X-81034Y357251D01*
X-80246Y357513D01*
X-79557Y358301D01*
X-79065Y359482D01*
X-78868Y360663D01*
Y362107D01*
X-79065Y363288D01*
X-79557Y364338D01*
X-80148Y364863D01*
X-80837Y365125D01*
X-81625Y364863D01*
X-82215Y364338D01*
X-82609Y363550D01*
X-82806Y362500D01*
X-82609Y361582D01*
X-82117Y360663D01*
X-81526Y360138D01*
X-80837Y360007D01*
X-80050Y360269D01*
X-79459Y360925D01*
X-78868Y362107D01*
G01X-72962Y365125D02*
X-73750Y364863D01*
X-74340Y364206D01*
X-74734Y363419D01*
X-75029Y362369D01*
X-75128Y361188D01*
X-75029Y360007D01*
X-74734Y358957D01*
X-74340Y358169D01*
X-73750Y357513D01*
X-72962Y357251D01*
X-72175Y357513D01*
X-71584Y358169D01*
X-71190Y358957D01*
X-70895Y360007D01*
X-70796Y361188D01*
X-70895Y362369D01*
X-71190Y363419D01*
X-71584Y364206D01*
X-72175Y364863D01*
X-72962Y365125D01*
G01X-29527Y772476D02*
X-29265Y771688D01*
X-28608Y771098D01*
X-27821Y770704D01*
X-26771Y770409D01*
X-25590Y770310D01*
X-24409Y770409D01*
X-23359Y770704D01*
X-22571Y771098D01*
X-21915Y771688D01*
X-21653Y772476D01*
X-21915Y773263D01*
X-22571Y773854D01*
X-23359Y774248D01*
X-24409Y774543D01*
X-25590Y774642D01*
X-26771Y774543D01*
X-27821Y774248D01*
X-28608Y773854D01*
X-29265Y773263D01*
X-29527Y772476D01*
G01X-21391Y780351D02*
X-21522Y780154D01*
X-21784D01*
X-21915Y780351D01*
X-21784Y780548D01*
X-21522D01*
X-21391Y780351D01*
G01X-29527Y788226D02*
X-29265Y787438D01*
X-28608Y786848D01*
X-27821Y786454D01*
X-26771Y786159D01*
X-25590Y786060D01*
X-24409Y786159D01*
X-23359Y786454D01*
X-22571Y786848D01*
X-21915Y787438D01*
X-21653Y788226D01*
X-21915Y789013D01*
X-22571Y789604D01*
X-23359Y789998D01*
X-24409Y790293D01*
X-25590Y790392D01*
X-26771Y790293D01*
X-27821Y789998D01*
X-28608Y789604D01*
X-29265Y789013D01*
X-29527Y788226D01*
G01Y796101D02*
X-29265Y795313D01*
X-28608Y794723D01*
X-27821Y794329D01*
X-26771Y794034D01*
X-25590Y793935D01*
X-24409Y794034D01*
X-23359Y794329D01*
X-22571Y794723D01*
X-21915Y795313D01*
X-21653Y796101D01*
X-21915Y796888D01*
X-22571Y797479D01*
X-23359Y797873D01*
X-24409Y798168D01*
X-25590Y798267D01*
X-26771Y798168D01*
X-27821Y797873D01*
X-28608Y797479D01*
X-29265Y796888D01*
X-29527Y796101D01*
G01X3578Y-396337D02*
X4048Y-395707D01*
X4596Y-395392D01*
X5223Y-395287D01*
X6006Y-395497D01*
X6554Y-396022D01*
X6711Y-396652D01*
X6633Y-397282D01*
X6319Y-397807D01*
X4753Y-398857D01*
X4048Y-399592D01*
X3578Y-400642D01*
X3421Y-401587D01*
X6711D01*
G01X656Y770606D02*
X-263Y771295D01*
X-787Y771885D01*
X-1050Y772673D01*
X-787Y773362D01*
X-263Y773854D01*
X525Y774248D01*
X1444Y774346D01*
X2231Y774248D01*
X3019Y773854D01*
X3675Y773263D01*
X3937Y772575D01*
X3675Y771787D01*
X2887Y771098D01*
X1706Y770704D01*
X394Y770606D01*
X-1312Y770803D01*
X-2231Y771098D01*
X-3150Y771590D01*
X-3806Y772279D01*
X-3937Y772968D01*
X-3675Y773657D01*
X-3018Y774149D01*
G01X4199Y780351D02*
X4068Y780154D01*
X3806D01*
X3675Y780351D01*
X3806Y780548D01*
X4068D01*
X4199Y780351D01*
G01X2756Y786060D02*
X3412Y786651D01*
X3806Y787340D01*
X3937Y788226D01*
X3675Y789112D01*
X3150Y789801D01*
X2231Y790293D01*
X1181Y790392D01*
X131Y790195D01*
X-525Y789702D01*
X-1050Y789013D01*
X-1181Y788325D01*
X-1050Y787635D01*
X-525Y786750D01*
X-3937Y787045D01*
Y789702D01*
G01Y796101D02*
X-3675Y795313D01*
X-3018Y794723D01*
X-2231Y794329D01*
X-1181Y794034D01*
X0Y793935D01*
X1181Y794034D01*
X2231Y794329D01*
X3019Y794723D01*
X3675Y795313D01*
X3937Y796101D01*
X3675Y796888D01*
X3019Y797479D01*
X2231Y797873D01*
X1181Y798168D01*
X0Y798267D01*
X-1181Y798168D01*
X-2231Y797873D01*
X-3018Y797479D01*
X-3675Y796888D01*
X-3937Y796101D01*
G01X3578Y964293D02*
X4048Y964923D01*
X4596Y965238D01*
X5223Y965343D01*
X6006Y965133D01*
X6554Y964608D01*
X6711Y963978D01*
X6633Y963348D01*
X6319Y962823D01*
X4753Y961773D01*
X4048Y961038D01*
X3578Y959988D01*
X3421Y959043D01*
X6711D01*
G01X39547Y712125D02*
Y717125D01*
X41953D01*
G01X41067Y714708D02*
X39547D01*
G01X45850Y715458D02*
Y712125D01*
G01Y716792D02*
X45723Y716875D01*
Y717042D01*
X45850Y717125D01*
X45977Y717042D01*
Y716875D01*
X45850Y716792D01*
G01X52090Y717125D02*
Y712125D01*
G01Y712875D02*
X51837Y712458D01*
X51457Y712208D01*
X51013Y712125D01*
X50507Y712292D01*
X50127Y712708D01*
X49873Y713208D01*
X49810Y713792D01*
X49873Y714375D01*
X50127Y714875D01*
X50507Y715292D01*
X51013Y715458D01*
X51457Y715375D01*
X51773Y715208D01*
X52090Y714875D01*
G01X54973Y715458D02*
Y713125D01*
X55227Y712542D01*
X55607Y712208D01*
X56050Y712125D01*
X56493Y712208D01*
X56873Y712542D01*
X57127Y713125D01*
G01Y712125D02*
Y715458D01*
G01X62163Y715042D02*
X61720Y715375D01*
X61340Y715458D01*
X60833Y715292D01*
X60453Y714958D01*
X60200Y714375D01*
X60137Y713792D01*
X60200Y713208D01*
X60453Y712708D01*
X60833Y712292D01*
X61340Y712125D01*
X61783Y712292D01*
X62163Y712625D01*
G01X66250Y715458D02*
Y712125D01*
G01Y716792D02*
X66123Y716875D01*
Y717042D01*
X66250Y717125D01*
X66377Y717042D01*
Y716875D01*
X66250Y716792D01*
G01X72490Y712125D02*
Y715458D01*
G01Y714875D02*
X72237Y715208D01*
X71857Y715375D01*
X71413Y715458D01*
X70970Y715292D01*
X70590Y714958D01*
X70337Y714458D01*
X70210Y713792D01*
X70337Y713125D01*
X70590Y712625D01*
X70970Y712292D01*
X71413Y712125D01*
X71857Y712208D01*
X72237Y712458D01*
X72490Y712792D01*
G01X76450Y712125D02*
Y717125D01*
G01X85003Y712125D02*
Y717125D01*
X86650Y712958D01*
X88297Y717125D01*
Y712125D01*
G01X92890D02*
Y715458D01*
G01Y714875D02*
X92637Y715208D01*
X92257Y715375D01*
X91813Y715458D01*
X91370Y715292D01*
X90990Y714958D01*
X90737Y714458D01*
X90610Y713792D01*
X90737Y713125D01*
X90990Y712625D01*
X91370Y712292D01*
X91813Y712125D01*
X92257Y712208D01*
X92637Y712458D01*
X92890Y712792D01*
G01X95963Y712125D02*
Y715458D01*
G01Y714792D02*
X96280Y715125D01*
X96597Y715375D01*
X97040Y715458D01*
X97357Y715375D01*
X97737Y715125D01*
G01X100873Y712125D02*
Y717125D01*
G01X102900Y715458D02*
X100873Y713542D01*
G01X101697Y714292D02*
X103027Y712125D01*
G01X111200Y715458D02*
X113100Y712125D01*
G01Y715458D02*
X111200Y712125D01*
G01X121147Y716292D02*
X121527Y716792D01*
X121970Y717042D01*
X122477Y717125D01*
X123110Y716958D01*
X123553Y716542D01*
X123680Y716042D01*
X123617Y715542D01*
X123363Y715125D01*
X122097Y714292D01*
X121527Y713708D01*
X121147Y712875D01*
X121020Y712125D01*
X123680D01*
G01X176571Y-400327D02*
X177041Y-401062D01*
X177667Y-401482D01*
X178372Y-401587D01*
X178999Y-401482D01*
X179626Y-400957D01*
X180017Y-400327D01*
X180096Y-399697D01*
X179939Y-398962D01*
X179391Y-398437D01*
X178842Y-398227D01*
X178137D01*
G01X178842D02*
X179312Y-397912D01*
X179704Y-397387D01*
X179861Y-396757D01*
X179704Y-396127D01*
X179312Y-395602D01*
X178607Y-395287D01*
X177902Y-395392D01*
X177197Y-395812D01*
G01X176571Y960303D02*
X177041Y959568D01*
X177667Y959148D01*
X178372Y959043D01*
X178999Y959148D01*
X179626Y959673D01*
X180017Y960303D01*
X180096Y960933D01*
X179939Y961668D01*
X179391Y962193D01*
X178842Y962403D01*
X178137D01*
G01X178842D02*
X179312Y962718D01*
X179704Y963243D01*
X179861Y963873D01*
X179704Y964503D01*
X179312Y965028D01*
X178607Y965343D01*
X177902Y965238D01*
X177197Y964818D01*
G01X226583Y206046D02*
Y221794D01*
G01X231110Y206046D02*
X222055D01*
G01X226583Y575731D02*
Y591479D01*
G01X231110Y575731D02*
X222055D01*
G01X312788Y155765D02*
Y140017D01*
G01X308261Y155765D02*
X317316D01*
G01X312788Y525450D02*
Y509702D01*
G01X308261Y525450D02*
X317316D01*
G01X352463Y-401587D02*
Y-395287D01*
X349565Y-399802D01*
X353481D01*
G01X352463Y959043D02*
Y965343D01*
X349565Y960828D01*
X353481D01*
G01X388674Y-8773D02*
X389461Y-9429D01*
X390347Y-9823D01*
X391135D01*
X391922Y-9429D01*
X392513Y-8773D01*
X392808Y-7854D01*
X392611Y-6936D01*
X392119Y-6149D01*
X391233Y-5623D01*
X390052Y-5361D01*
X389363Y-4836D01*
X389068Y-3918D01*
X389265Y-2999D01*
X389757Y-2343D01*
X390446Y-1949D01*
X391135D01*
X391824Y-2211D01*
X392414Y-2868D01*
G01X397140Y-6280D02*
X400289D01*
X399994Y-5361D01*
X399502Y-4836D01*
X398813Y-4574D01*
X398124Y-4705D01*
X397533Y-5099D01*
X397140Y-6017D01*
X396943Y-6805D01*
Y-7592D01*
X397140Y-8380D01*
X397632Y-9167D01*
X398222Y-9692D01*
X398911Y-9823D01*
X399600Y-9561D01*
X400289Y-8773D01*
G01X405113Y-9823D02*
Y-4574D01*
G01Y-5623D02*
X405605Y-5099D01*
X406097Y-4705D01*
X406786Y-4574D01*
X407278Y-4705D01*
X407869Y-5099D01*
G01X414366Y-4574D02*
Y-9823D01*
G01Y-2474D02*
X414169Y-2343D01*
Y-2080D01*
X414366Y-1949D01*
X414563Y-2080D01*
Y-2343D01*
X414366Y-2474D01*
G01X420765Y-6280D02*
X423914D01*
X423619Y-5361D01*
X423127Y-4836D01*
X422438Y-4574D01*
X421749Y-4705D01*
X421158Y-5099D01*
X420765Y-6017D01*
X420568Y-6805D01*
Y-7592D01*
X420765Y-8380D01*
X421257Y-9167D01*
X421847Y-9692D01*
X422536Y-9823D01*
X423225Y-9561D01*
X423914Y-8773D01*
G01X428640Y-8905D02*
X429132Y-9429D01*
X429821Y-9823D01*
X430411D01*
X431002Y-9561D01*
X431396Y-9167D01*
X431592Y-8642D01*
X431494Y-7854D01*
X431100Y-7461D01*
X429328Y-6674D01*
X428935Y-5755D01*
X429132Y-5099D01*
X429525Y-4705D01*
X430116Y-4574D01*
X430707Y-4705D01*
X431297Y-5099D01*
G01X444193Y-9823D02*
Y-4574D01*
G01Y-5886D02*
X444586Y-5230D01*
X445177Y-4705D01*
X445965Y-4574D01*
X446653Y-4705D01*
X447244Y-5230D01*
X447539Y-6149D01*
Y-9823D01*
G01X452068Y-4574D02*
Y-8248D01*
X452461Y-9167D01*
X453052Y-9692D01*
X453741Y-9823D01*
X454430Y-9692D01*
X455021Y-9167D01*
X455414Y-8248D01*
G01Y-9823D02*
Y-4574D01*
G01X458663Y-9823D02*
Y-4574D01*
G01Y-6017D02*
X458958Y-5361D01*
X459450Y-4836D01*
X460140Y-4574D01*
X460828Y-4836D01*
X461321Y-5361D01*
X461616Y-6017D01*
Y-9823D01*
G01Y-6017D02*
X461911Y-5361D01*
X462403Y-4836D01*
X463092Y-4574D01*
X463782Y-4836D01*
X464274Y-5361D01*
X464569Y-6149D01*
Y-9823D01*
G01X467719D02*
Y-1949D01*
G01Y-5886D02*
X468211Y-5099D01*
X468802Y-4705D01*
X469392Y-4574D01*
X470278Y-4836D01*
X470869Y-5361D01*
X471263Y-6280D01*
Y-7330D01*
X471066Y-8380D01*
X470672Y-9167D01*
X469983Y-9692D01*
X469392Y-9823D01*
X468802Y-9692D01*
X468211Y-9298D01*
X467719Y-8642D01*
G01X475890Y-6280D02*
X479039D01*
X478744Y-5361D01*
X478252Y-4836D01*
X477563Y-4574D01*
X476874Y-4705D01*
X476283Y-5099D01*
X475890Y-6017D01*
X475693Y-6805D01*
Y-7592D01*
X475890Y-8380D01*
X476382Y-9167D01*
X476972Y-9692D01*
X477661Y-9823D01*
X478350Y-9561D01*
X479039Y-8773D01*
G01X483863Y-9823D02*
Y-4574D01*
G01Y-5623D02*
X484355Y-5099D01*
X484847Y-4705D01*
X485536Y-4574D01*
X486028Y-4705D01*
X486619Y-5099D01*
G01X502763Y-9823D02*
Y-4574D01*
G01Y-5492D02*
X502369Y-4967D01*
X501778Y-4705D01*
X501090Y-4574D01*
X500400Y-4836D01*
X499810Y-5361D01*
X499416Y-6149D01*
X499219Y-7198D01*
X499416Y-8248D01*
X499810Y-9036D01*
X500400Y-9561D01*
X501090Y-9823D01*
X501778Y-9692D01*
X502369Y-9298D01*
X502763Y-8773D01*
G01X507193Y-9823D02*
Y-4574D01*
G01Y-5886D02*
X507586Y-5230D01*
X508177Y-4705D01*
X508965Y-4574D01*
X509653Y-4705D01*
X510244Y-5230D01*
X510539Y-6149D01*
Y-9823D01*
G01X518513Y-1949D02*
Y-9823D01*
G01Y-8642D02*
X518119Y-9298D01*
X517528Y-9692D01*
X516840Y-9823D01*
X516052Y-9561D01*
X515461Y-8905D01*
X515068Y-8117D01*
X514969Y-7198D01*
X515068Y-6280D01*
X515461Y-5492D01*
X516052Y-4836D01*
X516840Y-4574D01*
X517528Y-4705D01*
X518021Y-4967D01*
X518513Y-5492D01*
G01X531113Y-9823D02*
Y-4574D01*
G01Y-5623D02*
X531605Y-5099D01*
X532097Y-4705D01*
X532786Y-4574D01*
X533278Y-4705D01*
X533869Y-5099D01*
G01X538890Y-6280D02*
X542039D01*
X541744Y-5361D01*
X541252Y-4836D01*
X540563Y-4574D01*
X539874Y-4705D01*
X539283Y-5099D01*
X538890Y-6017D01*
X538693Y-6805D01*
Y-7592D01*
X538890Y-8380D01*
X539382Y-9167D01*
X539972Y-9692D01*
X540661Y-9823D01*
X541350Y-9561D01*
X542039Y-8773D01*
G01X547650Y-9823D02*
Y-3130D01*
X547847Y-2474D01*
X548241Y-2080D01*
X548832Y-1949D01*
X549422Y-2211D01*
X549717Y-2868D01*
G01X548536Y-5099D02*
X546568D01*
G01X554640Y-6280D02*
X557789D01*
X557494Y-5361D01*
X557002Y-4836D01*
X556313Y-4574D01*
X555624Y-4705D01*
X555033Y-5099D01*
X554640Y-6017D01*
X554443Y-6805D01*
Y-7592D01*
X554640Y-8380D01*
X555132Y-9167D01*
X555722Y-9692D01*
X556411Y-9823D01*
X557100Y-9561D01*
X557789Y-8773D01*
G01X562613Y-9823D02*
Y-4574D01*
G01Y-5623D02*
X563105Y-5099D01*
X563597Y-4705D01*
X564286Y-4574D01*
X564778Y-4705D01*
X565369Y-5099D01*
G01X570390Y-6280D02*
X573539D01*
X573244Y-5361D01*
X572752Y-4836D01*
X572063Y-4574D01*
X571374Y-4705D01*
X570783Y-5099D01*
X570390Y-6017D01*
X570193Y-6805D01*
Y-7592D01*
X570390Y-8380D01*
X570882Y-9167D01*
X571472Y-9692D01*
X572161Y-9823D01*
X572850Y-9561D01*
X573539Y-8773D01*
G01X578068Y-9823D02*
Y-4574D01*
G01Y-5886D02*
X578461Y-5230D01*
X579052Y-4705D01*
X579840Y-4574D01*
X580528Y-4705D01*
X581119Y-5230D01*
X581414Y-6149D01*
Y-9823D01*
G01X589191Y-5230D02*
X588502Y-4705D01*
X587911Y-4574D01*
X587124Y-4836D01*
X586533Y-5361D01*
X586140Y-6280D01*
X586041Y-7198D01*
X586140Y-8117D01*
X586533Y-8905D01*
X587124Y-9561D01*
X587911Y-9823D01*
X588600Y-9561D01*
X589191Y-9036D01*
G01X594015Y-6280D02*
X597164D01*
X596869Y-5361D01*
X596377Y-4836D01*
X595688Y-4574D01*
X594999Y-4705D01*
X594408Y-5099D01*
X594015Y-6017D01*
X593818Y-6805D01*
Y-7592D01*
X594015Y-8380D01*
X594507Y-9167D01*
X595097Y-9692D01*
X595786Y-9823D01*
X596475Y-9561D01*
X597164Y-8773D01*
G01X611241Y-9823D02*
X610650Y-9692D01*
X610060Y-9167D01*
X609666Y-8248D01*
X609469Y-7198D01*
X609666Y-6149D01*
X610060Y-5230D01*
X610650Y-4705D01*
X611241Y-4574D01*
X611832Y-4705D01*
X612422Y-5230D01*
X612816Y-6149D01*
X612914Y-7198D01*
X612816Y-8248D01*
X612422Y-9167D01*
X611832Y-9692D01*
X611241Y-9823D01*
G01X617443D02*
Y-4574D01*
G01Y-5886D02*
X617836Y-5230D01*
X618427Y-4705D01*
X619215Y-4574D01*
X619903Y-4705D01*
X620494Y-5230D01*
X620789Y-6149D01*
Y-9823D01*
G01X626991D02*
Y-1949D01*
G01X632799Y-12185D02*
X633390Y-12448D01*
X634177Y-12185D01*
X634669Y-11660D01*
X635063Y-11004D01*
X635653Y-8905D01*
X636933Y-4574D01*
G01X633783D02*
X635653Y-8905D01*
G01X642741Y-10085D02*
X642544Y-9954D01*
Y-9692D01*
X642741Y-9561D01*
X642938Y-9692D01*
Y-9954D01*
X642741Y-10085D01*
G01X523028Y-400642D02*
X523498Y-401167D01*
X524046Y-401482D01*
X524751Y-401587D01*
X525456Y-401377D01*
X526004Y-400957D01*
X526396Y-400222D01*
X526474Y-399382D01*
X526318Y-398542D01*
X525926Y-398017D01*
X525378Y-397597D01*
X524829Y-397492D01*
X524281Y-397597D01*
X523576Y-398017D01*
X523811Y-395287D01*
X525926D01*
G01X523028Y959988D02*
X523498Y959463D01*
X524046Y959148D01*
X524751Y959043D01*
X525456Y959253D01*
X526004Y959673D01*
X526396Y960408D01*
X526474Y961248D01*
X526318Y962088D01*
X525926Y962613D01*
X525378Y963033D01*
X524829Y963138D01*
X524281Y963033D01*
X523576Y962613D01*
X523811Y965343D01*
X525926D01*
G01X543307Y772476D02*
X535433D01*
X537008Y771295D01*
G01X543307D02*
Y773657D01*
G01Y781532D02*
X535433D01*
X541076Y777890D01*
Y782812D01*
G01X541732Y786060D02*
X542651Y786651D01*
X543176Y787438D01*
X543307Y788325D01*
X543176Y789112D01*
X542520Y789899D01*
X541732Y790392D01*
X540945Y790490D01*
X540026Y790293D01*
X539370Y789604D01*
X539107Y788915D01*
Y788029D01*
G01Y788915D02*
X538714Y789506D01*
X538058Y789998D01*
X537270Y790195D01*
X536483Y789998D01*
X535827Y789506D01*
X535433Y788620D01*
X535564Y787734D01*
X536089Y786848D01*
G01X543569Y796101D02*
X543438Y795904D01*
X543176D01*
X543045Y796101D01*
X543176Y796298D01*
X543438D01*
X543569Y796101D01*
G01X542126Y801810D02*
X542782Y802401D01*
X543176Y803090D01*
X543307Y803976D01*
X543045Y804862D01*
X542520Y805551D01*
X541601Y806043D01*
X540551Y806142D01*
X539501Y805945D01*
X538845Y805452D01*
X538320Y804763D01*
X538189Y804075D01*
X538320Y803385D01*
X538845Y802500D01*
X535433Y802795D01*
Y805452D01*
G01Y811851D02*
X535695Y811063D01*
X536352Y810473D01*
X537139Y810079D01*
X538189Y809784D01*
X539370Y809685D01*
X540551Y809784D01*
X541601Y810079D01*
X542389Y810473D01*
X543045Y811063D01*
X543307Y811851D01*
X543045Y812638D01*
X542389Y813229D01*
X541601Y813623D01*
X540551Y813918D01*
X539370Y814017D01*
X538189Y813918D01*
X537139Y813623D01*
X536352Y813229D01*
X535695Y812638D01*
X535433Y811851D01*
G01X568898Y772476D02*
X561024D01*
X562599Y771295D01*
G01X568898D02*
Y773657D01*
G01X567717Y778185D02*
X568373Y778776D01*
X568767Y779465D01*
X568898Y780351D01*
X568636Y781237D01*
X568111Y781926D01*
X567192Y782418D01*
X566142Y782517D01*
X565092Y782320D01*
X564436Y781827D01*
X563911Y781138D01*
X563780Y780450D01*
X563911Y779760D01*
X564436Y778875D01*
X561024Y779170D01*
Y781827D01*
G01Y788226D02*
X561286Y787438D01*
X561943Y786848D01*
X562730Y786454D01*
X563780Y786159D01*
X564961Y786060D01*
X566142Y786159D01*
X567192Y786454D01*
X567980Y786848D01*
X568636Y787438D01*
X568898Y788226D01*
X568636Y789013D01*
X567980Y789604D01*
X567192Y789998D01*
X566142Y790293D01*
X564961Y790392D01*
X563780Y790293D01*
X562730Y789998D01*
X561943Y789604D01*
X561286Y789013D01*
X561024Y788226D01*
G01X569160Y796101D02*
X569029Y795904D01*
X568767D01*
X568636Y796101D01*
X568767Y796298D01*
X569029D01*
X569160Y796101D01*
G01X561024Y803976D02*
X561286Y803188D01*
X561943Y802598D01*
X562730Y802204D01*
X563780Y801909D01*
X564961Y801810D01*
X566142Y801909D01*
X567192Y802204D01*
X567980Y802598D01*
X568636Y803188D01*
X568898Y803976D01*
X568636Y804763D01*
X567980Y805354D01*
X567192Y805748D01*
X566142Y806043D01*
X564961Y806142D01*
X563780Y806043D01*
X562730Y805748D01*
X561943Y805354D01*
X561286Y804763D01*
X561024Y803976D01*
G01Y811851D02*
X561286Y811063D01*
X561943Y810473D01*
X562730Y810079D01*
X563780Y809784D01*
X564961Y809685D01*
X566142Y809784D01*
X567192Y810079D01*
X567980Y810473D01*
X568636Y811063D01*
X568898Y811851D01*
X568636Y812638D01*
X567980Y813229D01*
X567192Y813623D01*
X566142Y813918D01*
X564961Y814017D01*
X563780Y813918D01*
X562730Y813623D01*
X561943Y813229D01*
X561286Y812638D01*
X561024Y811851D01*
G01X696491Y-398962D02*
X697039Y-398227D01*
X697509Y-397807D01*
X698136Y-397597D01*
X698684Y-397807D01*
X699076Y-398227D01*
X699389Y-398857D01*
X699467Y-399592D01*
X699389Y-400222D01*
X699076Y-400852D01*
X698606Y-401377D01*
X698057Y-401587D01*
X697431Y-401377D01*
X696882Y-400747D01*
X696569Y-399802D01*
X696491Y-398752D01*
X696647Y-397387D01*
X696882Y-396652D01*
X697274Y-395917D01*
X697822Y-395392D01*
X698371Y-395287D01*
X698919Y-395497D01*
X699311Y-396022D01*
G01X696491Y961668D02*
X697039Y962403D01*
X697509Y962823D01*
X698136Y963033D01*
X698684Y962823D01*
X699076Y962403D01*
X699389Y961773D01*
X699467Y961038D01*
X699389Y960408D01*
X699076Y959778D01*
X698606Y959253D01*
X698057Y959043D01*
X697431Y959253D01*
X696882Y959883D01*
X696569Y960828D01*
X696491Y961878D01*
X696647Y963243D01*
X696882Y963978D01*
X697274Y964713D01*
X697822Y965238D01*
X698371Y965343D01*
X698919Y965133D01*
X699311Y964608D01*
G01X758285Y-286137D02*
X756706Y-285084D01*
X754863Y-284382D01*
X752757D01*
X750388Y-285435D01*
X748546Y-287190D01*
X747229Y-289296D01*
X746176Y-292806D01*
X745913Y-295965D01*
X746440Y-299123D01*
X747229Y-301229D01*
X748809Y-303336D01*
X750652Y-304739D01*
X752494Y-305441D01*
X754336D01*
X756179Y-304739D01*
X757759Y-303686D01*
X759075Y-302283D01*
G01X769868Y-305441D02*
Y-291402D01*
G01Y-294209D02*
X771184Y-292806D01*
X772500Y-291753D01*
X774343Y-291402D01*
X775659Y-291753D01*
X777238Y-292806D01*
G01X790664Y-295965D02*
X799087D01*
X798297Y-293508D01*
X796981Y-292104D01*
X795139Y-291402D01*
X793296Y-291753D01*
X791716Y-292806D01*
X790664Y-295263D01*
X790137Y-297369D01*
Y-299474D01*
X790664Y-301580D01*
X791980Y-303686D01*
X793559Y-305090D01*
X795402Y-305441D01*
X797244Y-304739D01*
X799087Y-302634D01*
G01X820409Y-305441D02*
Y-291402D01*
G01Y-293858D02*
X819356Y-292455D01*
X817777Y-291753D01*
X815934Y-291402D01*
X814092Y-292104D01*
X812512Y-293508D01*
X811459Y-295614D01*
X810933Y-298422D01*
X811459Y-301229D01*
X812512Y-303336D01*
X814092Y-304739D01*
X815934Y-305441D01*
X817777Y-305090D01*
X819356Y-304037D01*
X820409Y-302634D01*
G01X836730Y-284382D02*
Y-305441D01*
G01X833045Y-291402D02*
X840415D01*
G01X853841Y-295965D02*
X862264D01*
X861474Y-293508D01*
X860158Y-292104D01*
X858316Y-291402D01*
X856473Y-291753D01*
X854893Y-292806D01*
X853841Y-295263D01*
X853314Y-297369D01*
Y-299474D01*
X853841Y-301580D01*
X855157Y-303686D01*
X856736Y-305090D01*
X858579Y-305441D01*
X860421Y-304739D01*
X862264Y-302634D01*
G01X883586Y-284382D02*
Y-305441D01*
G01Y-302283D02*
X882533Y-304037D01*
X880954Y-305090D01*
X879111Y-305441D01*
X877006Y-304739D01*
X875426Y-302985D01*
X874373Y-300879D01*
X874110Y-298422D01*
X874373Y-295965D01*
X875426Y-293858D01*
X877006Y-292104D01*
X879111Y-291402D01*
X880954Y-291753D01*
X882270Y-292455D01*
X883586Y-293858D01*
G01X743211Y-235474D02*
X749792Y-256533D01*
X756373Y-235474D01*
G01X766903Y-247057D02*
X775326D01*
X774536Y-244600D01*
X773220Y-243196D01*
X771378Y-242494D01*
X769535Y-242845D01*
X767955Y-243898D01*
X766903Y-246355D01*
X766376Y-248461D01*
Y-250566D01*
X766903Y-252672D01*
X768219Y-254778D01*
X769798Y-256182D01*
X771641Y-256533D01*
X773483Y-255831D01*
X775326Y-253726D01*
G01X788225Y-256533D02*
Y-242494D01*
G01Y-245301D02*
X789541Y-243898D01*
X790857Y-242845D01*
X792700Y-242494D01*
X794016Y-242845D01*
X795595Y-243898D01*
G01X809021Y-254077D02*
X810337Y-255480D01*
X812179Y-256533D01*
X813759D01*
X815338Y-255831D01*
X816391Y-254778D01*
X816917Y-253375D01*
X816654Y-251268D01*
X815601Y-250215D01*
X810863Y-248110D01*
X809810Y-245652D01*
X810337Y-243898D01*
X811390Y-242845D01*
X812969Y-242494D01*
X814548Y-242845D01*
X816128Y-243898D01*
G01X834028Y-242494D02*
Y-256533D01*
G01Y-236878D02*
X833501Y-236527D01*
Y-235825D01*
X834028Y-235474D01*
X834555Y-235825D01*
Y-236527D01*
X834028Y-236878D01*
G01X855087Y-256533D02*
X853508Y-256182D01*
X851928Y-254778D01*
X850875Y-252321D01*
X850349Y-249514D01*
X850875Y-246706D01*
X851928Y-244249D01*
X853508Y-242845D01*
X855087Y-242494D01*
X856666Y-242845D01*
X858246Y-244249D01*
X859299Y-246706D01*
X859562Y-249514D01*
X859299Y-252321D01*
X858246Y-254778D01*
X856666Y-256182D01*
X855087Y-256533D01*
G01X871671D02*
Y-242494D01*
G01Y-246004D02*
X872724Y-244249D01*
X874304Y-242845D01*
X876409Y-242494D01*
X878252Y-242845D01*
X879831Y-244249D01*
X880621Y-246706D01*
Y-256533D01*
G01X747229Y-212520D02*
Y-191461D01*
X753547D01*
X755653Y-192514D01*
X757232Y-194971D01*
X757759Y-197779D01*
X757232Y-200587D01*
X755916Y-202693D01*
X753547Y-203746D01*
X747229D01*
G01X779344Y-193216D02*
X777765Y-192163D01*
X775922Y-191461D01*
X773816D01*
X771447Y-192514D01*
X769605Y-194269D01*
X768288Y-196375D01*
X767235Y-199885D01*
X766972Y-203044D01*
X767499Y-206202D01*
X768288Y-208308D01*
X769868Y-210415D01*
X771711Y-211818D01*
X773553Y-212520D01*
X775395D01*
X777238Y-211818D01*
X778818Y-210765D01*
X780134Y-209362D01*
G01X796718Y-201288D02*
X797771Y-200236D01*
X798560Y-198481D01*
X799087Y-196023D01*
X798560Y-193918D01*
X797508Y-192514D01*
X795665Y-191461D01*
X788558D01*
Y-212520D01*
X797244D01*
X799087Y-211116D01*
X800140Y-209010D01*
X800666Y-206553D01*
X800140Y-204097D01*
X798560Y-201991D01*
X796718Y-201288D01*
X788558D01*
G01X830676Y-212520D02*
Y-191461D01*
X842784Y-212520D01*
Y-191461D01*
G01X857789Y-212520D02*
X856210Y-212169D01*
X854630Y-210765D01*
X853577Y-208308D01*
X853051Y-205501D01*
X853577Y-202693D01*
X854630Y-200236D01*
X856210Y-198832D01*
X857789Y-198481D01*
X859368Y-198832D01*
X860948Y-200236D01*
X862001Y-202693D01*
X862264Y-205501D01*
X862001Y-208308D01*
X860948Y-210765D01*
X859368Y-212169D01*
X857789Y-212520D01*
G01X878848Y-213222D02*
X878321Y-212871D01*
Y-212169D01*
X878848Y-211818D01*
X879375Y-212169D01*
Y-212871D01*
X878848Y-213222D01*
G01X755710Y-168307D02*
Y-139727D01*
X764998Y-163544D01*
X774287Y-139727D01*
Y-168307D01*
G01X793578D02*
X791435Y-167831D01*
X789291Y-165926D01*
X787862Y-162591D01*
X787148Y-158781D01*
X787862Y-154970D01*
X789291Y-151635D01*
X791435Y-149730D01*
X793578Y-149254D01*
X795722Y-149730D01*
X797866Y-151635D01*
X799294Y-154970D01*
X799652Y-158781D01*
X799294Y-162591D01*
X797866Y-165926D01*
X795722Y-167831D01*
X793578Y-168307D01*
G01X828589Y-139727D02*
Y-168307D01*
G01Y-164021D02*
X827160Y-166402D01*
X825016Y-167831D01*
X822516Y-168307D01*
X819658Y-167355D01*
X817514Y-164973D01*
X816085Y-162115D01*
X815728Y-158781D01*
X816085Y-155446D01*
X817514Y-152588D01*
X819658Y-150207D01*
X822516Y-149254D01*
X825016Y-149730D01*
X826803Y-150683D01*
X828589Y-152588D01*
G01X845380Y-155446D02*
X856812D01*
X855740Y-152112D01*
X853954Y-150207D01*
X851453Y-149254D01*
X848952Y-149730D01*
X846809Y-151159D01*
X845380Y-154494D01*
X844665Y-157352D01*
Y-160209D01*
X845380Y-163068D01*
X847166Y-165926D01*
X849309Y-167831D01*
X851810Y-168307D01*
X854311Y-167355D01*
X856812Y-164497D01*
G01X879318Y-168307D02*
Y-139727D01*
G01X871051Y-401587D02*
X871208Y-400222D01*
X871443Y-399067D01*
X871756Y-398017D01*
X872148Y-396862D01*
X872775Y-395287D01*
X869641D01*
G01X871051Y959043D02*
X871208Y960408D01*
X871443Y961563D01*
X871756Y962613D01*
X872148Y963768D01*
X872775Y965343D01*
X869641D01*
G01X896250Y578318D02*
X897873Y568021D01*
X900185Y578186D01*
X896250Y578318D01*
G01X925276Y-328132D02*
X931198Y-361976D01*
X937967Y-328132D01*
X944736Y-361976D01*
X950659Y-328132D01*
G01X971811Y-339414D02*
Y-361976D01*
G01Y-330389D02*
X970965Y-329825D01*
Y-328696D01*
X971811Y-328132D01*
X972658Y-328696D01*
Y-329825D01*
X971811Y-330389D01*
G01X999310Y-358028D02*
X1001425Y-360284D01*
X1004386Y-361976D01*
X1006925D01*
X1009463Y-360848D01*
X1011155Y-359156D01*
X1012001Y-356900D01*
X1011578Y-353515D01*
X1009886Y-351823D01*
X1002271Y-348439D01*
X1000579Y-344490D01*
X1001425Y-341670D01*
X1003117Y-339978D01*
X1005655Y-339414D01*
X1008194Y-339978D01*
X1010732Y-341670D01*
G01X1039499Y-328132D02*
Y-361976D01*
G01X1033577Y-339414D02*
X1045422D01*
G01X1067421Y-361976D02*
Y-339414D01*
G01Y-343926D02*
X1069536Y-341670D01*
X1071651Y-339978D01*
X1074613Y-339414D01*
X1076728Y-339978D01*
X1079266Y-341670D01*
G01X1107187Y-361976D02*
X1104649Y-361412D01*
X1102111Y-359156D01*
X1100418Y-355208D01*
X1099572Y-350695D01*
X1100418Y-346182D01*
X1102111Y-342234D01*
X1104649Y-339978D01*
X1107187Y-339414D01*
X1109726Y-339978D01*
X1112264Y-342234D01*
X1113956Y-346182D01*
X1114380Y-350695D01*
X1113956Y-355208D01*
X1112264Y-359156D01*
X1109726Y-361412D01*
X1107187Y-361976D01*
G01X1133839D02*
Y-339414D01*
G01Y-345055D02*
X1135532Y-342234D01*
X1138070Y-339978D01*
X1141455Y-339414D01*
X1144416Y-339978D01*
X1146954Y-342234D01*
X1148224Y-346182D01*
Y-361976D01*
G01X1218027Y-330953D02*
X1215488Y-329260D01*
X1212527Y-328132D01*
X1209143D01*
X1205335Y-329825D01*
X1202374Y-332645D01*
X1200258Y-336029D01*
X1198566Y-341670D01*
X1198143Y-346746D01*
X1198989Y-351823D01*
X1200258Y-355208D01*
X1202797Y-358592D01*
X1205758Y-360848D01*
X1208719Y-361976D01*
X1211681D01*
X1214642Y-360848D01*
X1217181Y-359156D01*
X1219296Y-356900D01*
G01X1242563Y-361976D02*
X1240025Y-361412D01*
X1237487Y-359156D01*
X1235794Y-355208D01*
X1234948Y-350695D01*
X1235794Y-346182D01*
X1237487Y-342234D01*
X1240025Y-339978D01*
X1242563Y-339414D01*
X1245102Y-339978D01*
X1247640Y-342234D01*
X1249332Y-346182D01*
X1249756Y-350695D01*
X1249332Y-355208D01*
X1247640Y-359156D01*
X1245102Y-361412D01*
X1242563Y-361976D01*
G01X1270485D02*
Y-339414D01*
G01Y-343926D02*
X1272600Y-341670D01*
X1274715Y-339978D01*
X1277677Y-339414D01*
X1279792Y-339978D01*
X1282330Y-341670D01*
G01X1302636Y-373257D02*
Y-339414D01*
G01Y-344490D02*
X1304752Y-341670D01*
X1306867Y-339978D01*
X1310251Y-339414D01*
X1313213Y-339978D01*
X1316174Y-342798D01*
X1317444Y-346746D01*
X1317867Y-350695D01*
X1317444Y-354644D01*
X1316174Y-358592D01*
X1313636Y-360848D01*
X1310251Y-361976D01*
X1307290Y-361412D01*
X1304329Y-359720D01*
X1302636Y-357464D01*
G01X1344095Y-361976D02*
X1341557Y-361412D01*
X1339019Y-359156D01*
X1337326Y-355208D01*
X1336480Y-350695D01*
X1337326Y-346182D01*
X1339019Y-342234D01*
X1341557Y-339978D01*
X1344095Y-339414D01*
X1346634Y-339978D01*
X1349172Y-342234D01*
X1350864Y-346182D01*
X1351288Y-350695D01*
X1350864Y-355208D01*
X1349172Y-359156D01*
X1346634Y-361412D01*
X1344095Y-361976D01*
G01X1372017D02*
Y-339414D01*
G01Y-343926D02*
X1374132Y-341670D01*
X1376247Y-339978D01*
X1379209Y-339414D01*
X1381324Y-339978D01*
X1383862Y-341670D01*
G01X1419399Y-361976D02*
Y-339414D01*
G01Y-343362D02*
X1417706Y-341106D01*
X1415168Y-339978D01*
X1412207Y-339414D01*
X1409245Y-340542D01*
X1406707Y-342798D01*
X1405014Y-346182D01*
X1404168Y-350695D01*
X1405014Y-355208D01*
X1406707Y-358592D01*
X1409245Y-360848D01*
X1412207Y-361976D01*
X1415168Y-361412D01*
X1417706Y-359720D01*
X1419399Y-357464D01*
G01X1445627Y-328132D02*
Y-361976D01*
G01X1439705Y-339414D02*
X1451550D01*
G01X1479471D02*
Y-361976D01*
G01Y-330389D02*
X1478625Y-329825D01*
Y-328696D01*
X1479471Y-328132D01*
X1480318Y-328696D01*
Y-329825D01*
X1479471Y-330389D01*
G01X1513315Y-361976D02*
X1510777Y-361412D01*
X1508239Y-359156D01*
X1506546Y-355208D01*
X1505700Y-350695D01*
X1506546Y-346182D01*
X1508239Y-342234D01*
X1510777Y-339978D01*
X1513315Y-339414D01*
X1515854Y-339978D01*
X1518392Y-342234D01*
X1520084Y-346182D01*
X1520508Y-350695D01*
X1520084Y-355208D01*
X1518392Y-359156D01*
X1515854Y-361412D01*
X1513315Y-361976D01*
G01X1539967D02*
Y-339414D01*
G01Y-345055D02*
X1541660Y-342234D01*
X1544198Y-339978D01*
X1547583Y-339414D01*
X1550544Y-339978D01*
X1553082Y-342234D01*
X1554352Y-346182D01*
Y-361976D01*
G01X912371Y117675D02*
X915494Y107730D01*
X918960Y109598D01*
X912371Y117675D01*
G01X914463Y186300D02*
X921369Y194108D01*
X917981Y196112D01*
X914463Y186300D01*
G01X948367Y-282407D02*
X954948Y-303466D01*
X961529Y-282407D01*
G01X976007Y-289427D02*
Y-303466D01*
G01Y-283811D02*
X975480Y-283460D01*
Y-282758D01*
X976007Y-282407D01*
X976534Y-282758D01*
Y-283460D01*
X976007Y-283811D01*
G01X997066Y-303466D02*
Y-282407D01*
G01X1014177Y-293990D02*
X1022600D01*
X1021810Y-291533D01*
X1020494Y-290129D01*
X1018652Y-289427D01*
X1016809Y-289778D01*
X1015229Y-290831D01*
X1014177Y-293288D01*
X1013650Y-295394D01*
Y-297499D01*
X1014177Y-299605D01*
X1015493Y-301711D01*
X1017072Y-303115D01*
X1018915Y-303466D01*
X1020757Y-302764D01*
X1022600Y-300659D01*
G01X1043922Y-303466D02*
Y-289427D01*
G01Y-291883D02*
X1042869Y-290480D01*
X1041290Y-289778D01*
X1039447Y-289427D01*
X1037605Y-290129D01*
X1036025Y-291533D01*
X1034972Y-293639D01*
X1034446Y-296447D01*
X1034972Y-299254D01*
X1036025Y-301361D01*
X1037605Y-302764D01*
X1039447Y-303466D01*
X1041290Y-303115D01*
X1042869Y-302062D01*
X1043922Y-300659D01*
G01X1055768Y-303466D02*
Y-289427D01*
G01Y-292937D02*
X1056821Y-291182D01*
X1058401Y-289778D01*
X1060506Y-289427D01*
X1062349Y-289778D01*
X1063928Y-291182D01*
X1064718Y-293639D01*
Y-303466D01*
G01X1097096Y-282407D02*
Y-303466D01*
X1107626D01*
G01X1123420Y-289427D02*
Y-303466D01*
G01Y-283811D02*
X1122893Y-283460D01*
Y-282758D01*
X1123420Y-282407D01*
X1123947Y-282758D01*
Y-283460D01*
X1123420Y-283811D01*
G01X960695Y-210545D02*
Y-189486D01*
X957536Y-193698D01*
G01Y-210545D02*
X963853D01*
G01X981227D02*
X981754Y-205983D01*
X982544Y-202122D01*
X983596Y-198612D01*
X984913Y-194751D01*
X987019Y-189486D01*
X976489D01*
G01X997022Y-206333D02*
X998601Y-208790D01*
X1000707Y-210194D01*
X1003076Y-210545D01*
X1005182Y-210194D01*
X1007288Y-208440D01*
X1008604Y-206333D01*
X1008867Y-204227D01*
X1008341Y-201771D01*
X1006498Y-200016D01*
X1004655Y-199313D01*
X1002286D01*
G01X1004655D02*
X1006235Y-198261D01*
X1007551Y-196506D01*
X1008078Y-194400D01*
X1007551Y-192294D01*
X1006235Y-190539D01*
X1003866Y-189486D01*
X1001497Y-189837D01*
X999128Y-191241D01*
G01X1023872Y-189486D02*
X1021766Y-190188D01*
X1020187Y-191943D01*
X1019134Y-194048D01*
X1018344Y-196857D01*
X1018081Y-200016D01*
X1018344Y-203175D01*
X1019134Y-205983D01*
X1020187Y-208089D01*
X1021766Y-209843D01*
X1023872Y-210545D01*
X1025978Y-209843D01*
X1027557Y-208089D01*
X1028610Y-205983D01*
X1029400Y-203175D01*
X1029663Y-200016D01*
X1029400Y-196857D01*
X1028610Y-194048D01*
X1027557Y-191943D01*
X1025978Y-190188D01*
X1023872Y-189486D01*
G01X1044931Y-210545D02*
Y-189486D01*
X1041772Y-193698D01*
G01Y-210545D02*
X1048089D01*
G01X951500Y-135658D02*
Y-164600D01*
G01X943179Y-135658D02*
X959821D01*
G01X980441Y-145306D02*
Y-164600D01*
G01Y-137588D02*
X979717Y-137106D01*
Y-136140D01*
X980441Y-135658D01*
X981165Y-136140D01*
Y-137106D01*
X980441Y-137588D01*
G01X1009382Y-164600D02*
X1007212Y-164118D01*
X1005041Y-162189D01*
X1003593Y-158812D01*
X1002870Y-154953D01*
X1003593Y-151094D01*
X1005041Y-147717D01*
X1007212Y-145788D01*
X1009382Y-145306D01*
X1011552Y-145788D01*
X1013723Y-147717D01*
X1015170Y-151094D01*
X1015532Y-154953D01*
X1015170Y-158812D01*
X1013723Y-162189D01*
X1011552Y-164118D01*
X1009382Y-164600D01*
G01X1033258Y-171836D02*
X1035791Y-173765D01*
X1038685Y-174247D01*
X1041217Y-173765D01*
X1043388Y-171353D01*
X1044835Y-167977D01*
Y-145306D01*
G01Y-149164D02*
X1043388Y-147235D01*
X1041217Y-145788D01*
X1038685Y-145306D01*
X1035791Y-146270D01*
X1033982Y-148200D01*
X1032534Y-151576D01*
X1031811Y-154953D01*
X1032173Y-157847D01*
X1033620Y-161224D01*
X1035791Y-163635D01*
X1038685Y-164600D01*
X1040855Y-164118D01*
X1043388Y-162189D01*
X1044835Y-160260D01*
G01X1073776Y-164600D02*
Y-145306D01*
G01Y-148682D02*
X1072329Y-146753D01*
X1070158Y-145788D01*
X1067626Y-145306D01*
X1065094Y-146270D01*
X1062923Y-148200D01*
X1061475Y-151094D01*
X1060752Y-154953D01*
X1061475Y-158812D01*
X1062923Y-161706D01*
X1065094Y-163635D01*
X1067626Y-164600D01*
X1070158Y-164118D01*
X1072329Y-162671D01*
X1073776Y-160742D01*
G01X1091502Y-154953D02*
X1100908D01*
G01X1117911Y-164600D02*
Y-135658D01*
X1126593D01*
X1129487Y-137106D01*
X1131658Y-140482D01*
X1132381Y-144341D01*
X1131658Y-148200D01*
X1129849Y-151094D01*
X1126593Y-152542D01*
X1117911D01*
G01X1160599Y-164600D02*
Y-145306D01*
G01Y-148682D02*
X1159152Y-146753D01*
X1156981Y-145788D01*
X1154449Y-145306D01*
X1151917Y-146270D01*
X1149746Y-148200D01*
X1148298Y-151094D01*
X1147575Y-154953D01*
X1148298Y-158812D01*
X1149746Y-161706D01*
X1151917Y-163635D01*
X1154449Y-164600D01*
X1156981Y-164118D01*
X1159152Y-162671D01*
X1160599Y-160742D01*
G01X1177602Y-161224D02*
X1179410Y-163153D01*
X1181943Y-164600D01*
X1184113D01*
X1186284Y-163635D01*
X1187731Y-162189D01*
X1188454Y-160260D01*
X1188093Y-157364D01*
X1186646Y-155917D01*
X1180133Y-153024D01*
X1178687Y-149646D01*
X1179410Y-147235D01*
X1180858Y-145788D01*
X1183028Y-145306D01*
X1185198Y-145788D01*
X1187369Y-147235D01*
G01X1206543Y-161224D02*
X1208351Y-163153D01*
X1210884Y-164600D01*
X1213054D01*
X1215225Y-163635D01*
X1216672Y-162189D01*
X1217395Y-160260D01*
X1217034Y-157364D01*
X1215587Y-155917D01*
X1209074Y-153024D01*
X1207628Y-149646D01*
X1208351Y-147235D01*
X1209799Y-145788D01*
X1211969Y-145306D01*
X1214139Y-145788D01*
X1216310Y-147235D01*
G01X1277810Y-138070D02*
X1275639Y-136623D01*
X1273107Y-135658D01*
X1270213D01*
X1266956Y-137106D01*
X1264425Y-139517D01*
X1262616Y-142411D01*
X1261168Y-147235D01*
X1260806Y-151576D01*
X1261530Y-155917D01*
X1262616Y-158812D01*
X1264786Y-161706D01*
X1267319Y-163635D01*
X1269851Y-164600D01*
X1272383D01*
X1274916Y-163635D01*
X1277086Y-162189D01*
X1278896Y-160260D01*
G01X1292642Y-164600D02*
Y-135658D01*
G01Y-149646D02*
X1294451Y-147235D01*
X1296260Y-145788D01*
X1299154Y-145306D01*
X1301324Y-145788D01*
X1303857Y-147717D01*
X1304942Y-150612D01*
Y-164600D01*
G01X1334245D02*
Y-145306D01*
G01Y-148682D02*
X1332798Y-146753D01*
X1330627Y-145788D01*
X1328095Y-145306D01*
X1325563Y-146270D01*
X1323392Y-148200D01*
X1321944Y-151094D01*
X1321221Y-154953D01*
X1321944Y-158812D01*
X1323392Y-161706D01*
X1325563Y-163635D01*
X1328095Y-164600D01*
X1330627Y-164118D01*
X1332798Y-162671D01*
X1334245Y-160742D01*
G01X1350524Y-164600D02*
Y-145306D01*
G01Y-150129D02*
X1351971Y-147717D01*
X1354142Y-145788D01*
X1357036Y-145306D01*
X1359568Y-145788D01*
X1361739Y-147717D01*
X1362824Y-151094D01*
Y-164600D01*
G01X1379465D02*
Y-145306D01*
G01Y-150129D02*
X1380912Y-147717D01*
X1383083Y-145788D01*
X1385977Y-145306D01*
X1388509Y-145788D01*
X1390680Y-147717D01*
X1391765Y-151094D01*
Y-164600D01*
G01X1409130Y-151576D02*
X1420706D01*
X1419621Y-148200D01*
X1417812Y-146270D01*
X1415280Y-145306D01*
X1412747Y-145788D01*
X1410576Y-147235D01*
X1409130Y-150612D01*
X1408406Y-153506D01*
Y-156400D01*
X1409130Y-159294D01*
X1410938Y-162189D01*
X1413109Y-164118D01*
X1415641Y-164600D01*
X1418174Y-163635D01*
X1420706Y-160742D01*
G01X1443497Y-164600D02*
Y-135658D01*
G01X969197Y-258620D02*
X971303Y-260374D01*
X973672Y-261427D01*
X975778D01*
X977884Y-260374D01*
X979463Y-258620D01*
X980253Y-256162D01*
X979727Y-253706D01*
X978410Y-251600D01*
X976041Y-250195D01*
X972883Y-249494D01*
X971040Y-248090D01*
X970250Y-245633D01*
X970777Y-243176D01*
X972093Y-241421D01*
X973935Y-240368D01*
X975778D01*
X977621Y-241070D01*
X979200Y-242825D01*
G01X989203Y-261427D02*
X995784Y-240368D01*
X1002365Y-261427D01*
G01X999996Y-254057D02*
X991572D01*
G01X1044436Y-401587D02*
X1044984Y-401482D01*
X1045611Y-401167D01*
X1046003Y-400642D01*
X1046159Y-399907D01*
X1046003Y-399172D01*
X1045533Y-398542D01*
X1044828Y-398227D01*
X1044044D01*
X1043574Y-398017D01*
X1043183Y-397492D01*
X1043026Y-396757D01*
X1043261Y-396022D01*
X1043809Y-395497D01*
X1044436Y-395287D01*
X1045063Y-395497D01*
X1045611Y-396022D01*
X1045846Y-396757D01*
X1045689Y-397492D01*
X1045298Y-398017D01*
X1044828Y-398227D01*
X1044044D01*
X1043339Y-398542D01*
X1042869Y-399172D01*
X1042713Y-399907D01*
X1042869Y-400642D01*
X1043261Y-401167D01*
X1043888Y-401482D01*
X1044436Y-401587D01*
G01Y959043D02*
X1044984Y959148D01*
X1045611Y959463D01*
X1046003Y959988D01*
X1046159Y960723D01*
X1046003Y961458D01*
X1045533Y962088D01*
X1044828Y962403D01*
X1044044D01*
X1043574Y962613D01*
X1043183Y963138D01*
X1043026Y963873D01*
X1043261Y964608D01*
X1043809Y965133D01*
X1044436Y965343D01*
X1045063Y965133D01*
X1045611Y964608D01*
X1045846Y963873D01*
X1045689Y963138D01*
X1045298Y962613D01*
X1044828Y962403D01*
X1044044D01*
X1043339Y962088D01*
X1042869Y961458D01*
X1042713Y960723D01*
X1042869Y959988D01*
X1043261Y959463D01*
X1043888Y959148D01*
X1044436Y959043D01*
G01X1190502Y355726D02*
X1183190Y363156D01*
X1180957Y359915D01*
X1190502Y355726D01*
G01X1216333Y-400852D02*
X1216882Y-401377D01*
X1217508Y-401587D01*
X1218135Y-401377D01*
X1218683Y-400747D01*
X1219075Y-399802D01*
X1219232Y-398857D01*
Y-397702D01*
X1219075Y-396757D01*
X1218683Y-395917D01*
X1218213Y-395497D01*
X1217665Y-395287D01*
X1217038Y-395497D01*
X1216568Y-395917D01*
X1216255Y-396547D01*
X1216098Y-397387D01*
X1216255Y-398122D01*
X1216647Y-398857D01*
X1217117Y-399277D01*
X1217665Y-399382D01*
X1218292Y-399172D01*
X1218762Y-398647D01*
X1219232Y-397702D01*
G01X1216333Y959778D02*
X1216882Y959253D01*
X1217508Y959043D01*
X1218135Y959253D01*
X1218683Y959883D01*
X1219075Y960828D01*
X1219232Y961773D01*
Y962928D01*
X1219075Y963873D01*
X1218683Y964713D01*
X1218213Y965133D01*
X1217665Y965343D01*
X1217038Y965133D01*
X1216568Y964713D01*
X1216255Y964083D01*
X1216098Y963243D01*
X1216255Y962508D01*
X1216647Y961773D01*
X1217117Y961353D01*
X1217665Y961248D01*
X1218292Y961458D01*
X1218762Y961983D01*
X1219232Y962928D01*
G01X1273158Y-235674D02*
Y-256733D01*
G01X1267104Y-235674D02*
X1279212D01*
G01X1289742Y-256733D02*
Y-235674D01*
G01Y-245852D02*
X1291058Y-244098D01*
X1292375Y-243045D01*
X1294480Y-242694D01*
X1296059Y-243045D01*
X1297902Y-244449D01*
X1298692Y-246555D01*
Y-256733D01*
G01X1315276Y-242694D02*
Y-256733D01*
G01Y-237078D02*
X1314749Y-236727D01*
Y-236025D01*
X1315276Y-235674D01*
X1315803Y-236025D01*
Y-236727D01*
X1315276Y-237078D01*
G01X1340547Y-244449D02*
X1338704Y-243045D01*
X1337125Y-242694D01*
X1335019Y-243396D01*
X1333439Y-244800D01*
X1332387Y-247257D01*
X1332123Y-249714D01*
X1332387Y-252171D01*
X1333439Y-254277D01*
X1335019Y-256031D01*
X1337125Y-256733D01*
X1338967Y-256031D01*
X1340547Y-254628D01*
G01X1352919Y-256733D02*
Y-235674D01*
G01X1361342Y-242694D02*
X1352919Y-250766D01*
G01X1356341Y-247607D02*
X1361869Y-256733D01*
G01X1373978D02*
Y-242694D01*
G01Y-246204D02*
X1375031Y-244449D01*
X1376611Y-243045D01*
X1378716Y-242694D01*
X1380559Y-243045D01*
X1382138Y-244449D01*
X1382928Y-246906D01*
Y-256733D01*
G01X1395564Y-247257D02*
X1403987D01*
X1403197Y-244800D01*
X1401881Y-243396D01*
X1400039Y-242694D01*
X1398196Y-243045D01*
X1396616Y-244098D01*
X1395564Y-246555D01*
X1395037Y-248661D01*
Y-250766D01*
X1395564Y-252872D01*
X1396880Y-254978D01*
X1398459Y-256382D01*
X1400302Y-256733D01*
X1402144Y-256031D01*
X1403987Y-253926D01*
G01X1416623Y-254277D02*
X1417939Y-255680D01*
X1419781Y-256733D01*
X1421361D01*
X1422940Y-256031D01*
X1423993Y-254978D01*
X1424519Y-253575D01*
X1424256Y-251468D01*
X1423203Y-250415D01*
X1418465Y-248310D01*
X1417412Y-245852D01*
X1417939Y-244098D01*
X1418992Y-243045D01*
X1420571Y-242694D01*
X1422150Y-243045D01*
X1423730Y-244098D01*
G01X1437682Y-254277D02*
X1438998Y-255680D01*
X1440840Y-256733D01*
X1442420D01*
X1443999Y-256031D01*
X1445052Y-254978D01*
X1445578Y-253575D01*
X1445315Y-251468D01*
X1444262Y-250415D01*
X1439524Y-248310D01*
X1438471Y-245852D01*
X1438998Y-244098D01*
X1440051Y-243045D01*
X1441630Y-242694D01*
X1443209Y-243045D01*
X1444789Y-244098D01*
G01X1309940Y-305441D02*
Y-284382D01*
X1315204D01*
X1317310Y-285435D01*
X1318890Y-286839D01*
X1320206Y-288944D01*
X1321259Y-291402D01*
X1321522Y-294912D01*
X1321259Y-298422D01*
X1320206Y-300879D01*
X1318890Y-302985D01*
X1317310Y-304388D01*
X1315204Y-305441D01*
X1309940D01*
G01X1341528D02*
Y-291402D01*
G01Y-293858D02*
X1340475Y-292455D01*
X1338896Y-291753D01*
X1337053Y-291402D01*
X1335211Y-292104D01*
X1333631Y-293508D01*
X1332578Y-295614D01*
X1332052Y-298422D01*
X1332578Y-301229D01*
X1333631Y-303336D01*
X1335211Y-304739D01*
X1337053Y-305441D01*
X1338896Y-305090D01*
X1340475Y-304037D01*
X1341528Y-302634D01*
G01X1357849Y-284382D02*
Y-305441D01*
G01X1354164Y-291402D02*
X1361534D01*
G01X1374960Y-295965D02*
X1383383D01*
X1382593Y-293508D01*
X1381277Y-292104D01*
X1379435Y-291402D01*
X1377592Y-291753D01*
X1376012Y-292806D01*
X1374960Y-295263D01*
X1374433Y-297369D01*
Y-299474D01*
X1374960Y-301580D01*
X1376276Y-303686D01*
X1377855Y-305090D01*
X1379698Y-305441D01*
X1381540Y-304739D01*
X1383383Y-302634D01*
G01X1390893Y-401587D02*
Y-395287D01*
X1389953Y-396547D01*
G01Y-401587D02*
X1391833D01*
G01X1397193Y-395287D02*
X1396566Y-395497D01*
X1396096Y-396022D01*
X1395783Y-396652D01*
X1395548Y-397492D01*
X1395470Y-398437D01*
X1395548Y-399382D01*
X1395783Y-400222D01*
X1396096Y-400852D01*
X1396566Y-401377D01*
X1397193Y-401587D01*
X1397820Y-401377D01*
X1398290Y-400852D01*
X1398603Y-400222D01*
X1398838Y-399382D01*
X1398916Y-398437D01*
X1398838Y-397492D01*
X1398603Y-396652D01*
X1398290Y-396022D01*
X1397820Y-395497D01*
X1397193Y-395287D01*
G01X1390893Y959043D02*
Y965343D01*
X1389953Y964083D01*
G01Y959043D02*
X1391833D01*
G01X1397193Y965343D02*
X1396566Y965133D01*
X1396096Y964608D01*
X1395783Y963978D01*
X1395548Y963138D01*
X1395470Y962193D01*
X1395548Y961248D01*
X1395783Y960408D01*
X1396096Y959778D01*
X1396566Y959253D01*
X1397193Y959043D01*
X1397820Y959253D01*
X1398290Y959778D01*
X1398603Y960408D01*
X1398838Y961248D01*
X1398916Y962193D01*
X1398838Y963138D01*
X1398603Y963978D01*
X1398290Y964608D01*
X1397820Y965133D01*
X1397193Y965343D01*
G01X1468389Y-285917D02*
X1469969Y-283811D01*
X1471812Y-282758D01*
X1473918Y-282407D01*
X1476550Y-283109D01*
X1478393Y-284864D01*
X1478919Y-286969D01*
X1478656Y-289076D01*
X1477603Y-290831D01*
X1472338Y-294340D01*
X1469969Y-296797D01*
X1468389Y-300308D01*
X1467863Y-303466D01*
X1478919D01*
G01X1494450Y-282407D02*
X1492344Y-283109D01*
X1490765Y-284864D01*
X1489712Y-286969D01*
X1488922Y-289778D01*
X1488659Y-292937D01*
X1488922Y-296096D01*
X1489712Y-298904D01*
X1490765Y-301010D01*
X1492344Y-302764D01*
X1494450Y-303466D01*
X1496556Y-302764D01*
X1498135Y-301010D01*
X1499188Y-298904D01*
X1499978Y-296096D01*
X1500241Y-292937D01*
X1499978Y-289778D01*
X1499188Y-286969D01*
X1498135Y-284864D01*
X1496556Y-283109D01*
X1494450Y-282407D01*
G01X1515509Y-303466D02*
Y-282407D01*
X1512350Y-286619D01*
G01Y-303466D02*
X1518667D01*
G01X1536041D02*
X1536568Y-298904D01*
X1537358Y-295043D01*
X1538410Y-291533D01*
X1539727Y-287672D01*
X1541833Y-282407D01*
X1531303D01*
G01X1554205Y-296447D02*
X1561049D01*
G01X1578686Y-282407D02*
X1576580Y-283109D01*
X1575001Y-284864D01*
X1573948Y-286969D01*
X1573158Y-289778D01*
X1572895Y-292937D01*
X1573158Y-296096D01*
X1573948Y-298904D01*
X1575001Y-301010D01*
X1576580Y-302764D01*
X1578686Y-303466D01*
X1580792Y-302764D01*
X1582371Y-301010D01*
X1583424Y-298904D01*
X1584214Y-296096D01*
X1584477Y-292937D01*
X1584214Y-289778D01*
X1583424Y-286969D01*
X1582371Y-284864D01*
X1580792Y-283109D01*
X1578686Y-282407D01*
G01X1594743Y-294692D02*
X1596586Y-292234D01*
X1598166Y-290831D01*
X1600272Y-290129D01*
X1602114Y-290831D01*
X1603430Y-292234D01*
X1604483Y-294340D01*
X1604747Y-296797D01*
X1604483Y-298904D01*
X1603430Y-301010D01*
X1601851Y-302764D01*
X1600008Y-303466D01*
X1597903Y-302764D01*
X1596060Y-300659D01*
X1595007Y-297499D01*
X1594743Y-293990D01*
X1595270Y-289427D01*
X1596060Y-286969D01*
X1597376Y-284513D01*
X1599218Y-282758D01*
X1601061Y-282407D01*
X1602904Y-283109D01*
X1604220Y-284864D01*
G01X1617382Y-296447D02*
X1624226D01*
G01X1636861Y-285917D02*
X1638441Y-283811D01*
X1640284Y-282758D01*
X1642390Y-282407D01*
X1645022Y-283109D01*
X1646865Y-284864D01*
X1647391Y-286969D01*
X1647128Y-289076D01*
X1646075Y-290831D01*
X1640810Y-294340D01*
X1638441Y-296797D01*
X1636861Y-300308D01*
X1636335Y-303466D01*
X1647391D01*
G01X1662922D02*
Y-282407D01*
X1659763Y-286619D01*
G01Y-303466D02*
X1666080D01*
G01X1486041Y-237209D02*
X1487621Y-235103D01*
X1489464Y-234050D01*
X1491570Y-233699D01*
X1494202Y-234401D01*
X1496045Y-236156D01*
X1496571Y-238261D01*
X1496308Y-240368D01*
X1495255Y-242123D01*
X1489990Y-245632D01*
X1487621Y-248089D01*
X1486041Y-251600D01*
X1485515Y-254758D01*
X1496571D01*
G01X1512102Y-255460D02*
X1511575Y-255109D01*
Y-254407D01*
X1512102Y-254056D01*
X1512629Y-254407D01*
Y-255109D01*
X1512102Y-255460D01*
G01X1533161Y-233699D02*
X1531055Y-234401D01*
X1529476Y-236156D01*
X1528423Y-238261D01*
X1527633Y-241070D01*
X1527370Y-244229D01*
X1527633Y-247388D01*
X1528423Y-250196D01*
X1529476Y-252302D01*
X1531055Y-254056D01*
X1533161Y-254758D01*
X1535267Y-254056D01*
X1536846Y-252302D01*
X1537899Y-250196D01*
X1538689Y-247388D01*
X1538952Y-244229D01*
X1538689Y-241070D01*
X1537899Y-238261D01*
X1536846Y-236156D01*
X1535267Y-234401D01*
X1533161Y-233699D01*
G01X1554220Y-254758D02*
Y-233699D01*
X1551061Y-237911D01*
G01Y-254758D02*
X1557378D01*
G01X1567382D02*
Y-240719D01*
G01Y-244580D02*
X1568172Y-242825D01*
X1569488Y-241421D01*
X1571331Y-240719D01*
X1573173Y-241421D01*
X1574489Y-242825D01*
X1575279Y-244580D01*
Y-254758D01*
G01Y-244580D02*
X1576069Y-242825D01*
X1577385Y-241421D01*
X1579227Y-240719D01*
X1581070Y-241421D01*
X1582386Y-242825D01*
X1583176Y-244931D01*
Y-254758D01*
G01X1588441D02*
Y-240719D01*
G01Y-244580D02*
X1589231Y-242825D01*
X1590547Y-241421D01*
X1592390Y-240719D01*
X1594232Y-241421D01*
X1595548Y-242825D01*
X1596338Y-244580D01*
Y-254758D01*
G01Y-244580D02*
X1597128Y-242825D01*
X1598444Y-241421D01*
X1600286Y-240719D01*
X1602129Y-241421D01*
X1603445Y-242825D01*
X1604235Y-244931D01*
Y-254758D01*
G01X1564121Y-401587D02*
Y-395287D01*
X1563181Y-396547D01*
G01Y-401587D02*
X1565061D01*
G01X1570421D02*
Y-395287D01*
X1569481Y-396547D01*
G01Y-401587D02*
X1571361D01*
G01X1564121Y959043D02*
Y965343D01*
X1563181Y964083D01*
G01Y959043D02*
X1565061D01*
G01X1570421D02*
Y965343D01*
X1569481Y964083D01*
G01Y959043D02*
X1571361D01*
G01X1693578Y-331509D02*
Y-325209D01*
X1696554D01*
G01X1695458Y-328254D02*
X1693578D01*
G01X1696633Y-95288D02*
X1693499D01*
Y-88988D01*
X1696633D01*
G01X1695379Y-92033D02*
X1693499D01*
G01X1693343Y140932D02*
Y147232D01*
X1694909D01*
X1695536Y146917D01*
X1696006Y146497D01*
X1696398Y145867D01*
X1696711Y145132D01*
X1696789Y144082D01*
X1696711Y143032D01*
X1696398Y142297D01*
X1696006Y141667D01*
X1695536Y141247D01*
X1694909Y140932D01*
X1693343D01*
G01X1696789Y382928D02*
X1696319Y383243D01*
X1695771Y383453D01*
X1695144D01*
X1694439Y383138D01*
X1693891Y382613D01*
X1693499Y381983D01*
X1693186Y380933D01*
X1693108Y379988D01*
X1693264Y379043D01*
X1693499Y378413D01*
X1693969Y377783D01*
X1694518Y377363D01*
X1695066Y377153D01*
X1695614D01*
X1696163Y377363D01*
X1696633Y377678D01*
X1697024Y378098D01*
G01X1695693Y616733D02*
X1696006Y617048D01*
X1696241Y617573D01*
X1696398Y618308D01*
X1696241Y618938D01*
X1695928Y619358D01*
X1695379Y619673D01*
X1693264D01*
Y613373D01*
X1695849D01*
X1696398Y613793D01*
X1696711Y614423D01*
X1696868Y615158D01*
X1696711Y615893D01*
X1696241Y616523D01*
X1695693Y616733D01*
X1693264D01*
G01X1693108Y849595D02*
X1695066Y855895D01*
X1697024Y849595D01*
G01X1696319Y851800D02*
X1693813D01*
G01X-262126Y-407840D02*
X1706377D01*
G01X-262126Y970112D02*
Y-407840D01*
G01Y-210990D02*
X-244804D01*
G01X-262126Y25230D02*
X-244804D01*
G01X-262126Y261450D02*
X-244804D01*
G01X-262126Y497671D02*
X-244804D01*
G01X-262126Y733891D02*
X-244804D01*
G01X-262126Y970112D02*
X1706377D01*
G01X-244804Y-390518D02*
X1689055D01*
G01X-244804Y952789D02*
Y-390518D01*
G01Y952789D02*
X1689055D01*
G01X-88898Y-390518D02*
Y-407840D01*
G01Y970112D02*
Y952789D01*
G01X0Y0D02*
X-61786D01*
G01X-25590Y105118D02*
X-61786D01*
G01X273622Y256693D02*
X-61786D01*
G01X-25590Y361811D02*
X-61786D01*
G01X0Y369685D02*
X-61786D01*
G01X-25590Y474803D02*
X-61786D01*
G01X273622Y626378D02*
X-61786D01*
G01X-25590Y731496D02*
X-61786D01*
G01X-25590Y9843D02*
G03X-15748Y0I9842J-1D01*
G01X-25590Y89370D02*
Y9843D01*
G01X-23622Y91339D02*
G03X-25590Y89370I1J-1969D01*
G01X-7874Y91339D02*
X-23622D01*
G01X-25590Y109055D02*
G03X-21653Y105118I3937J0D01*
G01X-3543Y118898D02*
G03I-8268J0D01*
G01X-25590Y357874D02*
Y109055D01*
G01X-21653Y105118D02*
X261811D01*
G01X-25590Y371654D02*
G03X-23622Y369685I1968J-1D01*
G01X-21653Y361811D02*
G03X-25590Y357874I0J-3937D01*
G01X1969Y361811D02*
X-21653D01*
G01X-7874Y369685D02*
X-23622D01*
G01X-25590Y459055D02*
Y371654D01*
G01X-10463Y415558D02*
G03I-4292J0D01*
G01X-23622Y461024D02*
G03X-25590Y459055I1J-1969D01*
G01X-7874Y461024D02*
X-23622D01*
G01X-25590Y478740D02*
G03X-21653Y474803I3937J0D01*
G01X-3543Y488583D02*
G03I-8268J0D01*
G01X-25590Y727559D02*
Y478740D01*
G01X-21653Y474803D02*
X261811D01*
G01X-25590Y731496D02*
Y769168D01*
G01X-21653Y731496D02*
G03X-25590Y727559I0J-3937D01*
G01X1969Y731496D02*
X-21653D01*
G01X-11811Y0D02*
G03X-7874Y3937I0J3937D01*
G01Y33071D02*
Y3937D01*
G01X-11811Y0D02*
X-15748D01*
G01X0Y3937D02*
G03X3937Y0I3937J0D01*
G01X0Y87402D02*
Y3937D01*
G01Y33071D02*
G03X-7874I-3937J0D01*
G01Y58268D02*
G03X0I3937J0D01*
G01X-7874Y91339D02*
Y58268D01*
G01X-8162Y45507D02*
G03I-4292J0D01*
G01X3937Y91339D02*
G03X0Y87402I0J-3937D01*
G01X-9134Y321654D02*
G03I-4291J0D01*
G01X-5315Y348032D02*
G03I-6496J0D01*
G01X5906Y357874D02*
G03X1969Y361811I-3937J0D01*
G01X0Y373622D02*
G03X3937Y369685I3937J0D01*
G01X-7874Y402756D02*
Y369685D01*
G01X0Y457087D02*
Y373622D01*
G01Y402756D02*
G03X-7874I-3937J0D01*
G01Y427953D02*
G03X0I3937J0D01*
G01X-7874Y461024D02*
Y427953D01*
G01X0Y461024D02*
Y769168D01*
G01X3937Y461024D02*
G03X0Y457087I0J-3937D01*
G01X-9134Y691339D02*
G03I-4291J0D01*
G01X-5315Y717717D02*
G03I-6496J0D01*
G01X5906Y727559D02*
G03X1969Y731496I-3937J0D01*
G01X24016Y15827D02*
G03I-8268J0D01*
G01X3937Y0D02*
X372048D01*
G01X22008Y44095D02*
G03I-4291J0D01*
G01X22244Y67008D02*
G03I-6496J0D01*
G01X192914Y91339D02*
X3937D01*
G01X18071Y120866D02*
G03I-4291J0D01*
G01X7500Y144213D02*
G03X9469Y142244I1969J0D01*
G01X7500Y161929D02*
Y144213D01*
G01X26319Y159961D02*
Y146181D01*
G01X9469Y142244D02*
X25217D01*
G01X26319Y146181D02*
X104744D01*
G01X28563Y145591D02*
X25217Y142244D01*
G01X19154Y156811D02*
G03X17973Y155630I0J-1181D01*
G01Y150512D02*
G03X19154Y149331I1181J0D01*
G01X9469Y163898D02*
G03X7500Y161929I0J-1969D01*
G01X17973Y150512D02*
Y155630D01*
G01X22658Y151890D02*
Y154252D01*
G01X24351Y151890D02*
Y154252D01*
G01X25217Y163898D02*
X28563Y160551D01*
G01X26319Y150586D02*
X24351Y151890D01*
G01X18429Y156562D02*
X22658Y154252D01*
G01X27697Y149331D02*
X19154D01*
G01X24351Y151890D02*
X22658D01*
G01Y154252D02*
X24351D01*
G01X27697Y156811D02*
X19154D01*
G01X168800Y159961D02*
X26319D01*
G01X25217Y163898D02*
X9469D01*
G01X24351Y154252D02*
X26319Y155556D01*
G01X22658Y151890D02*
X18429Y149580D01*
G01X17973Y216260D02*
G03X19154Y215079I1181J0D01*
G01X7500Y209961D02*
G03X9469Y207992I1969J0D01*
G01X7500Y227677D02*
Y209961D01*
G01X17973Y216260D02*
Y221378D01*
G01X26319Y225709D02*
Y211929D01*
G01Y216334D02*
X24351Y217638D01*
G01X28563Y211339D02*
X25217Y207992D01*
G01X22658Y217638D02*
X18429Y215328D01*
G01X9469Y207992D02*
X25217D01*
G01X26319Y211929D02*
X104744D01*
G01X27697Y215079D02*
X19154D01*
G01Y222559D02*
G03X17973Y221378I0J-1181D01*
G01X9469Y229646D02*
G03X7500Y227677I0J-1969D01*
G01X22658Y217638D02*
Y220000D01*
G01X24351Y217638D02*
Y220000D01*
G01X25217Y229646D02*
X28563Y226299D01*
G01X18429Y222310D02*
X22658Y220000D01*
G01X24351D02*
X26319Y221304D01*
G01X24351Y217638D02*
X22658D01*
G01Y220000D02*
X24351D01*
G01X27697Y222559D02*
X19154D01*
G01X168800Y225709D02*
X26319D01*
G01X25217Y229646D02*
X9469D01*
G01X5906Y290748D02*
G03X9843Y286811I3937J0D01*
G01X5906Y357874D02*
Y290748D01*
G01X69488Y286811D02*
X9843D01*
G01X13780Y315650D02*
Y294685D01*
G01X69488D02*
X13780D01*
G01Y315650D02*
G03X5906I-3937J0D01*
G01Y340847D02*
G03X13780I3937J0D01*
G01Y361811D02*
Y340847D01*
G01X43307Y361811D02*
X13780D01*
G01X3937Y369685D02*
X372048D01*
G01X24016Y385512D02*
G03I-8268J0D01*
G01X22008Y413780D02*
G03I-4291J0D01*
G01X22244Y436693D02*
G03I-6496J0D01*
G01X192914Y461024D02*
X3937D01*
G01X18071Y490551D02*
G03I-4291J0D01*
G01X5906Y660433D02*
G03X9843Y656496I3937J0D01*
G01X5906Y727559D02*
Y660433D01*
G01X69488Y656496D02*
X9843D01*
G01X13780Y685335D02*
Y664370D01*
G01X69488D02*
X13780D01*
G01Y685335D02*
G03X5906I-3937J0D01*
G01X33752Y718854D02*
G03I-4291J0D01*
G01X5906Y710532D02*
G03X13780I3937J0D01*
G01Y729528D02*
Y710532D01*
G01X24847Y701602D02*
G03I-4000J0D01*
G01X22847D02*
G03I-2000J0D01*
G01X23190Y704844D02*
X38405Y720059D01*
G01X30260Y708379D02*
X23190Y704844D01*
G01D02*
X26725Y711914D01*
G01X44819Y731496D02*
X15748D01*
G01D02*
G03X13780Y729528I0J-1968D01*
G01X27697Y149331D02*
Y146181D01*
G01X30059Y147362D02*
Y155236D01*
G01X31240Y148543D02*
Y154055D01*
G01X104903Y145591D02*
X28563D01*
G01X165059Y147362D02*
X30059D01*
G01D02*
X31240Y148543D01*
G01X163878D02*
X31240D01*
G01X35860Y153367D02*
X35886Y153437D01*
G01X35788Y153316D02*
X35860Y153367D01*
G01X35689Y153297D02*
X35788Y153316D01*
G01X40860Y153367D02*
X40886Y153437D01*
G01X40788Y153316D02*
X40860Y153367D01*
G01X40689Y153297D02*
X40788Y153316D01*
G01X45860Y153367D02*
X45886Y153437D01*
G01X45788Y153316D02*
X45860Y153367D01*
G01X45689Y153297D02*
X45788Y153316D01*
G01X49259Y153367D02*
X49331Y153316D01*
G01X49233Y153437D02*
X49259Y153367D01*
G01X44331Y153316D02*
X44429Y153297D01*
G01X44259Y153367D02*
X44331Y153316D01*
G01X44233Y153437D02*
X44259Y153367D01*
G01X39331Y153316D02*
X39429Y153297D01*
G01X39259Y153367D02*
X39331Y153316D01*
G01X39233Y153437D02*
X39259Y153367D01*
G01X34331Y153316D02*
X34429Y153297D01*
G01X34259Y153367D02*
X34331Y153316D01*
G01X34233Y153437D02*
X34259Y153367D01*
G01X34233Y152868D02*
G03X34429Y152671I197J0D01*
G01X35689D02*
G03X35886Y152868I0J197D01*
G01X39233D02*
G03X39429Y152671I197J0D01*
G01X40689D02*
G03X40886Y152868I0J197D01*
G01X44233D02*
G03X44429Y152671I197J0D01*
G01X45689D02*
G03X45886Y152868I0J197D01*
G01X31240Y154055D02*
X30059Y155236D01*
G01X27697Y159961D02*
Y156811D01*
G01X34233Y154055D02*
Y152869D01*
G01X34429Y154055D02*
Y152671D01*
G01X35689Y154055D02*
Y152671D01*
G01X35886Y152869D02*
Y154055D01*
G01X39233D02*
Y152869D01*
G01X39429Y154055D02*
Y152671D01*
G01X40689Y154055D02*
Y152671D01*
G01X40886Y152869D02*
Y154055D01*
G01X44233D02*
Y152869D01*
G01X44429Y154055D02*
Y152671D01*
G01X45689Y154055D02*
Y152671D01*
G01X45886Y152869D02*
Y154055D01*
G01X44429Y152671D02*
X45689D01*
G01X39429D02*
X40689D01*
G01X34429D02*
X35689D01*
G01X44429Y153297D02*
X45689D01*
G01X39429D02*
X40689D01*
G01X34429D02*
X35689D01*
G01X31240Y154055D02*
X107697D01*
G01X30059Y155236D02*
X106516D01*
G01X28563Y160551D02*
X166555D01*
G01X27697Y215079D02*
Y211929D01*
G01X30059Y213110D02*
Y220984D01*
G01X31240Y214291D02*
Y219803D01*
G01X30059Y213110D02*
X31240Y214291D01*
G01X104903Y211339D02*
X28563D01*
G01X165059Y213110D02*
X30059D01*
G01X163878Y214291D02*
X31240D01*
G01X35860Y219115D02*
X35886Y219185D01*
G01X35788Y219064D02*
X35860Y219115D01*
G01X35689Y219045D02*
X35788Y219064D01*
G01X40860Y219115D02*
X40886Y219185D01*
G01X40788Y219064D02*
X40860Y219115D01*
G01X40689Y219045D02*
X40788Y219064D01*
G01X45860Y219115D02*
X45886Y219185D01*
G01X45788Y219064D02*
X45860Y219115D01*
G01X45689Y219045D02*
X45788Y219064D01*
G01X49259Y219115D02*
X49331Y219064D01*
G01X49233Y219185D02*
X49259Y219115D01*
G01X44331Y219064D02*
X44429Y219045D01*
G01X44259Y219115D02*
X44331Y219064D01*
G01X44233Y219185D02*
X44259Y219115D01*
G01X39331Y219064D02*
X39429Y219045D01*
G01X39259Y219115D02*
X39331Y219064D01*
G01X39233Y219185D02*
X39259Y219115D01*
G01X34331Y219064D02*
X34429Y219045D01*
G01X34259Y219115D02*
X34331Y219064D01*
G01X34233Y219185D02*
X34259Y219115D01*
G01X44233Y218616D02*
G03X44429Y218419I197J0D01*
G01X45689D02*
G03X45886Y218616I0J197D01*
G01X34233D02*
G03X34429Y218419I197J0D01*
G01X35689D02*
G03X35886Y218616I0J197D01*
G01X39233D02*
G03X39429Y218419I197J0D01*
G01X40689D02*
G03X40886Y218616I0J197D01*
G01X27697Y225709D02*
Y222559D01*
G01X34233Y219803D02*
Y218617D01*
G01X34429Y219803D02*
Y218419D01*
G01X35689Y219803D02*
Y218419D01*
G01X35886Y218617D02*
Y219803D01*
G01X39233D02*
Y218617D01*
G01X39429Y219803D02*
Y218419D01*
G01X40689Y219803D02*
Y218419D01*
G01X40886Y218617D02*
Y219803D01*
G01X44233D02*
Y218617D01*
G01X44429Y219803D02*
Y218419D01*
G01X45689Y219803D02*
Y218419D01*
G01X45886Y218617D02*
Y219803D01*
G01X31240D02*
X30059Y220984D01*
G01X44429Y218419D02*
X45689D01*
G01X39429D02*
X40689D01*
G01X34429D02*
X35689D01*
G01X44429Y219045D02*
X45689D01*
G01X39429D02*
X40689D01*
G01X34429D02*
X35689D01*
G01X31240Y219803D02*
X107697D01*
G01X30059Y220984D02*
X106516D01*
G01X28563Y226299D02*
X166555D01*
G01X43307Y361811D02*
G03Y369685I0J3937D01*
G01X26725Y711914D02*
X30260Y708379D01*
G01X46675Y730184D02*
G03X44819Y731496I-1856J-657D01*
G01X46675Y730184D02*
G03X54098I3712J1313D01*
G01X38405Y720059D02*
X74605D01*
G01X71181Y12480D02*
G03X72363Y11299I1181J0D01*
G01X60709Y6181D02*
G03X62677Y4213I1968J0D01*
G01X75866Y13858D02*
X71637Y11548D01*
G01X62677Y4213D02*
X78426D01*
G01X71181Y12480D02*
Y17599D01*
G01X60709Y23898D02*
Y6181D01*
G01X72363Y18780D02*
G03X71181Y17599I-1J-1181D01*
G01X62677Y25866D02*
G03X60709Y23898I0J-1968D01*
G01X78426Y25866D02*
X62677D01*
G01X71637Y18530D02*
X75866Y16221D01*
G01X71181Y56969D02*
G03X72363Y55787I1181J-1D01*
G01X60709Y50669D02*
G03X62677Y48701I1968J0D01*
G01X75866Y58347D02*
X71637Y56036D01*
G01X62677Y48701D02*
X78426D01*
G01X71181Y56969D02*
Y62087D01*
G01X60709Y68386D02*
Y50669D01*
G01X72363Y63268D02*
G03X71181Y62087I-1J-1181D01*
G01X62677Y70354D02*
G03X60709Y68386I0J-1968D01*
G01X78426Y70354D02*
X62677D01*
G01X71637Y63019D02*
X75866Y60709D01*
G01X50860Y153367D02*
X50886Y153437D01*
G01X50788Y153316D02*
X50860Y153367D01*
G01X50689Y153297D02*
X50788Y153316D01*
G01X55860Y153367D02*
X55886Y153437D01*
G01X55788Y153316D02*
X55860Y153367D01*
G01X55689Y153297D02*
X55788Y153316D01*
G01X60860Y153367D02*
X60886Y153437D01*
G01X60788Y153316D02*
X60860Y153367D01*
G01X60689Y153297D02*
X60788Y153316D01*
G01X65860Y153367D02*
X65886Y153437D01*
G01X65788Y153316D02*
X65860Y153367D01*
G01X65689Y153297D02*
X65788Y153316D01*
G01X70860Y153367D02*
X70886Y153437D01*
G01X70788Y153316D02*
X70860Y153367D01*
G01X70689Y153297D02*
X70788Y153316D01*
G01X69331D02*
X69429Y153297D01*
G01X69259Y153367D02*
X69331Y153316D01*
G01X69233Y153437D02*
X69259Y153367D01*
G01X64331Y153316D02*
X64429Y153297D01*
G01X64259Y153367D02*
X64331Y153316D01*
G01X64233Y153437D02*
X64259Y153367D01*
G01X59331Y153316D02*
X59429Y153297D01*
G01X59259Y153367D02*
X59331Y153316D01*
G01X59233Y153437D02*
X59259Y153367D01*
G01X54331Y153316D02*
X54429Y153297D01*
G01X54259Y153367D02*
X54331Y153316D01*
G01X54233Y153437D02*
X54259Y153367D01*
G01X49331Y153316D02*
X49429Y153297D01*
G01X49233Y152868D02*
G03X49429Y152671I197J0D01*
G01X50689D02*
G03X50886Y152868I0J197D01*
G01X69233D02*
G03X69429Y152671I197J0D01*
G01X70689D02*
G03X70886Y152868I0J197D01*
G01X64233D02*
G03X64429Y152671I197J0D01*
G01X65689D02*
G03X65886Y152868I0J197D01*
G01X59233D02*
G03X59429Y152671I197J0D01*
G01X60689D02*
G03X60886Y152868I0J197D01*
G01X54233D02*
G03X54429Y152671I197J0D01*
G01X55689D02*
G03X55886Y152868I0J197D01*
G01X49233Y154055D02*
Y152869D01*
G01X49429Y154055D02*
Y152671D01*
G01X50689Y154055D02*
Y152671D01*
G01X50886Y152869D02*
Y154055D01*
G01X54233D02*
Y152869D01*
G01X54429Y154055D02*
Y152671D01*
G01X55689Y154055D02*
Y152671D01*
G01X55886Y152869D02*
Y154055D01*
G01X59233D02*
Y152869D01*
G01X59429Y154055D02*
Y152671D01*
G01X60689Y154055D02*
Y152671D01*
G01X60886Y152869D02*
Y154055D01*
G01X64233D02*
Y152869D01*
G01X64429Y154055D02*
Y152671D01*
G01X65689Y154055D02*
Y152671D01*
G01X65886Y152869D02*
Y154055D01*
G01X69233D02*
Y152869D01*
G01X69429Y154055D02*
Y152671D01*
G01X70689Y154055D02*
Y152671D01*
G01X70886Y152869D02*
Y154055D01*
G01X69429Y152671D02*
X70689D01*
G01X64429D02*
X65689D01*
G01X59429D02*
X60689D01*
G01X54429D02*
X55689D01*
G01X49429D02*
X50689D01*
G01X69429Y153297D02*
X70689D01*
G01X64429D02*
X65689D01*
G01X59429D02*
X60689D01*
G01X54429D02*
X55689D01*
G01X49429D02*
X50689D01*
G01X53150Y181697D02*
G03X55118Y179729I1968J0D01*
G01X53150Y195477D02*
Y181697D01*
G01X55118Y179729D02*
X161418D01*
G01X55118Y197445D02*
G03X53150Y195477I0J-1968D01*
G01X161418Y197445D02*
X55118D01*
G01X50860Y219115D02*
X50886Y219185D01*
G01X50788Y219064D02*
X50860Y219115D01*
G01X50689Y219045D02*
X50788Y219064D01*
G01X55860Y219115D02*
X55886Y219185D01*
G01X55788Y219064D02*
X55860Y219115D01*
G01X55689Y219045D02*
X55788Y219064D01*
G01X60860Y219115D02*
X60886Y219185D01*
G01X60788Y219064D02*
X60860Y219115D01*
G01X60689Y219045D02*
X60788Y219064D01*
G01X65860Y219115D02*
X65886Y219185D01*
G01X65788Y219064D02*
X65860Y219115D01*
G01X65689Y219045D02*
X65788Y219064D01*
G01X70860Y219115D02*
X70886Y219185D01*
G01X70788Y219064D02*
X70860Y219115D01*
G01X70689Y219045D02*
X70788Y219064D01*
G01X69331D02*
X69429Y219045D01*
G01X69259Y219115D02*
X69331Y219064D01*
G01X69233Y219185D02*
X69259Y219115D01*
G01X64331Y219064D02*
X64429Y219045D01*
G01X64259Y219115D02*
X64331Y219064D01*
G01X64233Y219185D02*
X64259Y219115D01*
G01X59331Y219064D02*
X59429Y219045D01*
G01X59259Y219115D02*
X59331Y219064D01*
G01X59233Y219185D02*
X59259Y219115D01*
G01X54331Y219064D02*
X54429Y219045D01*
G01X54259Y219115D02*
X54331Y219064D01*
G01X54233Y219185D02*
X54259Y219115D01*
G01X49331Y219064D02*
X49429Y219045D01*
G01X49233Y218616D02*
G03X49429Y218419I197J0D01*
G01X50689D02*
G03X50886Y218616I0J197D01*
G01X69233D02*
G03X69429Y218419I197J0D01*
G01X70689D02*
G03X70886Y218616I0J197D01*
G01X64233D02*
G03X64429Y218419I197J0D01*
G01X65689D02*
G03X65886Y218616I0J197D01*
G01X59233D02*
G03X59429Y218419I197J0D01*
G01X60689D02*
G03X60886Y218616I0J197D01*
G01X54233D02*
G03X54429Y218419I197J0D01*
G01X55689D02*
G03X55886Y218616I0J197D01*
G01X49233Y219803D02*
Y218617D01*
G01X49429Y219803D02*
Y218419D01*
G01X50689Y219803D02*
Y218419D01*
G01X50886Y218617D02*
Y219803D01*
G01X54233D02*
Y218617D01*
G01X54429Y219803D02*
Y218419D01*
G01X55689Y219803D02*
Y218419D01*
G01X55886Y218617D02*
Y219803D01*
G01X59233D02*
Y218617D01*
G01X59429Y219803D02*
Y218419D01*
G01X60689Y219803D02*
Y218419D01*
G01X60886Y218617D02*
Y219803D01*
G01X64233D02*
Y218617D01*
G01X64429Y219803D02*
Y218419D01*
G01X65689Y219803D02*
Y218419D01*
G01X65886Y218617D02*
Y219803D01*
G01X69233D02*
Y218617D01*
G01X69429Y219803D02*
Y218419D01*
G01X70689Y219803D02*
Y218419D01*
G01X70886Y218617D02*
Y219803D01*
G01X69429Y218419D02*
X70689D01*
G01X64429D02*
X65689D01*
G01X59429D02*
X60689D01*
G01X54429D02*
X55689D01*
G01X49429D02*
X50689D01*
G01X69429Y219045D02*
X70689D01*
G01X64429D02*
X65689D01*
G01X59429D02*
X60689D01*
G01X54429D02*
X55689D01*
G01X49429D02*
X50689D01*
G01X73426Y282874D02*
G03X69488Y286811I-3937J0D01*
G01X81300Y282874D02*
G03X69488Y294685I-11811J0D01*
G01X74016Y369685D02*
G03Y361811I0J-3937D01*
G01X53150Y551382D02*
G03X55118Y549414I1968J0D01*
G01X53150Y565162D02*
Y551382D01*
G01X55118Y549414D02*
X161418D01*
G01X55118Y567130D02*
G03X53150Y565162I0J-1968D01*
G01X161418Y567130D02*
X55118D01*
G01X73426Y652559D02*
G03X69488Y656496I-3937J0D01*
G01X81300Y652559D02*
G03X69488Y664370I-11811J0D01*
G01X55954Y731496D02*
G03X54098Y730184I0J-1969D01*
G01X50879Y731496D02*
X50387D01*
G01D02*
Y731102D01*
G01Y731496D02*
Y731890D01*
G01X49894Y731496D02*
X50879D01*
G01X153544D02*
X55954D01*
G01X84330Y-390518D02*
Y-407840D01*
G01X81772Y7559D02*
X78426Y4213D01*
G01X84449Y14055D02*
X83268Y12874D01*
G01X119725D02*
X83268D01*
G01X72363Y11299D02*
X80906D01*
G01X79528Y8150D02*
X222008D01*
G01X219764Y7559D02*
X81772D01*
G01X83268Y12874D02*
Y20748D01*
G01X80906Y11299D02*
Y8150D01*
G01X79528D02*
Y21929D01*
G01Y12554D02*
X77559Y13858D01*
G01X88996Y14794D02*
X88898Y14813D01*
G01X89068Y14743D02*
X88996Y14794D01*
G01X89095Y14673D02*
X89068Y14743D01*
G01X93996Y14794D02*
X93898Y14813D01*
G01X94068Y14743D02*
X93996Y14794D01*
G01X94095Y14673D02*
X94068Y14743D01*
G01X92468D02*
X92441Y14673D01*
G01X92540Y14794D02*
X92468Y14743D01*
G01X92638Y14813D02*
X92540Y14794D01*
G01X87468Y14743D02*
X87441Y14673D01*
G01X87540Y14794D02*
X87468Y14743D01*
G01X87638Y14813D02*
X87540Y14794D01*
G01X89095Y15242D02*
G03X88898Y15439I-197J0D01*
G01X87638D02*
G03X87441Y15242I0J-197D01*
G01X94095D02*
G03X93898Y15439I-197J0D01*
G01X92638D02*
G03X92441Y15242I0J-197D01*
G01X77559Y16221D02*
X79528Y17524D01*
G01X81772Y22520D02*
X118111D01*
G01X79528Y21929D02*
X117953D01*
G01X83268Y20748D02*
X218268D01*
G01X84449Y19567D02*
X217087D01*
G01X72363Y18780D02*
X80906D01*
G01X75866Y16221D02*
X77559D01*
G01X88898Y15439D02*
X87638D01*
G01X93898D02*
X92638D01*
G01X88898Y14813D02*
X87638D01*
G01X93898D02*
X92638D01*
G01X120906Y14055D02*
X84449D01*
G01X77559Y13858D02*
X75866D01*
G01X94095Y14055D02*
Y15241D01*
G01X93898Y14055D02*
Y15439D01*
G01X92638Y14055D02*
Y15439D01*
G01X92441Y15241D02*
Y14055D01*
G01X89095D02*
Y15241D01*
G01X88898Y14055D02*
Y15439D01*
G01X87638Y14055D02*
Y15439D01*
G01X87441Y15241D02*
Y14055D01*
G01X84449D02*
Y19567D01*
G01X80906Y21929D02*
Y18780D01*
G01X78426Y25866D02*
X81772Y22520D01*
G01X84449Y19567D02*
X83268Y20748D01*
G01X77559Y13858D02*
Y16221D01*
G01X75866Y13858D02*
Y16221D01*
G01X80709Y43307D02*
G03X82677Y41339I1968J0D01*
G01Y47244D02*
G03X80709Y45276I0J-1968D01*
G01X119725Y57362D02*
X83268D01*
G01X72363Y55787D02*
X80906D01*
G01X79528Y52638D02*
X222008D01*
G01X219764Y52047D02*
X81772D01*
G01X188977Y47244D02*
X82677D01*
G01Y41339D02*
X188977D01*
G01X81772Y52047D02*
X78426Y48701D01*
G01X84449Y58543D02*
X83268Y57362D01*
G01X79528Y57043D02*
X77559Y58347D01*
G01X83268Y57362D02*
Y65236D01*
G01X80906Y55787D02*
Y52638D01*
G01X80709Y45276D02*
Y43307D01*
G01X79528Y52638D02*
Y66417D01*
G01X88996Y59282D02*
X88898Y59301D01*
G01X89068Y59231D02*
X88996Y59282D01*
G01X89095Y59161D02*
X89068Y59231D01*
G01X93996Y59282D02*
X93898Y59301D01*
G01X94068Y59231D02*
X93996Y59282D01*
G01X94095Y59161D02*
X94068Y59231D01*
G01X92468D02*
X92441Y59161D01*
G01X92540Y59282D02*
X92468Y59231D01*
G01X92638Y59301D02*
X92540Y59282D01*
G01X87468Y59231D02*
X87441Y59161D01*
G01X87540Y59282D02*
X87468Y59231D01*
G01X87638Y59301D02*
X87540Y59282D01*
G01X89095Y59730D02*
G03X88898Y59927I-197J0D01*
G01X87638D02*
G03X87441Y59730I0J-197D01*
G01X94095D02*
G03X93898Y59927I-197J0D01*
G01X92638D02*
G03X92441Y59730I0J-197D01*
G01X77559Y60709D02*
X79528Y62012D01*
G01X81772Y67008D02*
X118111D01*
G01X79528Y66417D02*
X117953D01*
G01X83268Y65236D02*
X218268D01*
G01X84449Y64055D02*
X217087D01*
G01X72363Y63268D02*
X80906D01*
G01X75866Y60709D02*
X77559D01*
G01X88898Y59927D02*
X87638D01*
G01X93898D02*
X92638D01*
G01X88898Y59301D02*
X87638D01*
G01X93898D02*
X92638D01*
G01X120906Y58543D02*
X84449D01*
G01X77559Y58347D02*
X75866D01*
G01X78426Y70354D02*
X81772Y67008D01*
G01X84449Y64055D02*
X83268Y65236D01*
G01X94095Y58543D02*
Y59730D01*
G01X93898Y58543D02*
Y59927D01*
G01X92638Y58543D02*
Y59927D01*
G01X92441Y59730D02*
Y58543D01*
G01X89095D02*
Y59730D01*
G01X88898Y58543D02*
Y59927D01*
G01X87638Y58543D02*
Y59927D01*
G01X87441Y59730D02*
Y58543D01*
G01X84449D02*
Y64055D01*
G01X80906Y66417D02*
Y63268D01*
G01X77559Y58347D02*
Y60709D01*
G01X75866Y58347D02*
Y60709D01*
G01X86614Y101181D02*
G03X82677Y105118I-3937J0D01*
G01X86614Y95276D02*
Y101181D01*
G01X82677Y91339D02*
G03X86614Y95276I0J3937D01*
G01X75860Y153367D02*
X75886Y153437D01*
G01X75788Y153316D02*
X75860Y153367D01*
G01X75689Y153297D02*
X75788Y153316D01*
G01X80860Y153367D02*
X80886Y153437D01*
G01X80788Y153316D02*
X80860Y153367D01*
G01X80689Y153297D02*
X80788Y153316D01*
G01X85860Y153367D02*
X85886Y153437D01*
G01X85788Y153316D02*
X85860Y153367D01*
G01X85689Y153297D02*
X85788Y153316D01*
G01X90860Y153367D02*
X90886Y153437D01*
G01X90788Y153316D02*
X90860Y153367D01*
G01X90689Y153297D02*
X90788Y153316D01*
G01X94331D02*
X94429Y153297D01*
G01X94259Y153367D02*
X94331Y153316D01*
G01X94233Y153437D02*
X94259Y153367D01*
G01X89331Y153316D02*
X89429Y153297D01*
G01X89259Y153367D02*
X89331Y153316D01*
G01X89233Y153437D02*
X89259Y153367D01*
G01X84331Y153316D02*
X84429Y153297D01*
G01X84259Y153367D02*
X84331Y153316D01*
G01X84233Y153437D02*
X84259Y153367D01*
G01X79331Y153316D02*
X79429Y153297D01*
G01X79259Y153367D02*
X79331Y153316D01*
G01X79233Y153437D02*
X79259Y153367D01*
G01X74331Y153316D02*
X74429Y153297D01*
G01X74259Y153367D02*
X74331Y153316D01*
G01X74233Y153437D02*
X74259Y153367D01*
G01X89233Y152868D02*
G03X89429Y152671I197J0D01*
G01X90689D02*
G03X90886Y152868I0J197D01*
G01X94233D02*
G03X94429Y152671I197J0D01*
G01X84233Y152868D02*
G03X84429Y152671I197J0D01*
G01X85689D02*
G03X85886Y152868I0J197D01*
G01X79233D02*
G03X79429Y152671I197J0D01*
G01X80689D02*
G03X80886Y152868I0J197D01*
G01X74233D02*
G03X74429Y152671I197J0D01*
G01X75689D02*
G03X75886Y152868I0J197D01*
G01X74233Y154055D02*
Y152869D01*
G01X74429Y154055D02*
Y152671D01*
G01X75689Y154055D02*
Y152671D01*
G01X75886Y152869D02*
Y154055D01*
G01X79233D02*
Y152869D01*
G01X79429Y154055D02*
Y152671D01*
G01X80689Y154055D02*
Y152671D01*
G01X80886Y152869D02*
Y154055D01*
G01X84233D02*
Y152869D01*
G01X84429Y154055D02*
Y152671D01*
G01X85689Y154055D02*
Y152671D01*
G01X85886Y152869D02*
Y154055D01*
G01X89233D02*
Y152869D01*
G01X89429Y154055D02*
Y152671D01*
G01X90689Y154055D02*
Y152671D01*
G01X90886Y152869D02*
Y154055D01*
G01X94233D02*
Y152869D01*
G01X94429Y154055D02*
Y152671D01*
G01D02*
X95689D01*
G01X89429D02*
X90689D01*
G01X84429D02*
X85689D01*
G01X79429D02*
X80689D01*
G01X74429D02*
X75689D01*
G01X94429Y153297D02*
X95689D01*
G01X89429D02*
X90689D01*
G01X84429D02*
X85689D01*
G01X79429D02*
X80689D01*
G01X74429D02*
X75689D01*
G01X75860Y219115D02*
X75886Y219185D01*
G01X75788Y219064D02*
X75860Y219115D01*
G01X75689Y219045D02*
X75788Y219064D01*
G01X80860Y219115D02*
X80886Y219185D01*
G01X80788Y219064D02*
X80860Y219115D01*
G01X80689Y219045D02*
X80788Y219064D01*
G01X85860Y219115D02*
X85886Y219185D01*
G01X85788Y219064D02*
X85860Y219115D01*
G01X85689Y219045D02*
X85788Y219064D01*
G01X90860Y219115D02*
X90886Y219185D01*
G01X90788Y219064D02*
X90860Y219115D01*
G01X90689Y219045D02*
X90788Y219064D01*
G01X94331D02*
X94429Y219045D01*
G01X94259Y219115D02*
X94331Y219064D01*
G01X94233Y219185D02*
X94259Y219115D01*
G01X89331Y219064D02*
X89429Y219045D01*
G01X89259Y219115D02*
X89331Y219064D01*
G01X89233Y219185D02*
X89259Y219115D01*
G01X84331Y219064D02*
X84429Y219045D01*
G01X84259Y219115D02*
X84331Y219064D01*
G01X84233Y219185D02*
X84259Y219115D01*
G01X79331Y219064D02*
X79429Y219045D01*
G01X79259Y219115D02*
X79331Y219064D01*
G01X79233Y219185D02*
X79259Y219115D01*
G01X74331Y219064D02*
X74429Y219045D01*
G01X74259Y219115D02*
X74331Y219064D01*
G01X74233Y219185D02*
X74259Y219115D01*
G01X89233Y218616D02*
G03X89429Y218419I197J0D01*
G01X90689D02*
G03X90886Y218616I0J197D01*
G01X94233D02*
G03X94429Y218419I197J0D01*
G01X84233Y218616D02*
G03X84429Y218419I197J0D01*
G01X85689D02*
G03X85886Y218616I0J197D01*
G01X79233D02*
G03X79429Y218419I197J0D01*
G01X80689D02*
G03X80886Y218616I0J197D01*
G01X74233D02*
G03X74429Y218419I197J0D01*
G01X75689D02*
G03X75886Y218616I0J197D01*
G01X74233Y219803D02*
Y218617D01*
G01X74429Y219803D02*
Y218419D01*
G01X75689Y219803D02*
Y218419D01*
G01X75886Y218617D02*
Y219803D01*
G01X79233D02*
Y218617D01*
G01X79429Y219803D02*
Y218419D01*
G01X80689Y219803D02*
Y218419D01*
G01X80886Y218617D02*
Y219803D01*
G01X84233D02*
Y218617D01*
G01X84429Y219803D02*
Y218419D01*
G01X85689Y219803D02*
Y218419D01*
G01X85886Y218617D02*
Y219803D01*
G01X89233D02*
Y218617D01*
G01X89429Y219803D02*
Y218419D01*
G01X90689Y219803D02*
Y218419D01*
G01X90886Y218617D02*
Y219803D01*
G01X94233D02*
Y218617D01*
G01X94429Y219803D02*
Y218419D01*
G01D02*
X95689D01*
G01X89429D02*
X90689D01*
G01X84429D02*
X85689D01*
G01X79429D02*
X80689D01*
G01X74429D02*
X75689D01*
G01X94429Y219045D02*
X95689D01*
G01X89429D02*
X90689D01*
G01X84429D02*
X85689D01*
G01X79429D02*
X80689D01*
G01X74429D02*
X75689D01*
G01X73426Y267323D02*
G03X77363Y263386I3937J0D01*
G01X73426Y267323D02*
Y282874D01*
G01X77363Y263386D02*
X159449D01*
G01X81300Y271260D02*
Y282874D01*
G01Y271260D02*
X155512D01*
G01Y361811D02*
X74016D01*
G01X80709Y412992D02*
G03X82677Y411024I1968J0D01*
G01Y416929D02*
G03X80709Y414961I0J-1968D01*
G01X188977Y416929D02*
X82677D01*
G01Y411024D02*
X188977D01*
G01X80709Y414961D02*
Y412992D01*
G01X86614Y464961D02*
Y470866D01*
G01X82677Y461024D02*
G03X86614Y464961I0J3937D01*
G01Y470866D02*
G03X82677Y474803I-3937J0D01*
G01X73426Y637008D02*
G03X77363Y633071I3937J0D01*
G01X73426Y637008D02*
Y652559D01*
G01X77363Y633071D02*
X159449D01*
G01X81300Y640945D02*
Y652559D01*
G01Y640945D02*
X155512D01*
G01X81882Y730096D02*
Y732896D01*
G01X84330Y970112D02*
Y952789D01*
G01X98996Y14794D02*
X98898Y14813D01*
G01X99068Y14743D02*
X98996Y14794D01*
G01X99095Y14673D02*
X99068Y14743D01*
G01X103996Y14794D02*
X103898Y14813D01*
G01X104068Y14743D02*
X103996Y14794D01*
G01X104095Y14673D02*
X104068Y14743D01*
G01X108996Y14794D02*
X108898Y14813D01*
G01X109068Y14743D02*
X108996Y14794D01*
G01X109095Y14673D02*
X109068Y14743D01*
G01X113996Y14794D02*
X113898Y14813D01*
G01X114068Y14743D02*
X113996Y14794D01*
G01X114095Y14673D02*
X114068Y14743D01*
G01X112468D02*
X112441Y14673D01*
G01X112540Y14794D02*
X112468Y14743D01*
G01X112638Y14813D02*
X112540Y14794D01*
G01X107468Y14743D02*
X107441Y14673D01*
G01X107540Y14794D02*
X107468Y14743D01*
G01X107638Y14813D02*
X107540Y14794D01*
G01X102468Y14743D02*
X102441Y14673D01*
G01X102540Y14794D02*
X102468Y14743D01*
G01X102638Y14813D02*
X102540Y14794D01*
G01X97468Y14743D02*
X97441Y14673D01*
G01X97540Y14794D02*
X97468Y14743D01*
G01X97638Y14813D02*
X97540Y14794D01*
G01X99095Y15242D02*
G03X98898Y15439I-197J0D01*
G01X97638D02*
G03X97441Y15242I0J-197D01*
G01X104095D02*
G03X103898Y15439I-197J0D01*
G01X102638D02*
G03X102441Y15242I0J-197D01*
G01X109095D02*
G03X108898Y15439I-197J0D01*
G01X107638D02*
G03X107441Y15242I0J-197D01*
G01X114095D02*
G03X113898Y15439I-197J0D01*
G01X112638D02*
G03X112441Y15242I0J-197D01*
G01X98898Y15439D02*
X97638D01*
G01X103898D02*
X102638D01*
G01X108898D02*
X107638D01*
G01X113898D02*
X112638D01*
G01X98898Y14813D02*
X97638D01*
G01X103898D02*
X102638D01*
G01X108898D02*
X107638D01*
G01X113898D02*
X112638D01*
G01X114095Y14055D02*
Y15241D01*
G01X113898Y14055D02*
Y15439D01*
G01X112638Y14055D02*
Y15439D01*
G01X112441Y15241D02*
Y14055D01*
G01X109095D02*
Y15241D01*
G01X108898Y14055D02*
Y15439D01*
G01X107638Y14055D02*
Y15439D01*
G01X107441Y15241D02*
Y14055D01*
G01X104095D02*
Y15241D01*
G01X103898Y14055D02*
Y15439D01*
G01X102638Y14055D02*
Y15439D01*
G01X102441Y15241D02*
Y14055D01*
G01X99095D02*
Y15241D01*
G01X98898Y14055D02*
Y15439D01*
G01X97638Y14055D02*
Y15439D01*
G01X97441Y15241D02*
Y14055D01*
G01X98996Y59282D02*
X98898Y59301D01*
G01X99068Y59231D02*
X98996Y59282D01*
G01X99095Y59161D02*
X99068Y59231D01*
G01X103996Y59282D02*
X103898Y59301D01*
G01X104068Y59231D02*
X103996Y59282D01*
G01X104095Y59161D02*
X104068Y59231D01*
G01X108996Y59282D02*
X108898Y59301D01*
G01X109068Y59231D02*
X108996Y59282D01*
G01X109095Y59161D02*
X109068Y59231D01*
G01X113996Y59282D02*
X113898Y59301D01*
G01X114068Y59231D02*
X113996Y59282D01*
G01X114095Y59161D02*
X114068Y59231D01*
G01X112468D02*
X112441Y59161D01*
G01X112540Y59282D02*
X112468Y59231D01*
G01X112638Y59301D02*
X112540Y59282D01*
G01X107468Y59231D02*
X107441Y59161D01*
G01X107540Y59282D02*
X107468Y59231D01*
G01X107638Y59301D02*
X107540Y59282D01*
G01X102468Y59231D02*
X102441Y59161D01*
G01X102540Y59282D02*
X102468Y59231D01*
G01X102638Y59301D02*
X102540Y59282D01*
G01X97468Y59231D02*
X97441Y59161D01*
G01X97540Y59282D02*
X97468Y59231D01*
G01X97638Y59301D02*
X97540Y59282D01*
G01X99095Y59730D02*
G03X98898Y59927I-197J0D01*
G01X97638D02*
G03X97441Y59730I0J-197D01*
G01X104095D02*
G03X103898Y59927I-197J0D01*
G01X102638D02*
G03X102441Y59730I0J-197D01*
G01X109095D02*
G03X108898Y59927I-197J0D01*
G01X107638D02*
G03X107441Y59730I0J-197D01*
G01X114095D02*
G03X113898Y59927I-197J0D01*
G01X112638D02*
G03X112441Y59730I0J-197D01*
G01X98898Y59927D02*
X97638D01*
G01X103898D02*
X102638D01*
G01X108898D02*
X107638D01*
G01X113898D02*
X112638D01*
G01X98898Y59301D02*
X97638D01*
G01X103898D02*
X102638D01*
G01X108898D02*
X107638D01*
G01X113898D02*
X112638D01*
G01X114095Y58543D02*
Y59730D01*
G01X113898Y58543D02*
Y59927D01*
G01X112638Y58543D02*
Y59927D01*
G01X112441Y59730D02*
Y58543D01*
G01X109095D02*
Y59730D01*
G01X108898Y58543D02*
Y59927D01*
G01X107638Y58543D02*
Y59927D01*
G01X107441Y59730D02*
Y58543D01*
G01X104095D02*
Y59730D01*
G01X103898Y58543D02*
Y59927D01*
G01X102638Y58543D02*
Y59927D01*
G01X102441Y59730D02*
Y58543D01*
G01X99095D02*
Y59730D01*
G01X98898Y58543D02*
Y59927D01*
G01X97638Y58543D02*
Y59927D01*
G01X97441Y59730D02*
Y58543D01*
G01X109449Y95276D02*
G03X113386Y91339I3937J0D01*
G01X109449Y95276D02*
Y101181D01*
G01X113386Y105118D02*
G03X109449Y101181I0J-3937D01*
G01X117028Y149108D02*
X117126Y149127D01*
G01X116956Y149058D02*
X117028Y149108D01*
G01X116929Y148989D02*
X116956Y149058D01*
G01X113878Y149108D02*
X113977Y149127D01*
G01X113806Y149058D02*
X113878Y149108D01*
G01X113780Y148989D02*
X113806Y149058D01*
G01X110729Y149108D02*
X110827Y149127D01*
G01X110657Y149058D02*
X110729Y149108D01*
G01X110630Y148989D02*
X110657Y149058D01*
G01X107579Y149108D02*
X107677Y149127D01*
G01X107507Y149058D02*
X107579Y149108D01*
G01X107481Y148989D02*
X107507Y149058D01*
G01X115013D02*
X115040Y148989D01*
G01X114941Y149108D02*
X115013Y149058D01*
G01X114843Y149127D02*
X114941Y149108D01*
G01X111864Y149058D02*
X111890Y148989D01*
G01X111792Y149108D02*
X111864Y149058D01*
G01X111693Y149127D02*
X111792Y149108D01*
G01X108714Y149058D02*
X108740Y148989D01*
G01X108642Y149108D02*
X108714Y149058D01*
G01X108544Y149127D02*
X108642Y149108D01*
G01X104744Y146181D02*
X105800Y142244D01*
G01X107481Y149586D02*
Y148543D01*
G01X107677Y149784D02*
Y148740D01*
G01X108544D02*
Y149784D01*
G01X108740Y148543D02*
Y149586D01*
G01X110630D02*
Y148543D01*
G01X110827Y149784D02*
Y148740D01*
G01X111693D02*
Y149784D01*
G01X111890Y148543D02*
Y149586D01*
G01X113780D02*
Y148543D01*
G01X113977Y149784D02*
Y148740D01*
G01X114843D02*
Y149784D01*
G01X115040Y148543D02*
Y149586D01*
G01X116929D02*
Y148543D01*
G01X117126Y149784D02*
Y148740D01*
G01X105800Y142244D02*
X129320D01*
G01X105430Y143622D02*
X129689D01*
G01X107677Y148740D02*
X107481D01*
G01X108740D02*
X108544D01*
G01X110827D02*
X110630D01*
G01X111890D02*
X111693D01*
G01X113977D02*
X113780D01*
G01X115040D02*
X114843D01*
G01X117126D02*
X116929D01*
G01X95860Y153367D02*
X95886Y153437D01*
G01X95788Y153316D02*
X95860Y153367D01*
G01X95689Y153297D02*
X95788Y153316D01*
G01X100860Y153367D02*
X100886Y153437D01*
G01X100788Y153316D02*
X100860Y153367D01*
G01X100689Y153297D02*
X100788Y153316D01*
G01X105860Y153367D02*
X105886Y153437D01*
G01X105788Y153316D02*
X105860Y153367D01*
G01X105689Y153297D02*
X105788Y153316D01*
G01X104331D02*
X104429Y153297D01*
G01X104259Y153367D02*
X104331Y153316D01*
G01X104233Y153437D02*
X104259Y153367D01*
G01X99331Y153316D02*
X99429Y153297D01*
G01X99259Y153367D02*
X99331Y153316D01*
G01X99233Y153437D02*
X99259Y153367D01*
G01X104233Y152868D02*
G03X104429Y152671I197J0D01*
G01X105689D02*
G03X105886Y152868I0J197D01*
G01X99233D02*
G03X99429Y152671I197J0D01*
G01X100689D02*
G03X100886Y152868I0J197D01*
G01X95689Y152671D02*
G03X95886Y152868I0J197D01*
G01X108740Y149587D02*
G03X108544Y149784I-197J0D01*
G01X107677D02*
G03X107481Y149587I1J-197D01*
G01X111890D02*
G03X111693Y149784I-197J0D01*
G01X110827D02*
G03X110630Y149587I0J-197D01*
G01X115040D02*
G03X114843Y149784I-197J0D01*
G01X113977D02*
G03X113780Y149587I0J-197D01*
G01X117126Y149784D02*
G03X116929Y149587I0J-197D01*
G01X107697Y154055D02*
X106516Y155236D01*
G01X107697Y157992D02*
X106516Y159173D01*
G01X95689Y154055D02*
Y152671D01*
G01X95886Y152869D02*
Y154055D01*
G01X99233D02*
Y152869D01*
G01X99429Y154055D02*
Y152671D01*
G01X100689Y154055D02*
Y152671D01*
G01X100886Y152869D02*
Y154055D01*
G01X104233D02*
Y152869D01*
G01X104429Y154055D02*
Y152671D01*
G01X105689Y154055D02*
Y152671D01*
G01X105886Y152869D02*
Y154055D01*
G01X106516Y155236D02*
Y159173D01*
G01X107697Y154055D02*
Y157992D01*
G01X108544Y149127D02*
X107677D01*
G01X111693D02*
X110827D01*
G01X114843D02*
X113977D01*
G01X117992D02*
X117126D01*
G01X108544Y149784D02*
X107677D01*
G01X111693D02*
X110827D01*
G01X114843D02*
X113977D01*
G01X117992D02*
X117126D01*
G01X104429Y152671D02*
X105689D01*
G01X99429D02*
X100689D01*
G01X104429Y153297D02*
X105689D01*
G01X99429D02*
X100689D01*
G01X107697Y157992D02*
X127422D01*
G01X106516Y159173D02*
X128603D01*
G01X115013Y214806D02*
X115040Y214737D01*
G01X114941Y214856D02*
X115013Y214806D01*
G01X114843Y214875D02*
X114941Y214856D01*
G01X111864Y214806D02*
X111890Y214737D01*
G01X111792Y214856D02*
X111864Y214806D01*
G01X111693Y214875D02*
X111792Y214856D01*
G01X108714Y214806D02*
X108740Y214737D01*
G01X108642Y214856D02*
X108714Y214806D01*
G01X108544Y214875D02*
X108642Y214856D01*
G01X117028D02*
X117126Y214875D01*
G01X116956Y214806D02*
X117028Y214856D01*
G01X116929Y214737D02*
X116956Y214806D01*
G01X113878Y214856D02*
X113977Y214875D01*
G01X113806Y214806D02*
X113878Y214856D01*
G01X113780Y214737D02*
X113806Y214806D01*
G01X110729Y214856D02*
X110827Y214875D01*
G01X110657Y214806D02*
X110729Y214856D01*
G01X110630Y214737D02*
X110657Y214806D01*
G01X107579Y214856D02*
X107677Y214875D01*
G01X107507Y214806D02*
X107579Y214856D01*
G01X107481Y214737D02*
X107507Y214806D01*
G01X108740Y215335D02*
G03X108544Y215532I-197J0D01*
G01X107677D02*
G03X107481Y215335I1J-197D01*
G01X111890D02*
G03X111693Y215532I-197J0D01*
G01X110827D02*
G03X110630Y215335I0J-197D01*
G01X115040D02*
G03X114843Y215532I-197J0D01*
G01X113977D02*
G03X113780Y215335I0J-197D01*
G01X117126Y215532D02*
G03X116929Y215335I0J-197D01*
G01X104744Y211929D02*
X105800Y207992D01*
G01X107481Y215334D02*
Y214291D01*
G01X107677Y215532D02*
Y214488D01*
G01X108544D02*
Y215532D01*
G01X108740Y214291D02*
Y215334D01*
G01X110630D02*
Y214291D01*
G01X110827Y215532D02*
Y214488D01*
G01X111693D02*
Y215532D01*
G01X111890Y214291D02*
Y215334D01*
G01X113780D02*
Y214291D01*
G01X113977Y215532D02*
Y214488D01*
G01X114843D02*
Y215532D01*
G01X115040Y214291D02*
Y215334D01*
G01X116929D02*
Y214291D01*
G01X117126Y215532D02*
Y214488D01*
G01X105800Y207992D02*
X129320D01*
G01X105430Y209370D02*
X129689D01*
G01X107677Y214488D02*
X107481D01*
G01X108740D02*
X108544D01*
G01X110827D02*
X110630D01*
G01X111890D02*
X111693D01*
G01X113977D02*
X113780D01*
G01X115040D02*
X114843D01*
G01X117126D02*
X116929D01*
G01X108544Y214875D02*
X107677D01*
G01X111693D02*
X110827D01*
G01X114843D02*
X113977D01*
G01X117992D02*
X117126D01*
G01X108544Y215532D02*
X107677D01*
G01X111693D02*
X110827D01*
G01X114843D02*
X113977D01*
G01X117992D02*
X117126D01*
G01X95860Y219115D02*
X95886Y219185D01*
G01X95788Y219064D02*
X95860Y219115D01*
G01X95689Y219045D02*
X95788Y219064D01*
G01X100860Y219115D02*
X100886Y219185D01*
G01X100788Y219064D02*
X100860Y219115D01*
G01X100689Y219045D02*
X100788Y219064D01*
G01X105860Y219115D02*
X105886Y219185D01*
G01X105788Y219064D02*
X105860Y219115D01*
G01X105689Y219045D02*
X105788Y219064D01*
G01X104331D02*
X104429Y219045D01*
G01X104259Y219115D02*
X104331Y219064D01*
G01X104233Y219185D02*
X104259Y219115D01*
G01X99331Y219064D02*
X99429Y219045D01*
G01X99259Y219115D02*
X99331Y219064D01*
G01X99233Y219185D02*
X99259Y219115D01*
G01X104233Y218616D02*
G03X104429Y218419I197J0D01*
G01X105689D02*
G03X105886Y218616I0J197D01*
G01X99233D02*
G03X99429Y218419I197J0D01*
G01X100689D02*
G03X100886Y218616I0J197D01*
G01X95689Y218419D02*
G03X95886Y218616I0J197D01*
G01X95689Y219803D02*
Y218419D01*
G01X95886Y218617D02*
Y219803D01*
G01X99233D02*
Y218617D01*
G01X99429Y219803D02*
Y218419D01*
G01X100689Y219803D02*
Y218419D01*
G01X100886Y218617D02*
Y219803D01*
G01X104233D02*
Y218617D01*
G01X104429Y219803D02*
Y218419D01*
G01X105689Y219803D02*
Y218419D01*
G01X105886Y218617D02*
Y219803D01*
G01X106516Y220984D02*
Y224921D01*
G01X107697Y219803D02*
Y223740D01*
G01Y219803D02*
X106516Y220984D01*
G01X107697Y223740D02*
X106516Y224921D01*
G01X104429Y218419D02*
X105689D01*
G01X99429D02*
X100689D01*
G01X104429Y219045D02*
X105689D01*
G01X99429D02*
X100689D01*
G01X107697Y223740D02*
X127422D01*
G01X106516Y224921D02*
X128603D01*
G01X109449Y464961D02*
Y470866D01*
G01Y464961D02*
G03X113386Y461024I3937J0D01*
G01Y474803D02*
G03X109449Y470866I0J-3937D01*
G01X113377Y730096D02*
Y732896D01*
G01X120906Y10118D02*
X119725Y8937D01*
G01X120906Y14055D02*
X119725Y12874D01*
G01X140630Y10118D02*
X120906D01*
G01X141811Y8937D02*
X119725D01*
G01X120906Y10118D02*
Y14055D01*
G01X119725Y8937D02*
Y12874D01*
G01X118996Y14794D02*
X118898Y14813D01*
G01X119068Y14743D02*
X118996Y14794D01*
G01X119095Y14673D02*
X119068Y14743D01*
G01X120716Y19052D02*
X120689Y19121D01*
G01X120788Y19002D02*
X120716Y19052D01*
G01X120886Y18984D02*
X120788Y19002D01*
G01X123865Y19052D02*
X123839Y19121D01*
G01X123937Y19002D02*
X123865Y19052D01*
G01X124036Y18984D02*
X123937Y19002D01*
G01X127015Y19052D02*
X126988Y19121D01*
G01X127087Y19002D02*
X127015Y19052D01*
G01X127185Y18984D02*
X127087Y19002D01*
G01X130164Y19052D02*
X130138Y19121D01*
G01X130237Y19002D02*
X130164Y19052D01*
G01X130335Y18984D02*
X130237Y19002D01*
G01X133314Y19052D02*
X133288Y19121D01*
G01X133386Y19002D02*
X133314Y19052D01*
G01X133485Y18984D02*
X133386Y19002D01*
G01X136464Y19052D02*
X136437Y19121D01*
G01X136536Y19002D02*
X136464Y19052D01*
G01X136634Y18984D02*
X136536Y19002D01*
G01X139613Y19052D02*
X139587Y19121D01*
G01X139685Y19002D02*
X139613Y19052D01*
G01X139784Y18984D02*
X139685Y19002D01*
G01X121851D02*
X121752Y18984D01*
G01X121923Y19052D02*
X121851Y19002D01*
G01X121949Y19121D02*
X121923Y19052D01*
G01X125000Y19002D02*
X124902Y18984D01*
G01X125072Y19052D02*
X125000Y19002D01*
G01X125099Y19121D02*
X125072Y19052D01*
G01X128150Y19002D02*
X128051Y18984D01*
G01X128222Y19052D02*
X128150Y19002D01*
G01X128248Y19121D02*
X128222Y19052D01*
G01X131300Y19002D02*
X131201Y18984D01*
G01X131372Y19052D02*
X131300Y19002D01*
G01X131398Y19121D02*
X131372Y19052D01*
G01X134449Y19002D02*
X134351Y18984D01*
G01X134521Y19052D02*
X134449Y19002D01*
G01X134548Y19121D02*
X134521Y19052D01*
G01X137599Y19002D02*
X137500Y18984D01*
G01X137671Y19052D02*
X137599Y19002D01*
G01X137697Y19121D02*
X137671Y19052D01*
G01X117468Y14743D02*
X117441Y14673D01*
G01X117540Y14794D02*
X117468Y14743D01*
G01X117638Y14813D02*
X117540Y14794D01*
G01X139587Y18524D02*
G03X139784Y18327I197J0D01*
G01X137500D02*
G03X137697Y18524I0J197D01*
G01X136437D02*
G03X136634Y18327I197J0D01*
G01X133288Y18524D02*
G03X133485Y18327I197J0D01*
G01X134351D02*
G03X134548Y18524I0J197D01*
G01X130138D02*
G03X130335Y18327I197J0D01*
G01X131201D02*
G03X131398Y18524I0J197D01*
G01X126988D02*
G03X127185Y18327I197J0D01*
G01X128051D02*
G03X128248Y18524I0J197D01*
G01X123839D02*
G03X124036Y18327I197J0D01*
G01X124902D02*
G03X125099Y18524I0J197D01*
G01X120689D02*
G03X120886Y18327I197J0D01*
G01X121752D02*
G03X121949Y18524I0J197D01*
G01X119095Y15242D02*
G03X118898Y15439I-197J0D01*
G01X117638D02*
G03X117441Y15242I0J-197D01*
G01X142528Y25866D02*
X119008D01*
G01X142898Y24488D02*
X118639D01*
G01X139587Y19370D02*
X139784D01*
G01X137500D02*
X137697D01*
G01X136437D02*
X136634D01*
G01X134351D02*
X134548D01*
G01X133288D02*
X133485D01*
G01X131201D02*
X131398D01*
G01X130138D02*
X130335D01*
G01X128051D02*
X128248D01*
G01X126988D02*
X127185D01*
G01X124902D02*
X125099D01*
G01X123839D02*
X124036D01*
G01X121752D02*
X121949D01*
G01X120689D02*
X120886D01*
G01X139784Y18984D02*
X140650D01*
G01X136634D02*
X137500D01*
G01X133485D02*
X134351D01*
G01X130335D02*
X131201D01*
G01X127185D02*
X128051D01*
G01X124036D02*
X124902D01*
G01X120886D02*
X121752D01*
G01X139784Y18327D02*
X140650D01*
G01X136634D02*
X137500D01*
G01X133485D02*
X134351D01*
G01X130335D02*
X131201D01*
G01X127185D02*
X128051D01*
G01X124036D02*
X124902D01*
G01X120886D02*
X121752D01*
G01X118898Y15439D02*
X117638D01*
G01X118898Y14813D02*
X117638D01*
G01X117953Y21929D02*
X119008Y25866D01*
G01X139784Y19370D02*
Y18327D01*
G01X139587Y19567D02*
Y18524D01*
G01X137697D02*
Y19567D01*
G01X137500Y18327D02*
Y19370D01*
G01X136634D02*
Y18327D01*
G01X136437Y19567D02*
Y18524D01*
G01X134548D02*
Y19567D01*
G01X134351Y18327D02*
Y19370D01*
G01X133485D02*
Y18327D01*
G01X133288Y19567D02*
Y18524D01*
G01X131398D02*
Y19567D01*
G01X131201Y18327D02*
Y19370D01*
G01X130335D02*
Y18327D01*
G01X130138Y19567D02*
Y18524D01*
G01X128248D02*
Y19567D01*
G01X128051Y18327D02*
Y19370D01*
G01X127185D02*
Y18327D01*
G01X126988Y19567D02*
Y18524D01*
G01X125099D02*
Y19567D01*
G01X124902Y18327D02*
Y19370D01*
G01X124036D02*
Y18327D01*
G01X123839Y19567D02*
Y18524D01*
G01X121949D02*
Y19567D01*
G01X121752Y18327D02*
Y19370D01*
G01X120886D02*
Y18327D01*
G01X120689Y19567D02*
Y18524D01*
G01X119095Y14055D02*
Y15241D01*
G01X118898Y14055D02*
Y15439D01*
G01X117638Y14055D02*
Y15439D01*
G01X117441Y15241D02*
Y14055D01*
G01X140630Y54606D02*
X120906D01*
G01X141811Y53425D02*
X119725D01*
G01X120906Y54606D02*
X119725Y53425D01*
G01X120906Y58543D02*
X119725Y57362D01*
G01X120906Y54606D02*
Y58543D01*
G01X119725Y53425D02*
Y57362D01*
G01X118996Y59282D02*
X118898Y59301D01*
G01X119068Y59231D02*
X118996Y59282D01*
G01X119095Y59161D02*
X119068Y59231D01*
G01X121851Y63490D02*
X121752Y63472D01*
G01X121923Y63540D02*
X121851Y63490D01*
G01X121949Y63609D02*
X121923Y63540D01*
G01X125000Y63490D02*
X124902Y63472D01*
G01X125072Y63540D02*
X125000Y63490D01*
G01X125099Y63609D02*
X125072Y63540D01*
G01X128150Y63490D02*
X128051Y63472D01*
G01X128222Y63540D02*
X128150Y63490D01*
G01X128248Y63609D02*
X128222Y63540D01*
G01X131300Y63490D02*
X131201Y63472D01*
G01X131372Y63540D02*
X131300Y63490D01*
G01X131398Y63609D02*
X131372Y63540D01*
G01X134449Y63490D02*
X134351Y63472D01*
G01X134521Y63540D02*
X134449Y63490D01*
G01X134548Y63609D02*
X134521Y63540D01*
G01X137599Y63490D02*
X137500Y63472D01*
G01X137671Y63540D02*
X137599Y63490D01*
G01X137697Y63609D02*
X137671Y63540D01*
G01X120716D02*
X120689Y63609D01*
G01X120788Y63490D02*
X120716Y63540D01*
G01X120886Y63472D02*
X120788Y63490D01*
G01X123865Y63540D02*
X123839Y63609D01*
G01X123937Y63490D02*
X123865Y63540D01*
G01X124036Y63472D02*
X123937Y63490D01*
G01X127015Y63540D02*
X126988Y63609D01*
G01X127087Y63490D02*
X127015Y63540D01*
G01X127185Y63472D02*
X127087Y63490D01*
G01X130164Y63540D02*
X130138Y63609D01*
G01X130237Y63490D02*
X130164Y63540D01*
G01X130335Y63472D02*
X130237Y63490D01*
G01X133314Y63540D02*
X133288Y63609D01*
G01X133386Y63490D02*
X133314Y63540D01*
G01X133485Y63472D02*
X133386Y63490D01*
G01X136464Y63540D02*
X136437Y63609D01*
G01X136536Y63490D02*
X136464Y63540D01*
G01X136634Y63472D02*
X136536Y63490D01*
G01X139613Y63540D02*
X139587Y63609D01*
G01X139685Y63490D02*
X139613Y63540D01*
G01X139784Y63472D02*
X139685Y63490D01*
G01X117468Y59231D02*
X117441Y59161D01*
G01X117540Y59282D02*
X117468Y59231D01*
G01X117638Y59301D02*
X117540Y59282D01*
G01X139587Y63012D02*
G03X139784Y62815I197J0D01*
G01X137500D02*
G03X137697Y63012I0J197D01*
G01X136437D02*
G03X136634Y62815I197J0D01*
G01X133288Y63012D02*
G03X133485Y62815I197J0D01*
G01X134351D02*
G03X134548Y63012I0J197D01*
G01X130138D02*
G03X130335Y62815I197J0D01*
G01X131201D02*
G03X131398Y63012I0J197D01*
G01X126988D02*
G03X127185Y62815I197J0D01*
G01X128051D02*
G03X128248Y63012I0J197D01*
G01X123839D02*
G03X124036Y62815I197J0D01*
G01X124902D02*
G03X125099Y63012I0J197D01*
G01X120689D02*
G03X120886Y62815I197J0D01*
G01X121752D02*
G03X121949Y63012I0J197D01*
G01X119095Y59730D02*
G03X118898Y59927I-197J0D01*
G01X117638D02*
G03X117441Y59730I0J-197D01*
G01X142528Y70354D02*
X119008D01*
G01X142898Y68976D02*
X118639D01*
G01X139587Y63858D02*
X139784D01*
G01X137500D02*
X137697D01*
G01X136437D02*
X136634D01*
G01X134351D02*
X134548D01*
G01X133288D02*
X133485D01*
G01X131201D02*
X131398D01*
G01X130138D02*
X130335D01*
G01X128051D02*
X128248D01*
G01X126988D02*
X127185D01*
G01X124902D02*
X125099D01*
G01X123839D02*
X124036D01*
G01X121752D02*
X121949D01*
G01X120689D02*
X120886D01*
G01X139784Y63472D02*
X140650D01*
G01X136634D02*
X137500D01*
G01X133485D02*
X134351D01*
G01X130335D02*
X131201D01*
G01X127185D02*
X128051D01*
G01X124036D02*
X124902D01*
G01X120886D02*
X121752D01*
G01X139784Y62815D02*
X140650D01*
G01X136634D02*
X137500D01*
G01X133485D02*
X134351D01*
G01X130335D02*
X131201D01*
G01X127185D02*
X128051D01*
G01X124036D02*
X124902D01*
G01X120886D02*
X121752D01*
G01X118898Y59927D02*
X117638D01*
G01X118898Y59301D02*
X117638D01*
G01X117953Y66417D02*
X119008Y70354D01*
G01X139784Y63858D02*
Y62815D01*
G01X139587Y64055D02*
Y63012D01*
G01X137697D02*
Y64055D01*
G01X137500Y62815D02*
Y63858D01*
G01X136634D02*
Y62815D01*
G01X136437Y64055D02*
Y63012D01*
G01X134548D02*
Y64055D01*
G01X134351Y62815D02*
Y63858D01*
G01X133485D02*
Y62815D01*
G01X133288Y64055D02*
Y63012D01*
G01X131398D02*
Y64055D01*
G01X131201Y62815D02*
Y63858D01*
G01X130335D02*
Y62815D01*
G01X130138Y64055D02*
Y63012D01*
G01X128248D02*
Y64055D01*
G01X128051Y62815D02*
Y63858D01*
G01X127185D02*
Y62815D01*
G01X126988Y64055D02*
Y63012D01*
G01X125099D02*
Y64055D01*
G01X124902Y62815D02*
Y63858D01*
G01X124036D02*
Y62815D01*
G01X123839Y64055D02*
Y63012D01*
G01X121949D02*
Y64055D01*
G01X121752Y62815D02*
Y63858D01*
G01X120886D02*
Y62815D01*
G01X120689Y64055D02*
Y63012D01*
G01X119095Y58543D02*
Y59730D01*
G01X118898Y58543D02*
Y59927D01*
G01X117638Y58543D02*
Y59927D01*
G01X117441Y59730D02*
Y58543D01*
G01X126477Y149108D02*
X126575Y149127D01*
G01X126405Y149058D02*
X126477Y149108D01*
G01X126378Y148989D02*
X126405Y149058D01*
G01X123327Y149108D02*
X123426Y149127D01*
G01X123255Y149058D02*
X123327Y149108D01*
G01X123229Y148989D02*
X123255Y149058D01*
G01X120177Y149108D02*
X120276Y149127D01*
G01X120105Y149058D02*
X120177Y149108D01*
G01X120079Y148989D02*
X120105Y149058D01*
G01X127612D02*
X127638Y148989D01*
G01X127540Y149108D02*
X127612Y149058D01*
G01X127441Y149127D02*
X127540Y149108D01*
G01X124462Y149058D02*
X124488Y148989D01*
G01X124390Y149108D02*
X124462Y149058D01*
G01X124292Y149127D02*
X124390Y149108D01*
G01X121313Y149058D02*
X121339Y148989D01*
G01X121240Y149108D02*
X121313Y149058D01*
G01X121142Y149127D02*
X121240Y149108D01*
G01X118163Y149058D02*
X118189Y148989D01*
G01X118091Y149108D02*
X118163Y149058D01*
G01X117992Y149127D02*
X118091Y149108D01*
G01X117992Y148740D02*
Y149784D01*
G01X118189Y148543D02*
Y149586D01*
G01X120079D02*
Y148543D01*
G01X120276Y149784D02*
Y148740D01*
G01X121142D02*
Y149784D01*
G01X121339Y148543D02*
Y149586D01*
G01X123229D02*
Y148543D01*
G01X123426Y149784D02*
Y148740D01*
G01X124292D02*
Y149784D01*
G01X124488Y148543D02*
Y149586D01*
G01X126378D02*
Y148543D01*
G01X126575Y149784D02*
Y148740D01*
G01X127441D02*
Y149784D01*
G01X127638Y148543D02*
Y149586D01*
G01X166555Y145591D02*
X130216D01*
G01X168800Y146181D02*
X130374D01*
G01D02*
X129320Y142244D01*
G01X118189Y148740D02*
X117992D01*
G01X120276D02*
X120079D01*
G01X121339D02*
X121142D01*
G01X123426D02*
X123229D01*
G01X124488D02*
X124292D01*
G01X126575D02*
X126378D01*
G01X127638D02*
X127441D01*
G01X130860Y153367D02*
X130886Y153437D01*
G01X130788Y153316D02*
X130860Y153367D01*
G01X130689Y153297D02*
X130788Y153316D01*
G01X135860Y153367D02*
X135886Y153437D01*
G01X135788Y153316D02*
X135860Y153367D01*
G01X135689Y153297D02*
X135788Y153316D01*
G01X139331D02*
X139429Y153297D01*
G01X139259Y153367D02*
X139331Y153316D01*
G01X139233Y153437D02*
X139259Y153367D01*
G01X134331Y153316D02*
X134429Y153297D01*
G01X134259Y153367D02*
X134331Y153316D01*
G01X134233Y153437D02*
X134259Y153367D01*
G01X129331Y153316D02*
X129429Y153297D01*
G01X129259Y153367D02*
X129331Y153316D01*
G01X129233Y153437D02*
X129259Y153367D01*
G01X118189Y149587D02*
G03X117992Y149784I-197J0D01*
G01X121339Y149587D02*
G03X121142Y149784I-197J0D01*
G01X120276D02*
G03X120079Y149587I0J-197D01*
G01X124488D02*
G03X124292Y149784I-197J0D01*
G01X123426D02*
G03X123229Y149587I0J-197D01*
G01X127638D02*
G03X127441Y149784I-197J0D01*
G01X126575D02*
G03X126378Y149587I0J-197D01*
G01X139233Y152868D02*
G03X139429Y152671I197J0D01*
G01X134233Y152868D02*
G03X134429Y152671I197J0D01*
G01X135689D02*
G03X135886Y152868I0J197D01*
G01X129233D02*
G03X129429Y152671I197J0D01*
G01X130689D02*
G03X130886Y152868I0J197D01*
G01X127422Y157992D02*
Y154055D01*
G01X128603Y159173D02*
Y155236D01*
G01X129233Y154055D02*
Y152869D01*
G01X129429Y154055D02*
Y152671D01*
G01X130689Y154055D02*
Y152671D01*
G01X130886Y152869D02*
Y154055D01*
G01X134233D02*
Y152869D01*
G01X134429Y154055D02*
Y152671D01*
G01X135689Y154055D02*
Y152671D01*
G01X135886Y152869D02*
Y154055D01*
G01X139233D02*
Y152869D01*
G01X139429Y154055D02*
Y152671D01*
G01X121142Y149127D02*
X120276D01*
G01X124292D02*
X123426D01*
G01X127441D02*
X126575D01*
G01X121142Y149784D02*
X120276D01*
G01X124292D02*
X123426D01*
G01X127441D02*
X126575D01*
G01X139429Y152671D02*
X140689D01*
G01X134429D02*
X135689D01*
G01X129429D02*
X130689D01*
G01X139429Y153297D02*
X140689D01*
G01X134429D02*
X135689D01*
G01X129429D02*
X130689D01*
G01X127422Y154055D02*
X163878D01*
G01X128603Y155236D02*
X165059D01*
G01X127422Y157992D02*
X128603Y159173D01*
G01X127422Y154055D02*
X128603Y155236D01*
G01X127612Y214806D02*
X127638Y214737D01*
G01X127540Y214856D02*
X127612Y214806D01*
G01X127441Y214875D02*
X127540Y214856D01*
G01X124462Y214806D02*
X124488Y214737D01*
G01X124390Y214856D02*
X124462Y214806D01*
G01X124292Y214875D02*
X124390Y214856D01*
G01X121313Y214806D02*
X121339Y214737D01*
G01X121240Y214856D02*
X121313Y214806D01*
G01X121142Y214875D02*
X121240Y214856D01*
G01X118163Y214806D02*
X118189Y214737D01*
G01X118091Y214856D02*
X118163Y214806D01*
G01X117992Y214875D02*
X118091Y214856D01*
G01X126477D02*
X126575Y214875D01*
G01X126405Y214806D02*
X126477Y214856D01*
G01X126378Y214737D02*
X126405Y214806D01*
G01X123327Y214856D02*
X123426Y214875D01*
G01X123255Y214806D02*
X123327Y214856D01*
G01X123229Y214737D02*
X123255Y214806D01*
G01X120177Y214856D02*
X120276Y214875D01*
G01X120105Y214806D02*
X120177Y214856D01*
G01X120079Y214737D02*
X120105Y214806D01*
G01X118189Y215335D02*
G03X117992Y215532I-197J0D01*
G01X121339Y215335D02*
G03X121142Y215532I-197J0D01*
G01X120276D02*
G03X120079Y215335I0J-197D01*
G01X124488D02*
G03X124292Y215532I-197J0D01*
G01X123426D02*
G03X123229Y215335I0J-197D01*
G01X127638D02*
G03X127441Y215532I-197J0D01*
G01X126575D02*
G03X126378Y215335I0J-197D01*
G01X117992Y214488D02*
Y215532D01*
G01X118189Y214291D02*
Y215334D01*
G01X120079D02*
Y214291D01*
G01X120276Y215532D02*
Y214488D01*
G01X121142D02*
Y215532D01*
G01X121339Y214291D02*
Y215334D01*
G01X123229D02*
Y214291D01*
G01X123426Y215532D02*
Y214488D01*
G01X124292D02*
Y215532D01*
G01X124488Y214291D02*
Y215334D01*
G01X126378D02*
Y214291D01*
G01X126575Y215532D02*
Y214488D01*
G01X127441D02*
Y215532D01*
G01X127638Y214291D02*
Y215334D01*
G01X130374Y211929D02*
X129320Y207992D01*
G01X166555Y211339D02*
X130216D01*
G01X168800Y211929D02*
X130374D01*
G01X118189Y214488D02*
X117992D01*
G01X120276D02*
X120079D01*
G01X121339D02*
X121142D01*
G01X123426D02*
X123229D01*
G01X124488D02*
X124292D01*
G01X126575D02*
X126378D01*
G01X127638D02*
X127441D01*
G01X121142Y214875D02*
X120276D01*
G01X124292D02*
X123426D01*
G01X127441D02*
X126575D01*
G01X121142Y215532D02*
X120276D01*
G01X124292D02*
X123426D01*
G01X127441D02*
X126575D01*
G01X130860Y219115D02*
X130886Y219185D01*
G01X130788Y219064D02*
X130860Y219115D01*
G01X130689Y219045D02*
X130788Y219064D01*
G01X135860Y219115D02*
X135886Y219185D01*
G01X135788Y219064D02*
X135860Y219115D01*
G01X135689Y219045D02*
X135788Y219064D01*
G01X139331D02*
X139429Y219045D01*
G01X139259Y219115D02*
X139331Y219064D01*
G01X139233Y219185D02*
X139259Y219115D01*
G01X134331Y219064D02*
X134429Y219045D01*
G01X134259Y219115D02*
X134331Y219064D01*
G01X134233Y219185D02*
X134259Y219115D01*
G01X129331Y219064D02*
X129429Y219045D01*
G01X129259Y219115D02*
X129331Y219064D01*
G01X129233Y219185D02*
X129259Y219115D01*
G01X139233Y218616D02*
G03X139429Y218419I197J0D01*
G01X134233Y218616D02*
G03X134429Y218419I197J0D01*
G01X135689D02*
G03X135886Y218616I0J197D01*
G01X129233D02*
G03X129429Y218419I197J0D01*
G01X130689D02*
G03X130886Y218616I0J197D01*
G01X127422Y223740D02*
Y219803D01*
G01X128603Y224921D02*
Y220984D01*
G01X129233Y219803D02*
Y218617D01*
G01X129429Y219803D02*
Y218419D01*
G01X130689Y219803D02*
Y218419D01*
G01X130886Y218617D02*
Y219803D01*
G01X134233D02*
Y218617D01*
G01X134429Y219803D02*
Y218419D01*
G01X135689Y219803D02*
Y218419D01*
G01X135886Y218617D02*
Y219803D01*
G01X139233D02*
Y218617D01*
G01X139429Y219803D02*
Y218419D01*
G01X127422Y223740D02*
X128603Y224921D01*
G01X127422Y219803D02*
X128603Y220984D01*
G01X139429Y218419D02*
X140689D01*
G01X134429D02*
X135689D01*
G01X129429D02*
X130689D01*
G01X139429Y219045D02*
X140689D01*
G01X134429D02*
X135689D01*
G01X129429D02*
X130689D01*
G01X127422Y219803D02*
X163878D01*
G01X128603Y220984D02*
X165059D01*
G01X145758Y655356D02*
G03I-4292J0D01*
G01X218268Y12874D02*
X141811D01*
G01D02*
Y8937D01*
G01X140630Y14055D02*
Y10118D01*
G01Y14055D02*
X141811Y12874D01*
G01X140630Y10118D02*
X141811Y8937D01*
G01X143996Y14794D02*
X143898Y14813D01*
G01X144068Y14743D02*
X143996Y14794D01*
G01X144095Y14673D02*
X144068Y14743D01*
G01X148996Y14794D02*
X148898Y14813D01*
G01X149068Y14743D02*
X148996Y14794D01*
G01X149095Y14673D02*
X149068Y14743D01*
G01X153996Y14794D02*
X153898Y14813D01*
G01X154068Y14743D02*
X153996Y14794D01*
G01X154095Y14673D02*
X154068Y14743D01*
G01X158996Y14794D02*
X158898Y14813D01*
G01X159068Y14743D02*
X158996Y14794D01*
G01X159095Y14673D02*
X159068Y14743D01*
G01X140748Y19002D02*
X140650Y18984D01*
G01X140820Y19052D02*
X140748Y19002D01*
G01X140847Y19121D02*
X140820Y19052D01*
G01X162468Y14743D02*
X162441Y14673D01*
G01X162540Y14794D02*
X162468Y14743D01*
G01X162638Y14813D02*
X162540Y14794D01*
G01X157468Y14743D02*
X157441Y14673D01*
G01X157540Y14794D02*
X157468Y14743D01*
G01X157638Y14813D02*
X157540Y14794D01*
G01X152468Y14743D02*
X152441Y14673D01*
G01X152540Y14794D02*
X152468Y14743D01*
G01X152638Y14813D02*
X152540Y14794D01*
G01X147468Y14743D02*
X147441Y14673D01*
G01X147540Y14794D02*
X147468Y14743D01*
G01X147638Y14813D02*
X147540Y14794D01*
G01X142468Y14743D02*
X142441Y14673D01*
G01X142540Y14794D02*
X142468Y14743D01*
G01X142638Y14813D02*
X142540Y14794D01*
G01X140650Y18327D02*
G03X140847Y18524I0J197D01*
G01X159095Y15242D02*
G03X158898Y15439I-197J0D01*
G01X157638D02*
G03X157441Y15242I0J-197D01*
G01X144095D02*
G03X143898Y15439I-197J0D01*
G01X142638D02*
G03X142441Y15242I0J-197D01*
G01X149095D02*
G03X148898Y15439I-197J0D01*
G01X147638D02*
G03X147441Y15242I0J-197D01*
G01X154095D02*
G03X153898Y15439I-197J0D01*
G01X152638D02*
G03X152441Y15242I0J-197D01*
G01X162638Y15439D02*
G03X162441Y15242I0J-197D01*
G01X143425Y22520D02*
X219764D01*
G01X222008Y21929D02*
X143583D01*
G01X140650Y19370D02*
X140847D01*
G01X143898Y15439D02*
X142638D01*
G01X148898D02*
X147638D01*
G01X153898D02*
X152638D01*
G01X158898D02*
X157638D01*
G01X143898Y14813D02*
X142638D01*
G01X148898D02*
X147638D01*
G01X153898D02*
X152638D01*
G01X158898D02*
X157638D01*
G01X217087Y14055D02*
X140630D01*
G01X162441Y15241D02*
Y14055D01*
G01X159095D02*
Y15241D01*
G01X158898Y14055D02*
Y15439D01*
G01X157638Y14055D02*
Y15439D01*
G01X157441Y15241D02*
Y14055D01*
G01X154095D02*
Y15241D01*
G01X153898Y14055D02*
Y15439D01*
G01X152638Y14055D02*
Y15439D01*
G01X152441Y15241D02*
Y14055D01*
G01X149095D02*
Y15241D01*
G01X148898Y14055D02*
Y15439D01*
G01X147638Y14055D02*
Y15439D01*
G01X147441Y15241D02*
Y14055D01*
G01X144095D02*
Y15241D01*
G01X143898Y14055D02*
Y15439D01*
G01X142638Y14055D02*
Y15439D01*
G01X142441Y15241D02*
Y14055D01*
G01X140847Y18524D02*
Y19567D01*
G01X140650Y18327D02*
Y19370D01*
G01X143583Y21929D02*
X142528Y25866D01*
G01X218268Y57362D02*
X141811D01*
G01D02*
Y53425D01*
G01X140630Y58543D02*
Y54606D01*
G01Y58543D02*
X141811Y57362D01*
G01X140630Y54606D02*
X141811Y53425D01*
G01X143996Y59282D02*
X143898Y59301D01*
G01X144068Y59231D02*
X143996Y59282D01*
G01X144095Y59161D02*
X144068Y59231D01*
G01X148996Y59282D02*
X148898Y59301D01*
G01X149068Y59231D02*
X148996Y59282D01*
G01X149095Y59161D02*
X149068Y59231D01*
G01X153996Y59282D02*
X153898Y59301D01*
G01X154068Y59231D02*
X153996Y59282D01*
G01X154095Y59161D02*
X154068Y59231D01*
G01X158996Y59282D02*
X158898Y59301D01*
G01X159068Y59231D02*
X158996Y59282D01*
G01X159095Y59161D02*
X159068Y59231D01*
G01X140748Y63490D02*
X140650Y63472D01*
G01X140820Y63540D02*
X140748Y63490D01*
G01X140847Y63609D02*
X140820Y63540D01*
G01X162468Y59231D02*
X162441Y59161D01*
G01X162540Y59282D02*
X162468Y59231D01*
G01X162638Y59301D02*
X162540Y59282D01*
G01X157468Y59231D02*
X157441Y59161D01*
G01X157540Y59282D02*
X157468Y59231D01*
G01X157638Y59301D02*
X157540Y59282D01*
G01X152468Y59231D02*
X152441Y59161D01*
G01X152540Y59282D02*
X152468Y59231D01*
G01X152638Y59301D02*
X152540Y59282D01*
G01X147468Y59231D02*
X147441Y59161D01*
G01X147540Y59282D02*
X147468Y59231D01*
G01X147638Y59301D02*
X147540Y59282D01*
G01X142468Y59231D02*
X142441Y59161D01*
G01X142540Y59282D02*
X142468Y59231D01*
G01X142638Y59301D02*
X142540Y59282D01*
G01X140650Y62815D02*
G03X140847Y63012I0J197D01*
G01X159095Y59730D02*
G03X158898Y59927I-197J0D01*
G01X157638D02*
G03X157441Y59730I0J-197D01*
G01X144095D02*
G03X143898Y59927I-197J0D01*
G01X142638D02*
G03X142441Y59730I0J-197D01*
G01X149095D02*
G03X148898Y59927I-197J0D01*
G01X147638D02*
G03X147441Y59730I0J-197D01*
G01X154095D02*
G03X153898Y59927I-197J0D01*
G01X152638D02*
G03X152441Y59730I0J-197D01*
G01X162638Y59927D02*
G03X162441Y59730I0J-197D01*
G01X143425Y67008D02*
X219764D01*
G01X222008Y66417D02*
X143583D01*
G01X140650Y63858D02*
X140847D01*
G01X143898Y59927D02*
X142638D01*
G01X148898D02*
X147638D01*
G01X153898D02*
X152638D01*
G01X158898D02*
X157638D01*
G01X143898Y59301D02*
X142638D01*
G01X148898D02*
X147638D01*
G01X153898D02*
X152638D01*
G01X158898D02*
X157638D01*
G01X217087Y58543D02*
X140630D01*
G01X162441Y59730D02*
Y58543D01*
G01X159095D02*
Y59730D01*
G01X158898Y58543D02*
Y59927D01*
G01X157638Y58543D02*
Y59927D01*
G01X157441Y59730D02*
Y58543D01*
G01X154095D02*
Y59730D01*
G01X153898Y58543D02*
Y59927D01*
G01X152638Y58543D02*
Y59927D01*
G01X152441Y59730D02*
Y58543D01*
G01X149095D02*
Y59730D01*
G01X148898Y58543D02*
Y59927D01*
G01X147638Y58543D02*
Y59927D01*
G01X147441Y59730D02*
Y58543D01*
G01X144095D02*
Y59730D01*
G01X143898Y58543D02*
Y59927D01*
G01X142638Y58543D02*
Y59927D01*
G01X142441Y59730D02*
Y58543D01*
G01X140847Y63012D02*
Y64055D01*
G01X140650Y62815D02*
Y63858D01*
G01X143583Y66417D02*
X142528Y70354D01*
G01X140860Y153367D02*
X140886Y153437D01*
G01X140788Y153316D02*
X140860Y153367D01*
G01X140689Y153297D02*
X140788Y153316D01*
G01X145860Y153367D02*
X145886Y153437D01*
G01X145788Y153316D02*
X145860Y153367D01*
G01X145689Y153297D02*
X145788Y153316D01*
G01X150860Y153367D02*
X150886Y153437D01*
G01X150788Y153316D02*
X150860Y153367D01*
G01X150689Y153297D02*
X150788Y153316D01*
G01X155860Y153367D02*
X155886Y153437D01*
G01X155788Y153316D02*
X155860Y153367D01*
G01X155689Y153297D02*
X155788Y153316D01*
G01X160860Y153367D02*
X160886Y153437D01*
G01X160788Y153316D02*
X160860Y153367D01*
G01X160689Y153297D02*
X160788Y153316D01*
G01X159331D02*
X159429Y153297D01*
G01X159259Y153367D02*
X159331Y153316D01*
G01X159233Y153437D02*
X159259Y153367D01*
G01X154331Y153316D02*
X154429Y153297D01*
G01X154259Y153367D02*
X154331Y153316D01*
G01X154233Y153437D02*
X154259Y153367D01*
G01X149331Y153316D02*
X149429Y153297D01*
G01X149259Y153367D02*
X149331Y153316D01*
G01X149233Y153437D02*
X149259Y153367D01*
G01X144331Y153316D02*
X144429Y153297D01*
G01X144259Y153367D02*
X144331Y153316D01*
G01X144233Y153437D02*
X144259Y153367D01*
G01X159233Y152868D02*
G03X159429Y152671I197J0D01*
G01X160689D02*
G03X160886Y152868I0J197D01*
G01X154233D02*
G03X154429Y152671I197J0D01*
G01X155689D02*
G03X155886Y152868I0J197D01*
G01X149233D02*
G03X149429Y152671I197J0D01*
G01X150689D02*
G03X150886Y152868I0J197D01*
G01X144233D02*
G03X144429Y152671I197J0D01*
G01X145689D02*
G03X145886Y152868I0J197D01*
G01X140689Y152671D02*
G03X140886Y152868I0J197D01*
G01X140689Y154055D02*
Y152671D01*
G01X140886Y152869D02*
Y154055D01*
G01X144233D02*
Y152869D01*
G01X144429Y154055D02*
Y152671D01*
G01X145689Y154055D02*
Y152671D01*
G01X145886Y152869D02*
Y154055D01*
G01X149233D02*
Y152869D01*
G01X149429Y154055D02*
Y152671D01*
G01X150689Y154055D02*
Y152671D01*
G01X150886Y152869D02*
Y154055D01*
G01X154233D02*
Y152869D01*
G01X154429Y154055D02*
Y152671D01*
G01X155689Y154055D02*
Y152671D01*
G01X155886Y152869D02*
Y154055D01*
G01X159233D02*
Y152869D01*
G01X159429Y154055D02*
Y152671D01*
G01X160689Y154055D02*
Y152671D01*
G01X160886Y152869D02*
Y154055D01*
G01X159429Y152671D02*
X160689D01*
G01X154429D02*
X155689D01*
G01X149429D02*
X150689D01*
G01X144429D02*
X145689D01*
G01X159429Y153297D02*
X160689D01*
G01X154429D02*
X155689D01*
G01X149429D02*
X150689D01*
G01X144429D02*
X145689D01*
G01X161418Y179729D02*
G03X163386Y181697I0J1968D01*
G01Y195477D02*
G03X161418Y197445I-1968J0D01*
G01X140860Y219115D02*
X140886Y219185D01*
G01X140788Y219064D02*
X140860Y219115D01*
G01X140689Y219045D02*
X140788Y219064D01*
G01X145860Y219115D02*
X145886Y219185D01*
G01X145788Y219064D02*
X145860Y219115D01*
G01X145689Y219045D02*
X145788Y219064D01*
G01X150860Y219115D02*
X150886Y219185D01*
G01X150788Y219064D02*
X150860Y219115D01*
G01X150689Y219045D02*
X150788Y219064D01*
G01X155860Y219115D02*
X155886Y219185D01*
G01X155788Y219064D02*
X155860Y219115D01*
G01X155689Y219045D02*
X155788Y219064D01*
G01X160860Y219115D02*
X160886Y219185D01*
G01X160788Y219064D02*
X160860Y219115D01*
G01X160689Y219045D02*
X160788Y219064D01*
G01X159331D02*
X159429Y219045D01*
G01X159259Y219115D02*
X159331Y219064D01*
G01X159233Y219185D02*
X159259Y219115D01*
G01X154331Y219064D02*
X154429Y219045D01*
G01X154259Y219115D02*
X154331Y219064D01*
G01X154233Y219185D02*
X154259Y219115D01*
G01X149331Y219064D02*
X149429Y219045D01*
G01X149259Y219115D02*
X149331Y219064D01*
G01X149233Y219185D02*
X149259Y219115D01*
G01X144331Y219064D02*
X144429Y219045D01*
G01X144259Y219115D02*
X144331Y219064D01*
G01X144233Y219185D02*
X144259Y219115D01*
G01X159233Y218616D02*
G03X159429Y218419I197J0D01*
G01X160689D02*
G03X160886Y218616I0J197D01*
G01X154233D02*
G03X154429Y218419I197J0D01*
G01X155689D02*
G03X155886Y218616I0J197D01*
G01X149233D02*
G03X149429Y218419I197J0D01*
G01X150689D02*
G03X150886Y218616I0J197D01*
G01X144233D02*
G03X144429Y218419I197J0D01*
G01X145689D02*
G03X145886Y218616I0J197D01*
G01X140689Y218419D02*
G03X140886Y218616I0J197D01*
G01X140689Y219803D02*
Y218419D01*
G01X140886Y218617D02*
Y219803D01*
G01X144233D02*
Y218617D01*
G01X144429Y219803D02*
Y218419D01*
G01X145689Y219803D02*
Y218419D01*
G01X145886Y218617D02*
Y219803D01*
G01X149233D02*
Y218617D01*
G01X149429Y219803D02*
Y218419D01*
G01X150689Y219803D02*
Y218419D01*
G01X150886Y218617D02*
Y219803D01*
G01X154233D02*
Y218617D01*
G01X154429Y219803D02*
Y218419D01*
G01X155689Y219803D02*
Y218419D01*
G01X155886Y218617D02*
Y219803D01*
G01X159233D02*
Y218617D01*
G01X159429Y219803D02*
Y218419D01*
G01X160689Y219803D02*
Y218419D01*
G01X160886Y218617D02*
Y219803D01*
G01X159429Y218419D02*
X160689D01*
G01X154429D02*
X155689D01*
G01X149429D02*
X150689D01*
G01X144429D02*
X145689D01*
G01X159429Y219045D02*
X160689D01*
G01X154429D02*
X155689D01*
G01X149429D02*
X150689D01*
G01X144429D02*
X145689D01*
G01X159449Y263386D02*
G03X163386Y267323I0J3937D01*
G01X155512Y303937D02*
Y271260D01*
G01X163386Y303937D02*
G03X155512I-3937J0D01*
G01Y329134D02*
G03X163386I3937J0D01*
G01X155512Y361811D02*
Y329134D01*
G01X161418Y549414D02*
G03X163386Y551382I0J1968D01*
G01Y565162D02*
G03X161418Y567130I-1968J0D01*
G01X159449Y633071D02*
G03X163386Y637008I0J3937D01*
G01X155512Y673622D02*
Y640945D01*
G01X163386Y673622D02*
G03X155512I-3937J0D01*
G01Y698819D02*
G03X163386I3937J0D01*
G01X155512Y729528D02*
Y698819D01*
G01Y729528D02*
G03X153544Y731496I-1968J0D01*
G01X163996Y14794D02*
X163898Y14813D01*
G01X164068Y14743D02*
X163996Y14794D01*
G01X164095Y14673D02*
X164068Y14743D01*
G01X168996Y14794D02*
X168898Y14813D01*
G01X169068Y14743D02*
X168996Y14794D01*
G01X169095Y14673D02*
X169068Y14743D01*
G01X173996Y14794D02*
X173898Y14813D01*
G01X174068Y14743D02*
X173996Y14794D01*
G01X174095Y14673D02*
X174068Y14743D01*
G01X178996Y14794D02*
X178898Y14813D01*
G01X179068Y14743D02*
X178996Y14794D01*
G01X179095Y14673D02*
X179068Y14743D01*
G01X183996Y14794D02*
X183898Y14813D01*
G01X184068Y14743D02*
X183996Y14794D01*
G01X184095Y14673D02*
X184068Y14743D01*
G01X182468D02*
X182441Y14673D01*
G01X182540Y14794D02*
X182468Y14743D01*
G01X182638Y14813D02*
X182540Y14794D01*
G01X177468Y14743D02*
X177441Y14673D01*
G01X177540Y14794D02*
X177468Y14743D01*
G01X177638Y14813D02*
X177540Y14794D01*
G01X172468Y14743D02*
X172441Y14673D01*
G01X172540Y14794D02*
X172468Y14743D01*
G01X172638Y14813D02*
X172540Y14794D01*
G01X167468Y14743D02*
X167441Y14673D01*
G01X167540Y14794D02*
X167468Y14743D01*
G01X167638Y14813D02*
X167540Y14794D01*
G01X164095Y15242D02*
G03X163898Y15439I-197J0D01*
G01X169095Y15242D02*
G03X168898Y15439I-197J0D01*
G01X167638D02*
G03X167441Y15242I0J-197D01*
G01X174095D02*
G03X173898Y15439I-197J0D01*
G01X172638D02*
G03X172441Y15242I0J-197D01*
G01X179095D02*
G03X178898Y15439I-197J0D01*
G01X177638D02*
G03X177441Y15242I0J-197D01*
G01X184095D02*
G03X183898Y15439I-197J0D01*
G01X182638D02*
G03X182441Y15242I0J-197D01*
G01X184095Y14055D02*
Y15241D01*
G01X183898Y14055D02*
Y15439D01*
G01X182638Y14055D02*
Y15439D01*
G01X182441Y15241D02*
Y14055D01*
G01X163898Y15439D02*
X162638D01*
G01X168898D02*
X167638D01*
G01X173898D02*
X172638D01*
G01X178898D02*
X177638D01*
G01X183898D02*
X182638D01*
G01X163898Y14813D02*
X162638D01*
G01X168898D02*
X167638D01*
G01X173898D02*
X172638D01*
G01X178898D02*
X177638D01*
G01X183898D02*
X182638D01*
G01X179095Y14055D02*
Y15241D01*
G01X178898Y14055D02*
Y15439D01*
G01X177638Y14055D02*
Y15439D01*
G01X177441Y15241D02*
Y14055D01*
G01X174095D02*
Y15241D01*
G01X173898Y14055D02*
Y15439D01*
G01X172638Y14055D02*
Y15439D01*
G01X172441Y15241D02*
Y14055D01*
G01X169095D02*
Y15241D01*
G01X168898Y14055D02*
Y15439D01*
G01X167638Y14055D02*
Y15439D01*
G01X167441Y15241D02*
Y14055D01*
G01X164095D02*
Y15241D01*
G01X163898Y14055D02*
Y15439D01*
G01X162638Y14055D02*
Y15439D01*
G01X163996Y59282D02*
X163898Y59301D01*
G01X164068Y59231D02*
X163996Y59282D01*
G01X164095Y59161D02*
X164068Y59231D01*
G01X168996Y59282D02*
X168898Y59301D01*
G01X169068Y59231D02*
X168996Y59282D01*
G01X169095Y59161D02*
X169068Y59231D01*
G01X173996Y59282D02*
X173898Y59301D01*
G01X174068Y59231D02*
X173996Y59282D01*
G01X174095Y59161D02*
X174068Y59231D01*
G01X178996Y59282D02*
X178898Y59301D01*
G01X179068Y59231D02*
X178996Y59282D01*
G01X179095Y59161D02*
X179068Y59231D01*
G01X183996Y59282D02*
X183898Y59301D01*
G01X184068Y59231D02*
X183996Y59282D01*
G01X184095Y59161D02*
X184068Y59231D01*
G01X182468D02*
X182441Y59161D01*
G01X182540Y59282D02*
X182468Y59231D01*
G01X182638Y59301D02*
X182540Y59282D01*
G01X177468Y59231D02*
X177441Y59161D01*
G01X177540Y59282D02*
X177468Y59231D01*
G01X177638Y59301D02*
X177540Y59282D01*
G01X172468Y59231D02*
X172441Y59161D01*
G01X172540Y59282D02*
X172468Y59231D01*
G01X172638Y59301D02*
X172540Y59282D01*
G01X167468Y59231D02*
X167441Y59161D01*
G01X167540Y59282D02*
X167468Y59231D01*
G01X167638Y59301D02*
X167540Y59282D01*
G01X164095Y59730D02*
G03X163898Y59927I-197J0D01*
G01X169095Y59730D02*
G03X168898Y59927I-197J0D01*
G01X167638D02*
G03X167441Y59730I0J-197D01*
G01X174095D02*
G03X173898Y59927I-197J0D01*
G01X172638D02*
G03X172441Y59730I0J-197D01*
G01X179095D02*
G03X178898Y59927I-197J0D01*
G01X177638D02*
G03X177441Y59730I0J-197D01*
G01X184095D02*
G03X183898Y59927I-197J0D01*
G01X182638D02*
G03X182441Y59730I0J-197D01*
G01X163898Y59927D02*
X162638D01*
G01X168898D02*
X167638D01*
G01X173898D02*
X172638D01*
G01X178898D02*
X177638D01*
G01X183898D02*
X182638D01*
G01X163898Y59301D02*
X162638D01*
G01X168898D02*
X167638D01*
G01X173898D02*
X172638D01*
G01X178898D02*
X177638D01*
G01X183898D02*
X182638D01*
G01X184095Y58543D02*
Y59730D01*
G01X183898Y58543D02*
Y59927D01*
G01X182638Y58543D02*
Y59927D01*
G01X182441Y59730D02*
Y58543D01*
G01X179095D02*
Y59730D01*
G01X178898Y58543D02*
Y59927D01*
G01X177638Y58543D02*
Y59927D01*
G01X177441Y59730D02*
Y58543D01*
G01X174095D02*
Y59730D01*
G01X173898Y58543D02*
Y59927D01*
G01X172638Y58543D02*
Y59927D01*
G01X172441Y59730D02*
Y58543D01*
G01X169095D02*
Y59730D01*
G01X168898Y58543D02*
Y59927D01*
G01X167638Y58543D02*
Y59927D01*
G01X167441Y59730D02*
Y58543D01*
G01X164095D02*
Y59730D01*
G01X163898Y58543D02*
Y59927D01*
G01X162638Y58543D02*
Y59927D01*
G01X169902Y142244D02*
X166555Y145591D01*
G01X163878Y148543D02*
X165059Y147362D01*
G01X169902Y142244D02*
X185650D01*
G01X163878Y154055D02*
Y148543D01*
G01X165059Y155236D02*
Y147362D01*
G01X167422Y146181D02*
Y149331D01*
G01X168800Y159961D02*
Y146181D01*
G01X177146Y155630D02*
G03X175965Y156811I-1181J0D01*
G01Y149331D02*
G03X177146Y150512I0J1181D01*
G01X168800Y155556D02*
X170768Y154252D01*
G01X176690Y149580D02*
X172461Y151890D01*
G01X167422Y156811D02*
Y159961D01*
G01X170768Y154252D02*
Y151890D01*
G01X175965Y149331D02*
X167422D01*
G01X172461Y151890D02*
X170768D01*
G01Y154252D02*
X172461D01*
G01X175965Y156811D02*
X167422D01*
G01X185650Y163898D02*
X169902D01*
G01X172461Y154252D02*
Y151890D01*
G01X177146Y155630D02*
Y150512D01*
G01X166555Y160551D02*
X169902Y163898D01*
G01X163878Y154055D02*
X165059Y155236D01*
G01X172461Y154252D02*
X176690Y156562D01*
G01X170768Y151890D02*
X168800Y150586D01*
G01X163386Y181697D02*
Y195477D01*
G01X175965Y215079D02*
G03X177146Y216260I0J1181D01*
G01X163878Y219803D02*
Y214291D01*
G01X165059Y220984D02*
Y213110D01*
G01X167422Y211929D02*
Y215079D01*
G01X168800Y225709D02*
Y211929D01*
G01X169902Y207992D02*
X166555Y211339D01*
G01X163878Y214291D02*
X165059Y213110D01*
G01X177146Y221378D02*
Y216260D01*
G01X176690Y215328D02*
X172461Y217638D01*
G01X169902Y207992D02*
X185650D01*
G01X170768Y217638D02*
X168800Y216334D01*
G01X175965Y215079D02*
X167422D01*
G01X177146Y221378D02*
G03X175965Y222559I-1181J0D01*
G01X167422D02*
Y225709D01*
G01X170768Y220000D02*
Y217638D01*
G01X172461Y220000D02*
Y217638D01*
G01X168800Y221304D02*
X170768Y220000D01*
G01X166555Y226299D02*
X169902Y229646D01*
G01X163878Y219803D02*
X165059Y220984D01*
G01X172461Y220000D02*
X176690Y222310D01*
G01X172461Y217638D02*
X170768D01*
G01Y220000D02*
X172461D01*
G01X175965Y222559D02*
X167422D01*
G01X185650Y229646D02*
X169902D01*
G01X163386Y357874D02*
Y267323D01*
G01X172697Y356754D02*
G03Y352754I0J-2000D01*
G01D02*
G03Y356754I0J2000D01*
G01X166397Y350854D02*
Y358654D01*
G01X178997Y350854D02*
X166397D01*
G01X178997Y358654D02*
Y350854D01*
G01X165297Y349754D02*
Y359754D01*
G01X180097Y349754D02*
X165297D01*
G01X180097Y359754D02*
Y349754D01*
G01X166397Y358654D02*
X178997D01*
G01X165297Y359754D02*
X180097D01*
G01X167323Y361811D02*
G03X163386Y357874I0J-3937D01*
G01X535433Y361811D02*
X167323D01*
G01X163386Y551382D02*
Y565162D01*
G01Y727559D02*
Y637008D01*
G01X172697Y726439D02*
G03Y722439I0J-2000D01*
G01D02*
G03Y726439I0J2000D01*
G01X166397Y728339D02*
X178997D01*
G01X166397Y720539D02*
Y728339D01*
G01X178997Y720539D02*
X166397D01*
G01X178997Y728339D02*
Y720539D01*
G01X165297Y729439D02*
X180097D01*
G01X165297Y719439D02*
Y729439D01*
G01X180097Y719439D02*
X165297D01*
G01X180097Y729439D02*
Y719439D01*
G01X167323Y731496D02*
G03X163386Y727559I0J-3937D01*
G01X535433Y731496D02*
X167323D01*
G01X188996Y14794D02*
X188898Y14813D01*
G01X189068Y14743D02*
X188996Y14794D01*
G01X189095Y14673D02*
X189068Y14743D01*
G01X193996Y14794D02*
X193898Y14813D01*
G01X194068Y14743D02*
X193996Y14794D01*
G01X194095Y14673D02*
X194068Y14743D01*
G01X198996Y14794D02*
X198898Y14813D01*
G01X199068Y14743D02*
X198996Y14794D01*
G01X199095Y14673D02*
X199068Y14743D01*
G01X203996Y14794D02*
X203898Y14813D01*
G01X204068Y14743D02*
X203996Y14794D01*
G01X204095Y14673D02*
X204068Y14743D01*
G01X207468D02*
X207441Y14673D01*
G01X207540Y14794D02*
X207468Y14743D01*
G01X207638Y14813D02*
X207540Y14794D01*
G01X202468Y14743D02*
X202441Y14673D01*
G01X202540Y14794D02*
X202468Y14743D01*
G01X202638Y14813D02*
X202540Y14794D01*
G01X197468Y14743D02*
X197441Y14673D01*
G01X197540Y14794D02*
X197468Y14743D01*
G01X197638Y14813D02*
X197540Y14794D01*
G01X192468Y14743D02*
X192441Y14673D01*
G01X192540Y14794D02*
X192468Y14743D01*
G01X192638Y14813D02*
X192540Y14794D01*
G01X187468Y14743D02*
X187441Y14673D01*
G01X187540Y14794D02*
X187468Y14743D01*
G01X187638Y14813D02*
X187540Y14794D01*
G01X199095Y15242D02*
G03X198898Y15439I-197J0D01*
G01X197638D02*
G03X197441Y15242I0J-197D01*
G01X189095D02*
G03X188898Y15439I-197J0D01*
G01X194095Y15242D02*
G03X193898Y15439I-197J0D01*
G01X192638D02*
G03X192441Y15242I0J-197D01*
G01X204095D02*
G03X203898Y15439I-197J0D01*
G01X202638D02*
G03X202441Y15242I0J-197D01*
G01X207638Y15439D02*
G03X207441Y15242I0J-197D01*
G01X187638Y15439D02*
G03X187441Y15242I0J-197D01*
G01X207638Y14055D02*
Y15439D01*
G01X207441Y15241D02*
Y14055D01*
G01X204095D02*
Y15241D01*
G01X203898Y14055D02*
Y15439D01*
G01X202638Y14055D02*
Y15439D01*
G01X202441Y15241D02*
Y14055D01*
G01X199095D02*
Y15241D01*
G01X198898Y14055D02*
Y15439D01*
G01X197638Y14055D02*
Y15439D01*
G01X197441Y15241D02*
Y14055D01*
G01X194095D02*
Y15241D01*
G01X193898Y14055D02*
Y15439D01*
G01X192638Y14055D02*
Y15439D01*
G01X192441Y15241D02*
Y14055D01*
G01X189095D02*
Y15241D01*
G01X188898Y14055D02*
Y15439D01*
G01X187638Y14055D02*
Y15439D01*
G01X187441Y15241D02*
Y14055D01*
G01X188898Y15439D02*
X187638D01*
G01X193898D02*
X192638D01*
G01X198898D02*
X197638D01*
G01X203898D02*
X202638D01*
G01X208898D02*
X207638D01*
G01X188898Y14813D02*
X187638D01*
G01X193898D02*
X192638D01*
G01X198898D02*
X197638D01*
G01X203898D02*
X202638D01*
G01X208898D02*
X207638D01*
G01X188977Y41339D02*
G03X190945Y43307I0J1968D01*
G01Y45276D02*
G03X188977Y47244I-1968J0D01*
G01X190945Y43307D02*
Y45276D01*
G01X188996Y59282D02*
X188898Y59301D01*
G01X189068Y59231D02*
X188996Y59282D01*
G01X189095Y59161D02*
X189068Y59231D01*
G01X193996Y59282D02*
X193898Y59301D01*
G01X194068Y59231D02*
X193996Y59282D01*
G01X194095Y59161D02*
X194068Y59231D01*
G01X198996Y59282D02*
X198898Y59301D01*
G01X199068Y59231D02*
X198996Y59282D01*
G01X199095Y59161D02*
X199068Y59231D01*
G01X203996Y59282D02*
X203898Y59301D01*
G01X204068Y59231D02*
X203996Y59282D01*
G01X204095Y59161D02*
X204068Y59231D01*
G01X207468D02*
X207441Y59161D01*
G01X207540Y59282D02*
X207468Y59231D01*
G01X207638Y59301D02*
X207540Y59282D01*
G01X202468Y59231D02*
X202441Y59161D01*
G01X202540Y59282D02*
X202468Y59231D01*
G01X202638Y59301D02*
X202540Y59282D01*
G01X197468Y59231D02*
X197441Y59161D01*
G01X197540Y59282D02*
X197468Y59231D01*
G01X197638Y59301D02*
X197540Y59282D01*
G01X192468Y59231D02*
X192441Y59161D01*
G01X192540Y59282D02*
X192468Y59231D01*
G01X192638Y59301D02*
X192540Y59282D01*
G01X187468Y59231D02*
X187441Y59161D01*
G01X187540Y59282D02*
X187468Y59231D01*
G01X187638Y59301D02*
X187540Y59282D01*
G01X204095Y59730D02*
G03X203898Y59927I-197J0D01*
G01X207638D02*
G03X207441Y59730I0J-197D01*
G01X199095D02*
G03X198898Y59927I-197J0D01*
G01X197638D02*
G03X197441Y59730I0J-197D01*
G01X189095D02*
G03X188898Y59927I-197J0D01*
G01X187638D02*
G03X187441Y59730I0J-197D01*
G01X194095D02*
G03X193898Y59927I-197J0D01*
G01X192638D02*
G03X192441Y59730I0J-197D01*
G01X202638Y59927D02*
G03X202441Y59730I0J-197D01*
G01X188898Y59927D02*
X187638D01*
G01X193898D02*
X192638D01*
G01X198898D02*
X197638D01*
G01X203898D02*
X202638D01*
G01X208898D02*
X207638D01*
G01X188898Y59301D02*
X187638D01*
G01X193898D02*
X192638D01*
G01X198898D02*
X197638D01*
G01X203898D02*
X202638D01*
G01X208898D02*
X207638D01*
G01Y58543D02*
Y59927D01*
G01X207441Y59730D02*
Y58543D01*
G01X204095D02*
Y59730D01*
G01X203898Y58543D02*
Y59927D01*
G01X202638Y58543D02*
Y59927D01*
G01X202441Y59730D02*
Y58543D01*
G01X199095D02*
Y59730D01*
G01X198898Y58543D02*
Y59927D01*
G01X197638Y58543D02*
Y59927D01*
G01X197441Y59730D02*
Y58543D01*
G01X194095D02*
Y59730D01*
G01X193898Y58543D02*
Y59927D01*
G01X192638Y58543D02*
Y59927D01*
G01X192441Y59730D02*
Y58543D01*
G01X189095D02*
Y59730D01*
G01X188898Y58543D02*
Y59927D01*
G01X187638Y58543D02*
Y59927D01*
G01X187441Y59730D02*
Y58543D01*
G01X196851Y97244D02*
G03X194882Y95276I0J-1969D01*
G01X192914Y91339D02*
G03X194882Y93307I0J1968D01*
G01X196851Y97244D02*
X269685D01*
G01X194882Y93307D02*
Y95276D01*
G01X185650Y142244D02*
G03X187618Y144213I0J1968D01*
G01D02*
Y161929D01*
G01D02*
G03X185650Y163898I-1968J1D01*
G01Y207992D02*
G03X187618Y209961I0J1968D01*
G01D02*
Y227677D01*
G01D02*
G03X185650Y229646I-1968J1D01*
G01X188977Y411024D02*
G03X190945Y412992I0J1968D01*
G01Y414961D02*
G03X188977Y416929I-1968J0D01*
G01X190945Y412992D02*
Y414961D01*
G01X196851Y466929D02*
G03X194882Y464961I-1J-1968D01*
G01X192914Y461024D02*
G03X194882Y462992I0J1968D01*
G01D02*
Y464961D01*
G01X196851Y466929D02*
X269685D01*
G01X229174Y11299D02*
G03X230355Y12480I0J1181D01*
G01X223977Y13858D02*
X222008Y12554D01*
G01X230355Y17599D02*
Y12480D01*
G01X222008Y8150D02*
Y21929D01*
G01X220630Y8150D02*
Y11299D01*
G01X218268Y20748D02*
Y12874D01*
G01X220630Y11299D02*
X229174D01*
G01X217087Y14055D02*
X218268Y12874D01*
G01X223111Y4213D02*
X219764Y7559D01*
G01X229899Y11548D02*
X225670Y13858D01*
G01X223111Y4213D02*
X238859D01*
G01X208996Y14794D02*
X208898Y14813D01*
G01X209068Y14743D02*
X208996Y14794D01*
G01X209095Y14673D02*
X209068Y14743D01*
G01X213996Y14794D02*
X213898Y14813D01*
G01X214068Y14743D02*
X213996Y14794D01*
G01X214095Y14673D02*
X214068Y14743D01*
G01X212468D02*
X212441Y14673D01*
G01X212540Y14794D02*
X212468Y14743D01*
G01X212638Y14813D02*
X212540Y14794D01*
G01X214095Y15242D02*
G03X213898Y15439I-197J0D01*
G01X212638D02*
G03X212441Y15242I0J-197D01*
G01X209095D02*
G03X208898Y15439I-197J0D01*
G01X230355Y17599D02*
G03X229174Y18780I-1181J0D01*
G01X225670Y16221D02*
X229899Y18530D01*
G01X218268Y20748D02*
X217087Y19567D01*
G01X219764Y22520D02*
X223111Y25866D01*
G01X225670Y16221D02*
Y13858D01*
G01X223977Y16221D02*
Y13858D01*
G01X220630Y18780D02*
Y21929D01*
G01X217087Y19567D02*
Y14055D01*
G01X214095D02*
Y15241D01*
G01X213898Y14055D02*
Y15439D01*
G01X212638Y14055D02*
Y15439D01*
G01X212441Y15241D02*
Y14055D01*
G01X209095D02*
Y15241D01*
G01X208898Y14055D02*
Y15439D01*
G01X238859Y25866D02*
X223111D01*
G01X220630Y18780D02*
X229174D01*
G01X223977Y16221D02*
X225670D01*
G01X213898Y15439D02*
X212638D01*
G01X213898Y14813D02*
X212638D01*
G01X225670Y13858D02*
X223977D01*
G01X222008Y17524D02*
X223977Y16221D01*
G01X229174Y55787D02*
G03X230355Y56969I0J1181D01*
G01X223977Y58347D02*
X222008Y57043D01*
G01X230355Y62087D02*
Y56969D01*
G01X220630Y55787D02*
X229174D01*
G01X223111Y48701D02*
X238859D01*
G01X222008Y52638D02*
Y66417D01*
G01X220630Y52638D02*
Y55787D01*
G01X218268Y65236D02*
Y57362D01*
G01X217087Y58543D02*
X218268Y57362D01*
G01X223111Y48701D02*
X219764Y52047D01*
G01X229899Y56036D02*
X225670Y58347D01*
G01X208996Y59282D02*
X208898Y59301D01*
G01X209068Y59231D02*
X208996Y59282D01*
G01X209095Y59161D02*
X209068Y59231D01*
G01X213996Y59282D02*
X213898Y59301D01*
G01X214068Y59231D02*
X213996Y59282D01*
G01X214095Y59161D02*
X214068Y59231D01*
G01X212468D02*
X212441Y59161D01*
G01X212540Y59282D02*
X212468Y59231D01*
G01X212638Y59301D02*
X212540Y59282D01*
G01X214095Y59730D02*
G03X213898Y59927I-197J0D01*
G01X212638D02*
G03X212441Y59730I0J-197D01*
G01X209095D02*
G03X208898Y59927I-197J0D01*
G01X230355Y62087D02*
G03X229174Y63268I-1181J0D01*
G01X225670Y60709D02*
X229899Y63019D01*
G01X218268Y65236D02*
X217087Y64055D01*
G01X219764Y67008D02*
X223111Y70354D01*
G01X238859D02*
X223111D01*
G01X225670Y60709D02*
Y58347D01*
G01X223977Y60709D02*
Y58347D01*
G01X220630Y63268D02*
X229174D01*
G01X223977Y60709D02*
X225670D01*
G01X213898Y59927D02*
X212638D01*
G01X213898Y59301D02*
X212638D01*
G01X225670Y58347D02*
X223977D01*
G01X220630Y63268D02*
Y66417D01*
G01X217087Y64055D02*
Y58543D01*
G01X214095D02*
Y59730D01*
G01X213898Y58543D02*
Y59927D01*
G01X212638Y58543D02*
Y59927D01*
G01X212441Y59730D02*
Y58543D01*
G01X209095D02*
Y59730D01*
G01X208898Y58543D02*
Y59927D01*
G01X222008Y62012D02*
X223977Y60709D01*
G01X242717Y118898D02*
G03I-6496J0D01*
G01Y348032D02*
G03I-6496J0D01*
G01Y488583D02*
G03I-6496J0D01*
G01Y717717D02*
G03I-6496J0D01*
G01X238859Y4213D02*
G03X240827Y6181I0J1968D01*
G01D02*
Y23898D01*
G01D02*
G03X238859Y25866I-1968J0D01*
G01Y48701D02*
G03X240827Y50669I0J1968D01*
G01D02*
Y68386D01*
G01D02*
G03X238859Y70354I-1968J0D01*
G01X257559Y-390518D02*
Y-407840D01*
G01X269685Y97244D02*
G03X273622Y101181I0J3937D01*
G01Y252756D02*
Y101181D01*
G01X261811Y105118D02*
G03X265748Y109055I0J3937D01*
G01D02*
Y260630D01*
G01X273622Y165551D02*
G03X265748I-3937J0D01*
G01Y196260D02*
G03X273622I3937J0D01*
G01X269685Y264567D02*
G03X265748Y260630I0J-3937D01*
G01X277559Y256693D02*
G03X273622Y252756I0J-3937D01*
G01X342520Y264567D02*
X269685D01*
G01X254331Y361811D02*
G03Y369685I0J3937D01*
G01X261811Y474803D02*
G03X265748Y478740I0J3937D01*
G01D02*
Y630315D01*
G01X269685Y466929D02*
G03X273622Y470866I0J3937D01*
G01Y622441D02*
Y470866D01*
G01Y535236D02*
G03X265748I-3937J0D01*
G01Y565945D02*
G03X273622I3937J0D01*
G01X277559Y626378D02*
G03X273622Y622441I0J-3937D01*
G01X269685Y634252D02*
G03X265748Y630315I0J-3937D01*
G01X342520Y634252D02*
X269685D01*
G01X257559Y970112D02*
Y952789D01*
G01X309646Y13780D02*
G03I-6496J0D01*
G01Y242913D02*
G03I-6496J0D01*
G01X561024Y256693D02*
X277559D01*
G01X298544Y293425D02*
G03X300512Y291457I1968J0D01*
G01X298544Y311142D02*
Y293425D01*
G01X300512Y313110D02*
G03X298544Y311142I0J-1968D01*
G01Y337913D02*
G03X300512Y335945I1968J0D01*
G01X298544Y355630D02*
Y337913D01*
G01X300512Y357599D02*
G03X298544Y355630I1J-1969D01*
G01X285040Y369685D02*
G03Y361811I0J-3937D01*
G01X309646Y383465D02*
G03I-6496J0D01*
G01Y612599D02*
G03I-6496J0D01*
G01X561024Y626378D02*
X277559D01*
G01X310197Y306024D02*
G03X309016Y304843I0J-1181D01*
G01Y299725D02*
G03X310197Y298543I1181J-1D01*
G01X313701Y301102D02*
X309472Y298792D01*
G01X315394Y303465D02*
X317363Y304768D01*
G01X321103Y296575D02*
X322284Y297756D01*
G01X319607Y294803D02*
X316260Y291457D01*
G01X300512D02*
X316260D01*
G01X309016Y299725D02*
Y304843D01*
G01X313701Y301102D02*
Y303465D01*
G01X315394Y301102D02*
Y303465D01*
G01X395946Y294803D02*
X319607D01*
G01X317363Y295394D02*
X395788D01*
G01X456103Y296575D02*
X321103D01*
G01X318740Y298543D02*
X310197D01*
G01X315394Y301102D02*
X313701D01*
G01Y303465D02*
X315394D01*
G01X321103Y304449D02*
X397559D01*
G01X318740Y306024D02*
X310197D01*
G01X317363Y309173D02*
Y295394D01*
G01X318740Y298543D02*
Y295394D01*
G01Y309173D02*
Y306024D01*
G01X321103Y296575D02*
Y304449D01*
G01X322284Y303268D02*
X321103Y304449D01*
G01X317363Y299799D02*
X315394Y301102D01*
G01X309472Y305775D02*
X313701Y303465D01*
G01X459843Y309173D02*
X317363D01*
G01X319607Y309764D02*
X457599D01*
G01X316260Y313110D02*
X300512D01*
G01X316260D02*
X319607Y309764D01*
G01X310197Y350512D02*
G03X309016Y349331I0J-1181D01*
G01Y344213D02*
G03X310197Y343032I1181J0D01*
G01X313701Y345591D02*
X309472Y343280D01*
G01X315394Y347953D02*
X317363Y349256D01*
G01X321103Y341063D02*
X322284Y342244D01*
G01X319607Y339291D02*
X316260Y335945D01*
G01X309016Y344213D02*
Y349331D01*
G01X313701Y345591D02*
Y347953D01*
G01X315394Y345591D02*
Y347953D01*
G01X317363Y353662D02*
Y339882D01*
G01X318740Y343032D02*
Y339882D01*
G01Y353662D02*
Y350512D01*
G01X321103Y341063D02*
Y348937D01*
G01X300512Y335945D02*
X316260D01*
G01X395946Y339291D02*
X319607D01*
G01X317363Y339882D02*
X395788D01*
G01X456103Y341063D02*
X321103D01*
G01X318740Y343032D02*
X310197D01*
G01X315394Y345591D02*
X313701D01*
G01Y347953D02*
X315394D01*
G01X321103Y348937D02*
X397559D01*
G01X318740Y350512D02*
X310197D01*
G01X322284Y347756D02*
X321103Y348937D01*
G01X317363Y344287D02*
X315394Y345591D01*
G01X309472Y350263D02*
X313701Y347953D01*
G01X459843Y353662D02*
X317363D01*
G01X319607Y354252D02*
X457599D01*
G01X316260Y357599D02*
X319607Y354252D01*
G01X316260Y357599D02*
X300512D01*
G01X342520Y264567D02*
G03X344488Y266536I0J1968D01*
G01X340374Y302529D02*
X340473Y302510D01*
G01X340302Y302580D02*
X340374Y302529D01*
G01X340276Y302650D02*
X340302Y302580D01*
G01X335374Y302529D02*
X335473Y302510D01*
G01X335302Y302580D02*
X335374Y302529D01*
G01X335276Y302650D02*
X335302Y302580D01*
G01X330374Y302529D02*
X330473Y302510D01*
G01X330302Y302580D02*
X330374Y302529D01*
G01X330276Y302650D02*
X330302Y302580D01*
G01X325374Y302529D02*
X325473Y302510D01*
G01X325302Y302580D02*
X325374Y302529D01*
G01X325276Y302650D02*
X325302Y302580D01*
G01X326903D02*
X326929Y302650D01*
G01X326831Y302529D02*
X326903Y302580D01*
G01X326733Y302510D02*
X326831Y302529D01*
G01X331903Y302580D02*
X331929Y302650D01*
G01X331831Y302529D02*
X331903Y302580D01*
G01X331733Y302510D02*
X331831Y302529D01*
G01X336903Y302580D02*
X336929Y302650D01*
G01X336831Y302529D02*
X336903Y302580D01*
G01X336733Y302510D02*
X336831Y302529D01*
G01X341903Y302580D02*
X341929Y302650D01*
G01X341831Y302529D02*
X341903Y302580D01*
G01X341733Y302510D02*
X341831Y302529D01*
G01X335276Y302081D02*
G03X335473Y301884I197J0D01*
G01X325276Y302081D02*
G03X325473Y301884I197J0D01*
G01X326733D02*
G03X326929Y302081I-1J197D01*
G01X330276D02*
G03X330473Y301884I197J0D01*
G01X331733D02*
G03X331929Y302081I-1J197D01*
G01X340276D02*
G03X340473Y301884I197J0D01*
G01X341733D02*
G03X341929Y302081I-1J197D01*
G01X336733Y301884D02*
G03X336929Y302081I-1J197D01*
G01X454922Y297756D02*
X322284D01*
G01X340473Y301884D02*
X341733D01*
G01X335473D02*
X336733D01*
G01X330473D02*
X331733D01*
G01X325473D02*
X326733D01*
G01X340473Y302510D02*
X341733D01*
G01X335473D02*
X336733D01*
G01X330473D02*
X331733D01*
G01X325473D02*
X326733D01*
G01X322284Y303268D02*
X398740D01*
G01X322284Y297756D02*
Y303268D01*
G01X325276D02*
Y302081D01*
G01X325473Y303268D02*
Y301884D01*
G01X326733Y303268D02*
Y301884D01*
G01X326929Y302081D02*
Y303268D01*
G01X330276D02*
Y302081D01*
G01X330473Y303268D02*
Y301884D01*
G01X331733Y303268D02*
Y301884D01*
G01X331929Y302081D02*
Y303268D01*
G01X335276D02*
Y302081D01*
G01X335473Y303268D02*
Y301884D01*
G01X336733Y303268D02*
Y301884D01*
G01X336929Y302081D02*
Y303268D01*
G01X340276D02*
Y302081D01*
G01X340473Y303268D02*
Y301884D01*
G01X341733Y303268D02*
Y301884D01*
G01X341929Y302081D02*
Y303268D01*
G01X340374Y347017D02*
X340473Y346998D01*
G01X340302Y347068D02*
X340374Y347017D01*
G01X340276Y347138D02*
X340302Y347068D01*
G01X335374Y347017D02*
X335473Y346998D01*
G01X335302Y347068D02*
X335374Y347017D01*
G01X335276Y347138D02*
X335302Y347068D01*
G01X330374Y347017D02*
X330473Y346998D01*
G01X330302Y347068D02*
X330374Y347017D01*
G01X330276Y347138D02*
X330302Y347068D01*
G01X325374Y347017D02*
X325473Y346998D01*
G01X325302Y347068D02*
X325374Y347017D01*
G01X325276Y347138D02*
X325302Y347068D01*
G01X326903D02*
X326929Y347138D01*
G01X326831Y347017D02*
X326903Y347068D01*
G01X326733Y346998D02*
X326831Y347017D01*
G01X331903Y347068D02*
X331929Y347138D01*
G01X331831Y347017D02*
X331903Y347068D01*
G01X331733Y346998D02*
X331831Y347017D01*
G01X336903Y347068D02*
X336929Y347138D01*
G01X336831Y347017D02*
X336903Y347068D01*
G01X336733Y346998D02*
X336831Y347017D01*
G01X341903Y347068D02*
X341929Y347138D01*
G01X341831Y347017D02*
X341903Y347068D01*
G01X341733Y346998D02*
X341831Y347017D01*
G01X340276Y346569D02*
G03X340473Y346372I197J0D01*
G01X341733D02*
G03X341929Y346569I-1J197D01*
G01X335276D02*
G03X335473Y346372I197J0D01*
G01X336733D02*
G03X336929Y346569I-1J197D01*
G01X325276D02*
G03X325473Y346372I197J0D01*
G01X326733D02*
G03X326929Y346569I-1J197D01*
G01X330276D02*
G03X330473Y346372I197J0D01*
G01X331733D02*
G03X331929Y346569I-1J197D01*
G01X322284Y342244D02*
Y347756D01*
G01X325276D02*
Y346569D01*
G01X325473Y347756D02*
Y346372D01*
G01X326733Y347756D02*
Y346372D01*
G01X326929Y346569D02*
Y347756D01*
G01X330276D02*
Y346569D01*
G01X330473Y347756D02*
Y346372D01*
G01X331733Y347756D02*
Y346372D01*
G01X331929Y346569D02*
Y347756D01*
G01X335276D02*
Y346569D01*
G01X335473Y347756D02*
Y346372D01*
G01X336733Y347756D02*
Y346372D01*
G01X336929Y346569D02*
Y347756D01*
G01X340276D02*
Y346569D01*
G01X340473Y347756D02*
Y346372D01*
G01X341733Y347756D02*
Y346372D01*
G01X341929Y346569D02*
Y347756D01*
G01X454922Y342244D02*
X322284D01*
G01X340473Y346372D02*
X341733D01*
G01X335473D02*
X336733D01*
G01X330473D02*
X331733D01*
G01X325473D02*
X326733D01*
G01X340473Y346998D02*
X341733D01*
G01X335473D02*
X336733D01*
G01X330473D02*
X331733D01*
G01X325473D02*
X326733D01*
G01X322284Y347756D02*
X398740D01*
G01X342520Y634252D02*
G03X344488Y636221I0J1968D01*
G01X366674Y5056D02*
G03Y9056I0J2000D01*
G01D02*
G03Y5056I0J-2000D01*
G01X372974Y3156D02*
X360374D01*
G01Y10956D02*
X372974D01*
G01X360374Y3156D02*
Y10956D01*
G01X374074Y2056D02*
X359274D01*
G01Y12056D02*
X374074D01*
G01X359274Y2056D02*
Y12056D01*
G01X366674Y2056D02*
X381889Y-13159D01*
G01X373744Y-1479D02*
X366674Y2056D01*
G01D02*
X370209Y-5014D01*
G01X362225Y140433D02*
G03X363406Y139252I1181J0D01*
G01Y146732D02*
G03X362225Y145551I0J-1181D01*
G01X351752Y134134D02*
G03X353721Y132165I1969J0D01*
G01X362225Y140433D02*
Y145551D01*
G01X351752Y151850D02*
Y134134D01*
G01X362681Y146483D02*
X366910Y144173D01*
G01Y141811D02*
X362681Y139501D01*
G01X363406Y146732D02*
X371949D01*
G01X363406Y139252D02*
X371949D01*
G01X353721Y132165D02*
X369469D01*
G01X353721Y153819D02*
G03X351752Y151850I0J-1969D01*
G01X369469Y153819D02*
X353721D01*
G01X362225Y206181D02*
G03X363406Y205000I1181J0D01*
G01Y212480D02*
G03X362225Y211299I0J-1181D01*
G01X351752Y199882D02*
G03X353721Y197913I1969J0D01*
G01X362681Y212231D02*
X366910Y209921D01*
G01X363406Y212480D02*
X371949D01*
G01X363406Y205000D02*
X371949D01*
G01X353721Y197913D02*
X369469D01*
G01X362225Y206181D02*
Y211299D01*
G01X351752Y217599D02*
Y199882D01*
G01X366910Y207559D02*
X362681Y205249D01*
G01X353721Y219567D02*
G03X351752Y217599I0J-1969D01*
G01X369469Y219567D02*
X353721D01*
G01X346457Y270473D02*
G03X344488Y268504I0J-1969D01*
G01X346457Y270473D02*
X535433D01*
G01X344488Y268504D02*
Y266536D01*
G01X365374Y302529D02*
X365473Y302510D01*
G01X365302Y302580D02*
X365374Y302529D01*
G01X365276Y302650D02*
X365302Y302580D01*
G01X360374Y302529D02*
X360473Y302510D01*
G01X360302Y302580D02*
X360374Y302529D01*
G01X360276Y302650D02*
X360302Y302580D01*
G01X355374Y302529D02*
X355473Y302510D01*
G01X355302Y302580D02*
X355374Y302529D01*
G01X355276Y302650D02*
X355302Y302580D01*
G01X350374Y302529D02*
X350473Y302510D01*
G01X350302Y302580D02*
X350374Y302529D01*
G01X350276Y302650D02*
X350302Y302580D01*
G01X345374Y302529D02*
X345473Y302510D01*
G01X345302Y302580D02*
X345374Y302529D01*
G01X345276Y302650D02*
X345302Y302580D01*
G01X346903D02*
X346929Y302650D01*
G01X346831Y302529D02*
X346903Y302580D01*
G01X346733Y302510D02*
X346831Y302529D01*
G01X351903Y302580D02*
X351929Y302650D01*
G01X351831Y302529D02*
X351903Y302580D01*
G01X351733Y302510D02*
X351831Y302529D01*
G01X356903Y302580D02*
X356929Y302650D01*
G01X356831Y302529D02*
X356903Y302580D01*
G01X356733Y302510D02*
X356831Y302529D01*
G01X361903Y302580D02*
X361929Y302650D01*
G01X361831Y302529D02*
X361903Y302580D01*
G01X361733Y302510D02*
X361831Y302529D01*
G01X366831D02*
X366903Y302580D01*
G01X366733Y302510D02*
X366831Y302529D01*
G01X365276Y302081D02*
G03X365473Y301884I197J0D01*
G01X366733D02*
G03X366929Y302081I-1J197D01*
G01X360276D02*
G03X360473Y301884I197J0D01*
G01X361733D02*
G03X361929Y302081I-1J197D01*
G01X355276D02*
G03X355473Y301884I197J0D01*
G01X356733D02*
G03X356929Y302081I-1J197D01*
G01X350276D02*
G03X350473Y301884I197J0D01*
G01X351733D02*
G03X351929Y302081I-1J197D01*
G01X345276D02*
G03X345473Y301884I197J0D01*
G01X346733D02*
G03X346929Y302081I-1J197D01*
G01X365473Y301884D02*
X366733D01*
G01X360473D02*
X361733D01*
G01X355473D02*
X356733D01*
G01X350473D02*
X351733D01*
G01X345473D02*
X346733D01*
G01X365473Y302510D02*
X366733D01*
G01X360473D02*
X361733D01*
G01X355473D02*
X356733D01*
G01X350473D02*
X351733D01*
G01X345473D02*
X346733D01*
G01X345276Y303268D02*
Y302081D01*
G01X345473Y303268D02*
Y301884D01*
G01X346733Y303268D02*
Y301884D01*
G01X346929Y302081D02*
Y303268D01*
G01X350276D02*
Y302081D01*
G01X350473Y303268D02*
Y301884D01*
G01X351733Y303268D02*
Y301884D01*
G01X351929Y302081D02*
Y303268D01*
G01X355276D02*
Y302081D01*
G01X355473Y303268D02*
Y301884D01*
G01X356733Y303268D02*
Y301884D01*
G01X356929Y302081D02*
Y303268D01*
G01X360276D02*
Y302081D01*
G01X360473Y303268D02*
Y301884D01*
G01X361733Y303268D02*
Y301884D01*
G01X361929Y302081D02*
Y303268D01*
G01X365276D02*
Y302081D01*
G01X365473Y303268D02*
Y301884D01*
G01X366733Y303268D02*
Y301884D01*
G01X350394Y320473D02*
G03X348426Y318504I0J-1968D01*
G01Y316536D02*
G03X350394Y314567I1968J-1D01*
G01D02*
X456693D01*
G01Y320473D02*
X350394D01*
G01X348426Y318504D02*
Y316536D01*
G01X365374Y347017D02*
X365473Y346998D01*
G01X365302Y347068D02*
X365374Y347017D01*
G01X365276Y347138D02*
X365302Y347068D01*
G01X360374Y347017D02*
X360473Y346998D01*
G01X360302Y347068D02*
X360374Y347017D01*
G01X360276Y347138D02*
X360302Y347068D01*
G01X355374Y347017D02*
X355473Y346998D01*
G01X355302Y347068D02*
X355374Y347017D01*
G01X355276Y347138D02*
X355302Y347068D01*
G01X350374Y347017D02*
X350473Y346998D01*
G01X350302Y347068D02*
X350374Y347017D01*
G01X350276Y347138D02*
X350302Y347068D01*
G01X345374Y347017D02*
X345473Y346998D01*
G01X345302Y347068D02*
X345374Y347017D01*
G01X345276Y347138D02*
X345302Y347068D01*
G01X346903D02*
X346929Y347138D01*
G01X346831Y347017D02*
X346903Y347068D01*
G01X346733Y346998D02*
X346831Y347017D01*
G01X351903Y347068D02*
X351929Y347138D01*
G01X351831Y347017D02*
X351903Y347068D01*
G01X351733Y346998D02*
X351831Y347017D01*
G01X356903Y347068D02*
X356929Y347138D01*
G01X356831Y347017D02*
X356903Y347068D01*
G01X356733Y346998D02*
X356831Y347017D01*
G01X361903Y347068D02*
X361929Y347138D01*
G01X361831Y347017D02*
X361903Y347068D01*
G01X361733Y346998D02*
X361831Y347017D01*
G01X366831D02*
X366903Y347068D01*
G01X366733Y346998D02*
X366831Y347017D01*
G01X350276Y346569D02*
G03X350473Y346372I197J0D01*
G01X345276Y346569D02*
G03X345473Y346372I197J0D01*
G01X346733D02*
G03X346929Y346569I-1J197D01*
G01X365276D02*
G03X365473Y346372I197J0D01*
G01X366733D02*
G03X366929Y346569I-1J197D01*
G01X360276D02*
G03X360473Y346372I197J0D01*
G01X361733D02*
G03X361929Y346569I-1J197D01*
G01X355276D02*
G03X355473Y346372I197J0D01*
G01X356733D02*
G03X356929Y346569I-1J197D01*
G01X351733Y346372D02*
G03X351929Y346569I-1J197D01*
G01X345276Y347756D02*
Y346569D01*
G01X345473Y347756D02*
Y346372D01*
G01X346733Y347756D02*
Y346372D01*
G01X346929Y346569D02*
Y347756D01*
G01X350276D02*
Y346569D01*
G01X350473Y347756D02*
Y346372D01*
G01X351733Y347756D02*
Y346372D01*
G01X351929Y346569D02*
Y347756D01*
G01X355276D02*
Y346569D01*
G01X355473Y347756D02*
Y346372D01*
G01X356733Y347756D02*
Y346372D01*
G01X356929Y346569D02*
Y347756D01*
G01X365473Y346372D02*
X366733D01*
G01X360473D02*
X361733D01*
G01X355473D02*
X356733D01*
G01X350473D02*
X351733D01*
G01X345473D02*
X346733D01*
G01X365473Y346998D02*
X366733D01*
G01X360473D02*
X361733D01*
G01X355473D02*
X356733D01*
G01X350473D02*
X351733D01*
G01X345473D02*
X346733D01*
G01X360276Y347756D02*
Y346569D01*
G01X360473Y347756D02*
Y346372D01*
G01X361733Y347756D02*
Y346372D01*
G01X361929Y346569D02*
Y347756D01*
G01X365276D02*
Y346569D01*
G01X365473Y347756D02*
Y346372D01*
G01X366733Y347756D02*
Y346372D01*
G01X366674Y374741D02*
G03Y378741I0J2000D01*
G01D02*
G03Y374741I0J-2000D01*
G01X372974Y372841D02*
X360374D01*
G01D02*
Y380641D01*
G01X374074Y371741D02*
X359274D01*
G01D02*
Y381741D01*
G01X360374Y380641D02*
X372974D01*
G01X359274Y381741D02*
X374074D01*
G01X346457Y640158D02*
G03X344488Y638189I0J-1969D01*
G01X346457Y640158D02*
X535433D01*
G01X344488Y638189D02*
Y636221D01*
G01X350394Y690158D02*
G03X348426Y688189I0J-1968D01*
G01Y686221D02*
G03X350394Y684252I1968J-1D01*
G01D02*
X456693D01*
G01Y690158D02*
X350394D01*
G01X348426Y688189D02*
Y686221D01*
G01X381889Y-13159D02*
X418089D01*
G01X383859Y1969D02*
G03X385827Y0I1968J-1D01*
G01D02*
X523622D01*
G01X383859Y1969D02*
Y32677D01*
G01X372974Y10956D02*
Y3156D01*
G01X374074Y12056D02*
Y2056D01*
G01X370209Y-5014D02*
X373744Y-1479D01*
G01X372048Y0D02*
G03X375985Y3937I0J3937D01*
G01D02*
Y94488D01*
G01X383859Y32677D02*
G03X375985I-3937J0D01*
G01X383859Y57874D02*
Y90551D01*
G01X375985Y57874D02*
G03X383859I3937J0D01*
G01X458071Y90551D02*
X383859D01*
G01X379922Y98425D02*
G03X375985Y94488I0J-3937D01*
G01X462008Y98425D02*
X379922D01*
G01X388511Y142696D02*
X388485Y142626D01*
G01X388583Y142747D02*
X388511Y142696D01*
G01X388681Y142765D02*
X388583Y142747D01*
G01X383511Y142696D02*
X383485Y142626D01*
G01X383583Y142747D02*
X383511Y142696D01*
G01X383681Y142765D02*
X383583Y142747D01*
G01X378511Y142696D02*
X378485Y142626D01*
G01X378583Y142747D02*
X378511Y142696D01*
G01X378681Y142765D02*
X378583Y142747D01*
G01X380040D02*
X379941Y142765D01*
G01X380112Y142696D02*
X380040Y142747D01*
G01X380138Y142626D02*
X380112Y142696D01*
G01X385040Y142747D02*
X384941Y142765D01*
G01X385112Y142696D02*
X385040Y142747D01*
G01X385138Y142626D02*
X385112Y142696D01*
G01X380138Y143195D02*
G03X379941Y143392I-197J0D01*
G01X378681D02*
G03X378485Y143195I1J-197D01*
G01X385138D02*
G03X384941Y143392I-197J0D01*
G01X383681D02*
G03X383485Y143195I1J-197D01*
G01X388681Y143392D02*
G03X388485Y143195I1J-197D01*
G01X388681Y142008D02*
Y143392D01*
G01X388485Y143194D02*
Y142008D01*
G01X385138D02*
Y143194D01*
G01X384941Y142008D02*
Y143392D01*
G01X383681Y142008D02*
Y143392D01*
G01X383485Y143194D02*
Y142008D01*
G01X380138D02*
Y143194D01*
G01X379941Y142008D02*
Y143392D01*
G01X378681Y142008D02*
Y143392D01*
G01X378485Y143194D02*
Y142008D01*
G01X375492D02*
Y147520D01*
G01X374311Y140827D02*
Y148701D01*
G01X371949Y139252D02*
Y136102D01*
G01Y149882D02*
Y146732D01*
G01X370571Y136102D02*
Y149882D01*
G01X368603Y141811D02*
Y144173D01*
G01X375492Y147520D02*
X374311Y148701D01*
G01X366910Y141811D02*
Y144173D01*
G01X370571Y140507D02*
X368603Y141811D01*
G01X372815Y135512D02*
X369469Y132165D01*
G01X375492Y142008D02*
X374311Y140827D01*
G01X368603Y144173D02*
X370571Y145477D01*
G01X374311Y148701D02*
X509311D01*
G01X375492Y147520D02*
X508130D01*
G01X366910Y144173D02*
X368603D01*
G01X379941Y143392D02*
X378681D01*
G01X384941D02*
X383681D01*
G01X389941D02*
X388681D01*
G01X379941Y142765D02*
X378681D01*
G01X384941D02*
X383681D01*
G01X389941D02*
X388681D01*
G01X411949Y142008D02*
X375492D01*
G01X368603Y141811D02*
X366910D01*
G01X410768Y140827D02*
X374311D01*
G01X370571Y136102D02*
X513051D01*
G01X510807Y135512D02*
X372815D01*
G01X375985Y166334D02*
G03X377953Y164365I1969J0D01*
G01X375985Y180113D02*
Y166334D01*
G01X369469Y153819D02*
X372815Y150473D01*
G01X377953Y164365D02*
X484252D01*
G01X372815Y150473D02*
X409155D01*
G01X370571Y149882D02*
X408996D01*
G01X377953Y182082D02*
G03X375985Y180113I0J-1968D01*
G01X484252Y182082D02*
X377953D01*
G01X388511Y208444D02*
X388485Y208374D01*
G01X388583Y208495D02*
X388511Y208444D01*
G01X388681Y208513D02*
X388583Y208495D01*
G01X383511Y208444D02*
X383485Y208374D01*
G01X383583Y208495D02*
X383511Y208444D01*
G01X383681Y208513D02*
X383583Y208495D01*
G01X378511Y208444D02*
X378485Y208374D01*
G01X378583Y208495D02*
X378511Y208444D01*
G01X378681Y208513D02*
X378583Y208495D01*
G01X380040D02*
X379941Y208513D01*
G01X380112Y208444D02*
X380040Y208495D01*
G01X380138Y208374D02*
X380112Y208444D01*
G01X385040Y208495D02*
X384941Y208513D01*
G01X385112Y208444D02*
X385040Y208495D01*
G01X385138Y208374D02*
X385112Y208444D01*
G01X380138Y208943D02*
G03X379941Y209140I-197J0D01*
G01X378681D02*
G03X378485Y208943I1J-197D01*
G01X385138D02*
G03X384941Y209140I-197J0D01*
G01X383681D02*
G03X383485Y208943I1J-197D01*
G01X388681Y209140D02*
G03X388485Y208943I1J-197D01*
G01X369469Y219567D02*
X372815Y216221D01*
G01X375492Y213268D02*
X374311Y214449D01*
G01X370571Y206255D02*
X368603Y207559D01*
G01X388681Y207756D02*
Y209140D01*
G01X372815Y216221D02*
X409155D01*
G01X370571Y215630D02*
X408996D01*
G01X374311Y214449D02*
X509311D01*
G01X388485Y208942D02*
Y207756D01*
G01X385138D02*
Y208942D01*
G01X384941Y207756D02*
Y209140D01*
G01X383681Y207756D02*
Y209140D01*
G01X383485Y208942D02*
Y207756D01*
G01X380138D02*
Y208942D01*
G01X379941Y207756D02*
Y209140D01*
G01X378681Y207756D02*
Y209140D01*
G01X378485Y208942D02*
Y207756D01*
G01X375492D02*
Y213268D01*
G01X374311Y206575D02*
Y214449D01*
G01X371949Y205000D02*
Y201850D01*
G01Y215630D02*
Y212480D01*
G01X370571Y201850D02*
Y215630D01*
G01X368603Y207559D02*
Y209921D01*
G01X375492Y213268D02*
X508130D01*
G01X366910Y209921D02*
X368603D01*
G01X379941Y209140D02*
X378681D01*
G01X384941D02*
X383681D01*
G01X389941D02*
X388681D01*
G01X379941Y208513D02*
X378681D01*
G01X384941D02*
X383681D01*
G01X389941D02*
X388681D01*
G01X411949Y207756D02*
X375492D01*
G01X368603Y207559D02*
X366910D01*
G01X410768Y206575D02*
X374311D01*
G01X370571Y201850D02*
X513051D01*
G01X510807Y201260D02*
X372815D01*
G01X366910Y207559D02*
Y209921D01*
G01X372815Y201260D02*
X369469Y197913D01*
G01X375492Y207756D02*
X374311Y206575D01*
G01X368603Y209921D02*
X370571Y211225D01*
G01X385374Y302529D02*
X385473Y302510D01*
G01X385302Y302580D02*
X385374Y302529D01*
G01X385276Y302650D02*
X385302Y302580D01*
G01X380374Y302529D02*
X380473Y302510D01*
G01X380302Y302580D02*
X380374Y302529D01*
G01X380276Y302650D02*
X380302Y302580D01*
G01X375374Y302529D02*
X375473Y302510D01*
G01X375302Y302580D02*
X375374Y302529D01*
G01X375276Y302650D02*
X375302Y302580D01*
G01X370374Y302529D02*
X370473Y302510D01*
G01X370302Y302580D02*
X370374Y302529D01*
G01X370276Y302650D02*
X370302Y302580D01*
G01X366903D02*
X366929Y302650D01*
G01X371903Y302580D02*
X371929Y302650D01*
G01X371831Y302529D02*
X371903Y302580D01*
G01X371733Y302510D02*
X371831Y302529D01*
G01X376903Y302580D02*
X376929Y302650D01*
G01X376831Y302529D02*
X376903Y302580D01*
G01X376733Y302510D02*
X376831Y302529D01*
G01X381903Y302580D02*
X381929Y302650D01*
G01X381831Y302529D02*
X381903Y302580D01*
G01X381733Y302510D02*
X381831Y302529D01*
G01X386903Y302580D02*
X386929Y302650D01*
G01X386831Y302529D02*
X386903Y302580D01*
G01X386733Y302510D02*
X386831Y302529D01*
G01X380276Y302081D02*
G03X380473Y301884I197J0D01*
G01X381733D02*
G03X381929Y302081I-1J197D01*
G01X385276D02*
G03X385473Y301884I197J0D01*
G01X386733D02*
G03X386929Y302081I-1J197D01*
G01X375276D02*
G03X375473Y301884I197J0D01*
G01X376733D02*
G03X376929Y302081I-1J197D01*
G01X370276D02*
G03X370473Y301884I197J0D01*
G01X371733D02*
G03X371929Y302081I-1J197D01*
G01X385473Y301884D02*
X386733D01*
G01X380473D02*
X381733D01*
G01X375473D02*
X376733D01*
G01X370473D02*
X371733D01*
G01X385473Y302510D02*
X386733D01*
G01X380473D02*
X381733D01*
G01X375473D02*
X376733D01*
G01X370473D02*
X371733D01*
G01X366929Y302081D02*
Y303268D01*
G01X370276D02*
Y302081D01*
G01X370473Y303268D02*
Y301884D01*
G01X371733Y303268D02*
Y301884D01*
G01X371929Y302081D02*
Y303268D01*
G01X375276D02*
Y302081D01*
G01X375473Y303268D02*
Y301884D01*
G01X376733Y303268D02*
Y301884D01*
G01X376929Y302081D02*
Y303268D01*
G01X380276D02*
Y302081D01*
G01X380473Y303268D02*
Y301884D01*
G01X381733Y303268D02*
Y301884D01*
G01X381929Y302081D02*
Y303268D01*
G01X385276D02*
Y302081D01*
G01X385473Y303268D02*
Y301884D01*
G01X386733Y303268D02*
Y301884D01*
G01X386929Y302081D02*
Y303268D01*
G01X385374Y347017D02*
X385473Y346998D01*
G01X385302Y347068D02*
X385374Y347017D01*
G01X385276Y347138D02*
X385302Y347068D01*
G01X380374Y347017D02*
X380473Y346998D01*
G01X380302Y347068D02*
X380374Y347017D01*
G01X380276Y347138D02*
X380302Y347068D01*
G01X375374Y347017D02*
X375473Y346998D01*
G01X375302Y347068D02*
X375374Y347017D01*
G01X375276Y347138D02*
X375302Y347068D01*
G01X370374Y347017D02*
X370473Y346998D01*
G01X370302Y347068D02*
X370374Y347017D01*
G01X370276Y347138D02*
X370302Y347068D01*
G01X366903D02*
X366929Y347138D01*
G01X371903Y347068D02*
X371929Y347138D01*
G01X371831Y347017D02*
X371903Y347068D01*
G01X371733Y346998D02*
X371831Y347017D01*
G01X376903Y347068D02*
X376929Y347138D01*
G01X376831Y347017D02*
X376903Y347068D01*
G01X376733Y346998D02*
X376831Y347017D01*
G01X381903Y347068D02*
X381929Y347138D01*
G01X381831Y347017D02*
X381903Y347068D01*
G01X381733Y346998D02*
X381831Y347017D01*
G01X386903Y347068D02*
X386929Y347138D01*
G01X386831Y347017D02*
X386903Y347068D01*
G01X386733Y346998D02*
X386831Y347017D01*
G01X380276Y346569D02*
G03X380473Y346372I197J0D01*
G01X381733D02*
G03X381929Y346569I-1J197D01*
G01X385276D02*
G03X385473Y346372I197J0D01*
G01X386733D02*
G03X386929Y346569I-1J197D01*
G01X375276D02*
G03X375473Y346372I197J0D01*
G01X376733D02*
G03X376929Y346569I-1J197D01*
G01X370276D02*
G03X370473Y346372I197J0D01*
G01X371733D02*
G03X371929Y346569I-1J197D01*
G01X385473Y346372D02*
X386733D01*
G01X380473D02*
X381733D01*
G01X375473D02*
X376733D01*
G01X370473D02*
X371733D01*
G01X385473Y346998D02*
X386733D01*
G01X380473D02*
X381733D01*
G01X375473D02*
X376733D01*
G01X370473D02*
X371733D01*
G01X366929Y346569D02*
Y347756D01*
G01X370276D02*
Y346569D01*
G01X370473Y347756D02*
Y346372D01*
G01X371733Y347756D02*
Y346372D01*
G01X371929Y346569D02*
Y347756D01*
G01X375276D02*
Y346569D01*
G01X375473Y347756D02*
Y346372D01*
G01X376733Y347756D02*
Y346372D01*
G01X376929Y346569D02*
Y347756D01*
G01X380276D02*
Y346569D01*
G01X380473Y347756D02*
Y346372D01*
G01X381733Y347756D02*
Y346372D01*
G01X381929Y346569D02*
Y347756D01*
G01X385276D02*
Y346569D01*
G01X385473Y347756D02*
Y346372D01*
G01X386733Y347756D02*
Y346372D01*
G01X386929Y346569D02*
Y347756D01*
G01X383859Y369685D02*
X465355D01*
G01X372974Y380641D02*
Y372841D01*
G01X374074Y381741D02*
Y371741D01*
G01X372048Y369685D02*
G03X375985Y373622I0J3937D01*
G01X383859Y369685D02*
Y402362D01*
G01X375985Y373622D02*
Y464173D01*
G01X383859Y402362D02*
G03X375985I-3937J0D01*
G01Y427559D02*
G03X383859I3937J0D01*
G01D02*
Y460236D01*
G01X379922Y468110D02*
G03X375985Y464173I0J-3937D01*
G01X458071Y460236D02*
X383859D01*
G01X462008Y468110D02*
X379922D01*
G01X375985Y536019D02*
G03X377953Y534050I1969J0D01*
G01D02*
X484252D01*
G01X377953Y551767D02*
G03X375985Y549799I0J-1968D01*
G01D02*
Y536019D01*
G01X484252Y551767D02*
X377953D01*
G01X400226Y76695D02*
G03I-4291J0D01*
G01X408511Y142696D02*
X408485Y142626D01*
G01X408583Y142747D02*
X408511Y142696D01*
G01X408681Y142765D02*
X408583Y142747D01*
G01X403511Y142696D02*
X403485Y142626D01*
G01X403583Y142747D02*
X403511Y142696D01*
G01X403681Y142765D02*
X403583Y142747D01*
G01X398511Y142696D02*
X398485Y142626D01*
G01X398583Y142747D02*
X398511Y142696D01*
G01X398681Y142765D02*
X398583Y142747D01*
G01X393511Y142696D02*
X393485Y142626D01*
G01X393583Y142747D02*
X393511Y142696D01*
G01X393681Y142765D02*
X393583Y142747D01*
G01X411759Y147005D02*
X411733Y147073D01*
G01X411831Y146954D02*
X411759Y147005D01*
G01X411929Y146936D02*
X411831Y146954D01*
G01X390040Y142747D02*
X389941Y142765D01*
G01X390112Y142696D02*
X390040Y142747D01*
G01X390138Y142626D02*
X390112Y142696D01*
G01X395040Y142747D02*
X394941Y142765D01*
G01X395112Y142696D02*
X395040Y142747D01*
G01X395138Y142626D02*
X395112Y142696D01*
G01X400040Y142747D02*
X399941Y142765D01*
G01X400112Y142696D02*
X400040Y142747D01*
G01X400138Y142626D02*
X400112Y142696D01*
G01X405040Y142747D02*
X404941Y142765D01*
G01X405112Y142696D02*
X405040Y142747D01*
G01X405138Y142626D02*
X405112Y142696D01*
G01X410040Y142747D02*
X409941Y142765D01*
G01X410112Y142696D02*
X410040Y142747D01*
G01X410138Y142626D02*
X410112Y142696D01*
G01X411733Y146476D02*
G03X411929Y146280I197J1D01*
G01X390138Y143195D02*
G03X389941Y143392I-197J0D01*
G01X395138Y143195D02*
G03X394941Y143392I-197J0D01*
G01X393681D02*
G03X393485Y143195I1J-197D01*
G01X400138D02*
G03X399941Y143392I-197J0D01*
G01X398681D02*
G03X398485Y143195I1J-197D01*
G01X405138D02*
G03X404941Y143392I-197J0D01*
G01X403681D02*
G03X403485Y143195I1J-197D01*
G01X410138D02*
G03X409941Y143392I-197J0D01*
G01X408681D02*
G03X408485Y143195I1J-197D01*
G01X411949Y138071D02*
Y142008D01*
G01X411929Y147323D02*
Y146280D01*
G01X411733Y147520D02*
Y146477D01*
G01X410768Y136890D02*
Y140827D01*
G01X410138Y142008D02*
Y143194D01*
G01X409941Y142008D02*
Y143392D01*
G01X408681Y142008D02*
Y143392D01*
G01X408485Y143194D02*
Y142008D01*
G01X405138D02*
Y143194D01*
G01X404941Y142008D02*
Y143392D01*
G01X403681Y142008D02*
Y143392D01*
G01X403485Y143194D02*
Y142008D01*
G01X400138D02*
Y143194D01*
G01X399941Y142008D02*
Y143392D01*
G01X398681Y142008D02*
Y143392D01*
G01X398485Y143194D02*
Y142008D01*
G01X395138D02*
Y143194D01*
G01X394941Y142008D02*
Y143392D01*
G01X393681Y142008D02*
Y143392D01*
G01X393485Y143194D02*
Y142008D01*
G01X390138D02*
Y143194D01*
G01X389941Y142008D02*
Y143392D01*
G01X411949Y138071D02*
X410768Y136890D01*
G01X411949Y142008D02*
X410768Y140827D01*
G01X411733Y147323D02*
X411929D01*
G01Y146936D02*
X412796D01*
G01X411929Y146280D02*
X412796D01*
G01X394941Y143392D02*
X393681D01*
G01X399941D02*
X398681D01*
G01X404941D02*
X403681D01*
G01X409941D02*
X408681D01*
G01X394941Y142765D02*
X393681D01*
G01X399941D02*
X398681D01*
G01X404941D02*
X403681D01*
G01X409941D02*
X408681D01*
G01X431674Y138071D02*
X411949D01*
G01X432855Y136890D02*
X410768D01*
G01X408996Y149882D02*
X410051Y153819D01*
G01X433572D02*
X410051D01*
G01X433941Y152441D02*
X409682D01*
G01X408511Y208444D02*
X408485Y208374D01*
G01X408583Y208495D02*
X408511Y208444D01*
G01X408681Y208513D02*
X408583Y208495D01*
G01X403511Y208444D02*
X403485Y208374D01*
G01X403583Y208495D02*
X403511Y208444D01*
G01X403681Y208513D02*
X403583Y208495D01*
G01X398511Y208444D02*
X398485Y208374D01*
G01X398583Y208495D02*
X398511Y208444D01*
G01X398681Y208513D02*
X398583Y208495D01*
G01X393511Y208444D02*
X393485Y208374D01*
G01X393583Y208495D02*
X393511Y208444D01*
G01X393681Y208513D02*
X393583Y208495D01*
G01X411759Y212753D02*
X411733Y212821D01*
G01X411831Y212702D02*
X411759Y212753D01*
G01X411929Y212684D02*
X411831Y212702D01*
G01X390040Y208495D02*
X389941Y208513D01*
G01X390112Y208444D02*
X390040Y208495D01*
G01X390138Y208374D02*
X390112Y208444D01*
G01X395040Y208495D02*
X394941Y208513D01*
G01X395112Y208444D02*
X395040Y208495D01*
G01X395138Y208374D02*
X395112Y208444D01*
G01X400040Y208495D02*
X399941Y208513D01*
G01X400112Y208444D02*
X400040Y208495D01*
G01X400138Y208374D02*
X400112Y208444D01*
G01X405040Y208495D02*
X404941Y208513D01*
G01X405112Y208444D02*
X405040Y208495D01*
G01X405138Y208374D02*
X405112Y208444D01*
G01X410040Y208495D02*
X409941Y208513D01*
G01X410112Y208444D02*
X410040Y208495D01*
G01X410138Y208374D02*
X410112Y208444D01*
G01X411733Y212225D02*
G03X411929Y212028I197J0D01*
G01X390138Y208943D02*
G03X389941Y209140I-197J0D01*
G01X395138Y208943D02*
G03X394941Y209140I-197J0D01*
G01X393681D02*
G03X393485Y208943I1J-197D01*
G01X400138D02*
G03X399941Y209140I-197J0D01*
G01X398681D02*
G03X398485Y208943I1J-197D01*
G01X405138D02*
G03X404941Y209140I-197J0D01*
G01X403681D02*
G03X403485Y208943I1J-197D01*
G01X410138D02*
G03X409941Y209140I-197J0D01*
G01X408681D02*
G03X408485Y208943I1J-197D01*
G01X411949Y203819D02*
Y207756D01*
G01X411929Y213071D02*
Y212028D01*
G01X411733Y213268D02*
Y212225D01*
G01X410768Y202638D02*
Y206575D01*
G01X410138Y207756D02*
Y208942D01*
G01X409941Y207756D02*
Y209140D01*
G01X408681Y207756D02*
Y209140D01*
G01X408485Y208942D02*
Y207756D01*
G01X405138D02*
Y208942D01*
G01X404941Y207756D02*
Y209140D01*
G01X403681Y207756D02*
Y209140D01*
G01X403485Y208942D02*
Y207756D01*
G01X400138D02*
Y208942D01*
G01X399941Y207756D02*
Y209140D01*
G01X398681Y207756D02*
Y209140D01*
G01X398485Y208942D02*
Y207756D01*
G01X395138D02*
Y208942D01*
G01X394941Y207756D02*
Y209140D01*
G01X393681Y207756D02*
Y209140D01*
G01X393485Y208942D02*
Y207756D01*
G01X390138D02*
Y208942D01*
G01X389941Y207756D02*
Y209140D01*
G01X408996Y215630D02*
X410051Y219567D01*
G01X411733Y213071D02*
X411929D01*
G01Y212684D02*
X412796D01*
G01X411929Y212028D02*
X412796D01*
G01X394941Y209140D02*
X393681D01*
G01X399941D02*
X398681D01*
G01X404941D02*
X403681D01*
G01X409941D02*
X408681D01*
G01X394941Y208513D02*
X393681D01*
G01X399941D02*
X398681D01*
G01X404941D02*
X403681D01*
G01X409941D02*
X408681D01*
G01X431674Y203819D02*
X411949D01*
G01X432855Y202638D02*
X410768D01*
G01X411949Y203819D02*
X410768Y202638D01*
G01X411949Y207756D02*
X410768Y206575D01*
G01X433572Y219567D02*
X410051D01*
G01X433941Y218189D02*
X409682D01*
G01X395374Y302529D02*
X395473Y302510D01*
G01X395302Y302580D02*
X395374Y302529D01*
G01X395276Y302650D02*
X395302Y302580D01*
G01X390374Y302529D02*
X390473Y302510D01*
G01X390302Y302580D02*
X390374Y302529D01*
G01X390276Y302650D02*
X390302Y302580D01*
G01X411221Y298321D02*
X411319Y298339D01*
G01X411149Y298271D02*
X411221Y298321D01*
G01X411122Y298202D02*
X411149Y298271D01*
G01X408071Y298321D02*
X408170Y298339D01*
G01X407999Y298271D02*
X408071Y298321D01*
G01X407973Y298202D02*
X407999Y298271D01*
G01X404922Y298321D02*
X405020Y298339D01*
G01X404850Y298271D02*
X404922Y298321D01*
G01X404823Y298202D02*
X404850Y298271D01*
G01X401772Y298321D02*
X401870Y298339D01*
G01X401700Y298271D02*
X401772Y298321D01*
G01X401674Y298202D02*
X401700Y298271D01*
G01X398622Y298321D02*
X398721Y298339D01*
G01X398550Y298271D02*
X398622Y298321D01*
G01X398524Y298202D02*
X398550Y298271D01*
G01X412185Y298339D02*
X412284Y298321D01*
G01X409206Y298271D02*
X409233Y298202D01*
G01X409134Y298321D02*
X409206Y298271D01*
G01X409036Y298339D02*
X409134Y298321D01*
G01X406057Y298271D02*
X406083Y298202D01*
G01X405985Y298321D02*
X406057Y298271D01*
G01X405886Y298339D02*
X405985Y298321D01*
G01X402907Y298271D02*
X402933Y298202D01*
G01X402835Y298321D02*
X402907Y298271D01*
G01X402737Y298339D02*
X402835Y298321D01*
G01X399757Y298271D02*
X399784Y298202D01*
G01X399685Y298321D02*
X399757Y298271D01*
G01X399587Y298339D02*
X399685Y298321D01*
G01X391903Y302580D02*
X391929Y302650D01*
G01X391831Y302529D02*
X391903Y302580D01*
G01X391733Y302510D02*
X391831Y302529D01*
G01X396903Y302580D02*
X396929Y302650D01*
G01X396831Y302529D02*
X396903Y302580D01*
G01X396733Y302510D02*
X396831Y302529D01*
G01X399784Y298799D02*
G03X399587Y298996I-197J0D01*
G01X398721D02*
G03X398524Y298799I0J-197D01*
G01X401870Y298996D02*
G03X401674Y298799I1J-197D01*
G01X395276Y302081D02*
G03X395473Y301884I197J0D01*
G01X396733D02*
G03X396929Y302081I-1J197D01*
G01X390276D02*
G03X390473Y301884I197J0D01*
G01X391733D02*
G03X391929Y302081I-1J197D01*
G01X402933Y298799D02*
G03X402737Y298996I-197J0D01*
G01X406083Y298799D02*
G03X405886Y298996I-197J0D01*
G01X405020D02*
G03X404823Y298799I0J-197D01*
G01X409233D02*
G03X409036Y298996I-197J0D01*
G01X408170D02*
G03X407973Y298799I0J-197D01*
G01X411319Y298996D02*
G03X411122Y298799I0J-197D01*
G01X396843Y291457D02*
X420363D01*
G01X396474Y292835D02*
X420732D01*
G01X398721Y297952D02*
X398524D01*
G01X399784D02*
X399587D01*
G01X401870D02*
X401674D01*
G01X402933D02*
X402737D01*
G01X405020D02*
X404823D01*
G01X406083D02*
X405886D01*
G01X408170D02*
X407973D01*
G01X409233D02*
X409036D01*
G01X411319D02*
X411122D01*
G01X399587Y298339D02*
X398721D01*
G01X402737D02*
X401870D01*
G01X405886D02*
X405020D01*
G01X409036D02*
X408170D01*
G01X412185D02*
X411319D01*
G01X399587Y298996D02*
X398721D01*
G01X402737D02*
X401870D01*
G01X405886D02*
X405020D01*
G01X409036D02*
X408170D01*
G01X412185D02*
X411319D01*
G01X395473Y301884D02*
X396733D01*
G01X390473D02*
X391733D01*
G01X395473Y302510D02*
X396733D01*
G01X390473D02*
X391733D01*
G01X398740Y307205D02*
X418465D01*
G01X390276Y303268D02*
Y302081D01*
G01X390473Y303268D02*
Y301884D01*
G01X391733Y303268D02*
Y301884D01*
G01X391929Y302081D02*
Y303268D01*
G01X395276D02*
Y302081D01*
G01X395473Y303268D02*
Y301884D01*
G01X396733Y303268D02*
Y301884D01*
G01X396929Y302081D02*
Y303268D01*
G01X397559Y304449D02*
Y308386D01*
G01X398524Y298799D02*
Y297756D01*
G01X398721Y298996D02*
Y297952D01*
G01X398740Y303268D02*
Y307205D01*
G01X395788Y295394D02*
X396843Y291457D01*
G01X398740Y303268D02*
X397559Y304449D01*
G01X398740Y307205D02*
X397559Y308386D01*
G01X399587Y297952D02*
Y298996D01*
G01X399784Y297756D02*
Y298799D01*
G01X401674D02*
Y297756D01*
G01X401870Y298996D02*
Y297952D01*
G01X402737D02*
Y298996D01*
G01X402933Y297756D02*
Y298799D01*
G01X404823D02*
Y297756D01*
G01X405020Y298996D02*
Y297952D01*
G01X405886D02*
Y298996D01*
G01X406083Y297756D02*
Y298799D01*
G01X407973D02*
Y297756D01*
G01X408170Y298996D02*
Y297952D01*
G01X409036D02*
Y298996D01*
G01X409233Y297756D02*
Y298799D01*
G01X411122D02*
Y297756D01*
G01X411319Y298996D02*
Y297952D01*
G01X397559Y308386D02*
X419646D01*
G01X395374Y347017D02*
X395473Y346998D01*
G01X395302Y347068D02*
X395374Y347017D01*
G01X395276Y347138D02*
X395302Y347068D01*
G01X390374Y347017D02*
X390473Y346998D01*
G01X390302Y347068D02*
X390374Y347017D01*
G01X390276Y347138D02*
X390302Y347068D01*
G01X412185Y342828D02*
X412284Y342809D01*
G01X409206Y342759D02*
X409233Y342690D01*
G01X409134Y342809D02*
X409206Y342759D01*
G01X409036Y342828D02*
X409134Y342809D01*
G01X406057Y342759D02*
X406083Y342690D01*
G01X405985Y342809D02*
X406057Y342759D01*
G01X405886Y342828D02*
X405985Y342809D01*
G01X402907Y342759D02*
X402933Y342690D01*
G01X402835Y342809D02*
X402907Y342759D01*
G01X402737Y342828D02*
X402835Y342809D01*
G01X399757Y342759D02*
X399784Y342690D01*
G01X399685Y342809D02*
X399757Y342759D01*
G01X399587Y342828D02*
X399685Y342809D01*
G01X411221D02*
X411319Y342828D01*
G01X411149Y342759D02*
X411221Y342809D01*
G01X411122Y342690D02*
X411149Y342759D01*
G01X408071Y342809D02*
X408170Y342828D01*
G01X407999Y342759D02*
X408071Y342809D01*
G01X407973Y342690D02*
X407999Y342759D01*
G01X404922Y342809D02*
X405020Y342828D01*
G01X404850Y342759D02*
X404922Y342809D01*
G01X404823Y342690D02*
X404850Y342759D01*
G01X401772Y342809D02*
X401870Y342828D01*
G01X401700Y342759D02*
X401772Y342809D01*
G01X401674Y342690D02*
X401700Y342759D01*
G01X398622Y342809D02*
X398721Y342828D01*
G01X398550Y342759D02*
X398622Y342809D01*
G01X398524Y342690D02*
X398550Y342759D01*
G01X391903Y347068D02*
X391929Y347138D01*
G01X391831Y347017D02*
X391903Y347068D01*
G01X391733Y346998D02*
X391831Y347017D01*
G01X396903Y347068D02*
X396929Y347138D01*
G01X396831Y347017D02*
X396903Y347068D01*
G01X396733Y346998D02*
X396831Y347017D01*
G01X399784Y343287D02*
G03X399587Y343484I-197J0D01*
G01X398721D02*
G03X398524Y343287I0J-197D01*
G01X401870Y343484D02*
G03X401674Y343287I1J-197D01*
G01X395276Y346569D02*
G03X395473Y346372I197J0D01*
G01X396733D02*
G03X396929Y346569I-1J197D01*
G01X390276D02*
G03X390473Y346372I197J0D01*
G01X391733D02*
G03X391929Y346569I-1J197D01*
G01X402933Y343287D02*
G03X402737Y343484I-197J0D01*
G01X406083Y343287D02*
G03X405886Y343484I-197J0D01*
G01X405020D02*
G03X404823Y343287I0J-197D01*
G01X409233D02*
G03X409036Y343484I-197J0D01*
G01X408170D02*
G03X407973Y343287I0J-197D01*
G01X411319Y343484D02*
G03X411122Y343287I0J-197D01*
G01X396843Y335945D02*
X420363D01*
G01X396474Y337323D02*
X420732D01*
G01X398721Y342441D02*
X398524D01*
G01X399784D02*
X399587D01*
G01X401870D02*
X401674D01*
G01X402933D02*
X402737D01*
G01X405020D02*
X404823D01*
G01X406083D02*
X405886D01*
G01X408170D02*
X407973D01*
G01X409233D02*
X409036D01*
G01X411319D02*
X411122D01*
G01X399587Y342828D02*
X398721D01*
G01X402737D02*
X401870D01*
G01X405886D02*
X405020D01*
G01X409036D02*
X408170D01*
G01X412185D02*
X411319D01*
G01X399587Y343484D02*
X398721D01*
G01X402737D02*
X401870D01*
G01X405886D02*
X405020D01*
G01X409036D02*
X408170D01*
G01X412185D02*
X411319D01*
G01X395473Y346372D02*
X396733D01*
G01X390473D02*
X391733D01*
G01X395473Y346998D02*
X396733D01*
G01X390473D02*
X391733D01*
G01X398740Y351693D02*
X418465D01*
G01X397559Y352874D02*
X419646D01*
G01X390276Y347756D02*
Y346569D01*
G01X390473Y347756D02*
Y346372D01*
G01X391733Y347756D02*
Y346372D01*
G01X391929Y346569D02*
Y347756D01*
G01X395276D02*
Y346569D01*
G01X395473Y347756D02*
Y346372D01*
G01X396733Y347756D02*
Y346372D01*
G01X396929Y346569D02*
Y347756D01*
G01X397559Y348937D02*
Y352874D01*
G01X398524Y343287D02*
Y342244D01*
G01X398721Y343484D02*
Y342441D01*
G01X398740Y347756D02*
Y351693D01*
G01X395788Y339882D02*
X396843Y335945D01*
G01X399587Y342441D02*
Y343484D01*
G01X399784Y342244D02*
Y343287D01*
G01X401674D02*
Y342244D01*
G01X401870Y343484D02*
Y342441D01*
G01X402737D02*
Y343484D01*
G01X402933Y342244D02*
Y343287D01*
G01X404823D02*
Y342244D01*
G01X405020Y343484D02*
Y342441D01*
G01X405886D02*
Y343484D01*
G01X406083Y342244D02*
Y343287D01*
G01X407973D02*
Y342244D01*
G01X408170Y343484D02*
Y342441D01*
G01X409036D02*
Y343484D01*
G01X409233Y342244D02*
Y343287D01*
G01X411122D02*
Y342244D01*
G01X411319Y343484D02*
Y342441D01*
G01X398740Y347756D02*
X397559Y348937D01*
G01X398740Y351693D02*
X397559Y352874D01*
G01X430787Y-390518D02*
Y-407840D01*
G01X433511Y142696D02*
X433485Y142626D01*
G01X433583Y142747D02*
X433511Y142696D01*
G01X433681Y142765D02*
X433583Y142747D01*
G01X414909Y147005D02*
X414882Y147073D01*
G01X414981Y146954D02*
X414909Y147005D01*
G01X415079Y146936D02*
X414981Y146954D01*
G01X418058Y147005D02*
X418032Y147073D01*
G01X418130Y146954D02*
X418058Y147005D01*
G01X418229Y146936D02*
X418130Y146954D01*
G01X421208Y147005D02*
X421181Y147073D01*
G01X421280Y146954D02*
X421208Y147005D01*
G01X421378Y146936D02*
X421280Y146954D01*
G01X424357Y147005D02*
X424331Y147073D01*
G01X424429Y146954D02*
X424357Y147005D01*
G01X424528Y146936D02*
X424429Y146954D01*
G01X427507Y147005D02*
X427481Y147073D01*
G01X427579Y146954D02*
X427507Y147005D01*
G01X427677Y146936D02*
X427579Y146954D01*
G01X430657Y147005D02*
X430630Y147073D01*
G01X430729Y146954D02*
X430657Y147005D01*
G01X430827Y146936D02*
X430729Y146954D01*
G01X412894D02*
X412796Y146936D01*
G01X412966Y147005D02*
X412894Y146954D01*
G01X412992Y147073D02*
X412966Y147005D01*
G01X416044Y146954D02*
X415945Y146936D01*
G01X416116Y147005D02*
X416044Y146954D01*
G01X416142Y147073D02*
X416116Y147005D01*
G01X419193Y146954D02*
X419095Y146936D01*
G01X419265Y147005D02*
X419193Y146954D01*
G01X419292Y147073D02*
X419265Y147005D01*
G01X422343Y146954D02*
X422244Y146936D01*
G01X422415Y147005D02*
X422343Y146954D01*
G01X422441Y147073D02*
X422415Y147005D01*
G01X425492Y146954D02*
X425394Y146936D01*
G01X425564Y147005D02*
X425492Y146954D01*
G01X425591Y147073D02*
X425564Y147005D01*
G01X428642Y146954D02*
X428544Y146936D01*
G01X428714Y147005D02*
X428642Y146954D01*
G01X428740Y147073D02*
X428714Y147005D01*
G01X431792Y146954D02*
X431693Y146936D01*
G01X431864Y147005D02*
X431792Y146954D01*
G01X431890Y147073D02*
X431864Y147005D01*
G01X433681Y143392D02*
G03X433485Y143195I1J-197D01*
G01X430630Y146476D02*
G03X430827Y146280I197J1D01*
G01X431693D02*
G03X431890Y146476I0J197D01*
G01X427481D02*
G03X427677Y146280I197J1D01*
G01X428544D02*
G03X428740Y146476I-1J197D01*
G01X424331D02*
G03X424528Y146280I197J1D01*
G01X425394D02*
G03X425591Y146476I0J197D01*
G01X421181D02*
G03X421378Y146280I197J1D01*
G01X422244D02*
G03X422441Y146476I0J197D01*
G01X418032D02*
G03X418229Y146280I197J1D01*
G01X419095D02*
G03X419292Y146476I0J197D01*
G01X414882D02*
G03X415079Y146280I197J1D01*
G01X415945D02*
G03X416142Y146476I0J197D01*
G01X412796Y146280D02*
G03X412992Y146476I-1J197D01*
G01X433681Y142008D02*
Y143392D01*
G01X433485Y143194D02*
Y142008D01*
G01X432855Y140827D02*
Y136890D01*
G01X431890Y146477D02*
Y147520D01*
G01X431693Y146280D02*
Y147323D01*
G01X431674Y142008D02*
Y138071D01*
G01X430827Y147323D02*
Y146280D01*
G01X430630Y147520D02*
Y146477D01*
G01X428740D02*
Y147520D01*
G01X428544Y146280D02*
Y147323D01*
G01X427677D02*
Y146280D01*
G01X427481Y147520D02*
Y146477D01*
G01X425591D02*
Y147520D01*
G01X425394Y146280D02*
Y147323D01*
G01X424528D02*
Y146280D01*
G01X424331Y147520D02*
Y146477D01*
G01X422441D02*
Y147520D01*
G01X422244Y146280D02*
Y147323D01*
G01X421378D02*
Y146280D01*
G01X421181Y147520D02*
Y146477D01*
G01X419292D02*
Y147520D01*
G01X419095Y146280D02*
Y147323D01*
G01X418229D02*
Y146280D01*
G01X418032Y147520D02*
Y146477D01*
G01X416142D02*
Y147520D01*
G01X415945Y146280D02*
Y147323D01*
G01X415079D02*
Y146280D01*
G01X414882Y147520D02*
Y146477D01*
G01X412992D02*
Y147520D01*
G01X412796Y146280D02*
Y147323D01*
G01X431674Y142008D02*
X432855Y140827D01*
G01X431674Y138071D02*
X432855Y136890D01*
G01X431693Y147323D02*
X431890D01*
G01X430630D02*
X430827D01*
G01X428544D02*
X428740D01*
G01X427481D02*
X427677D01*
G01X425394D02*
X425591D01*
G01X424331D02*
X424528D01*
G01X422244D02*
X422441D01*
G01X421181D02*
X421378D01*
G01X419095D02*
X419292D01*
G01X418032D02*
X418229D01*
G01X415945D02*
X416142D01*
G01X414882D02*
X415079D01*
G01X412796D02*
X412992D01*
G01X430827Y146936D02*
X431693D01*
G01X427677D02*
X428544D01*
G01X424528D02*
X425394D01*
G01X421378D02*
X422244D01*
G01X418229D02*
X419095D01*
G01X415079D02*
X415945D01*
G01X430827Y146280D02*
X431693D01*
G01X427677D02*
X428544D01*
G01X424528D02*
X425394D01*
G01X421378D02*
X422244D01*
G01X418229D02*
X419095D01*
G01X415079D02*
X415945D01*
G01X434941Y143392D02*
X433681D01*
G01X434941Y142765D02*
X433681D01*
G01X508130Y142008D02*
X431674D01*
G01X509311Y140827D02*
X432855D01*
G01X434626Y149882D02*
X433572Y153819D01*
G01X434468Y150473D02*
X510807D01*
G01X513051Y149882D02*
X434626D01*
G01X433511Y208444D02*
X433485Y208374D01*
G01X433583Y208495D02*
X433511Y208444D01*
G01X433681Y208513D02*
X433583Y208495D01*
G01X412894Y212702D02*
X412796Y212684D01*
G01X412966Y212753D02*
X412894Y212702D01*
G01X412992Y212821D02*
X412966Y212753D01*
G01X416044Y212702D02*
X415945Y212684D01*
G01X416116Y212753D02*
X416044Y212702D01*
G01X416142Y212821D02*
X416116Y212753D01*
G01X419193Y212702D02*
X419095Y212684D01*
G01X419265Y212753D02*
X419193Y212702D01*
G01X419292Y212821D02*
X419265Y212753D01*
G01X422343Y212702D02*
X422244Y212684D01*
G01X422415Y212753D02*
X422343Y212702D01*
G01X422441Y212821D02*
X422415Y212753D01*
G01X425492Y212702D02*
X425394Y212684D01*
G01X425564Y212753D02*
X425492Y212702D01*
G01X425591Y212821D02*
X425564Y212753D01*
G01X428642Y212702D02*
X428544Y212684D01*
G01X428714Y212753D02*
X428642Y212702D01*
G01X428740Y212821D02*
X428714Y212753D01*
G01X431792Y212702D02*
X431693Y212684D01*
G01X431864Y212753D02*
X431792Y212702D01*
G01X431890Y212821D02*
X431864Y212753D01*
G01X414909D02*
X414882Y212821D01*
G01X414981Y212702D02*
X414909Y212753D01*
G01X415079Y212684D02*
X414981Y212702D01*
G01X418058Y212753D02*
X418032Y212821D01*
G01X418130Y212702D02*
X418058Y212753D01*
G01X418229Y212684D02*
X418130Y212702D01*
G01X421208Y212753D02*
X421181Y212821D01*
G01X421280Y212702D02*
X421208Y212753D01*
G01X421378Y212684D02*
X421280Y212702D01*
G01X424357Y212753D02*
X424331Y212821D01*
G01X424429Y212702D02*
X424357Y212753D01*
G01X424528Y212684D02*
X424429Y212702D01*
G01X427507Y212753D02*
X427481Y212821D01*
G01X427579Y212702D02*
X427507Y212753D01*
G01X427677Y212684D02*
X427579Y212702D01*
G01X430657Y212753D02*
X430630Y212821D01*
G01X430729Y212702D02*
X430657Y212753D01*
G01X430827Y212684D02*
X430729Y212702D01*
G01X433681Y209140D02*
G03X433485Y208943I1J-197D01*
G01X430630Y212225D02*
G03X430827Y212028I197J0D01*
G01X431693D02*
G03X431890Y212225I0J197D01*
G01X427481D02*
G03X427677Y212028I197J0D01*
G01X428544D02*
G03X428740Y212225I-1J197D01*
G01X424331D02*
G03X424528Y212028I197J0D01*
G01X425394D02*
G03X425591Y212225I0J197D01*
G01X421181D02*
G03X421378Y212028I197J0D01*
G01X422244D02*
G03X422441Y212225I0J197D01*
G01X418032D02*
G03X418229Y212028I197J0D01*
G01X419095D02*
G03X419292Y212225I0J197D01*
G01X414882D02*
G03X415079Y212028I197J0D01*
G01X415945D02*
G03X416142Y212225I0J197D01*
G01X412796Y212028D02*
G03X412992Y212225I-1J197D01*
G01X434626Y215630D02*
X433572Y219567D01*
G01X431674Y207756D02*
X432855Y206575D01*
G01X431674Y203819D02*
X432855Y202638D01*
G01X433681Y207756D02*
Y209140D01*
G01X433485Y208942D02*
Y207756D01*
G01X432855Y206575D02*
Y202638D01*
G01X431890Y212225D02*
Y213268D01*
G01X431693Y212028D02*
Y213071D01*
G01X431674Y207756D02*
Y203819D01*
G01X430827Y213071D02*
Y212028D01*
G01X430630Y213268D02*
Y212225D01*
G01X428740D02*
Y213268D01*
G01X428544Y212028D02*
Y213071D01*
G01X427677D02*
Y212028D01*
G01X427481Y213268D02*
Y212225D01*
G01X425591D02*
Y213268D01*
G01X425394Y212028D02*
Y213071D01*
G01X424528D02*
Y212028D01*
G01X424331Y213268D02*
Y212225D01*
G01X422441D02*
Y213268D01*
G01X422244Y212028D02*
Y213071D01*
G01X421378D02*
Y212028D01*
G01X421181Y213268D02*
Y212225D01*
G01X419292D02*
Y213268D01*
G01X419095Y212028D02*
Y213071D01*
G01X418229D02*
Y212028D01*
G01X418032Y213268D02*
Y212225D01*
G01X416142D02*
Y213268D01*
G01X415945Y212028D02*
Y213071D01*
G01X415079D02*
Y212028D01*
G01X414882Y213268D02*
Y212225D01*
G01X412992D02*
Y213268D01*
G01X412796Y212028D02*
Y213071D01*
G01X434468Y216221D02*
X510807D01*
G01X513051Y215630D02*
X434626D01*
G01X431693Y213071D02*
X431890D01*
G01X430630D02*
X430827D01*
G01X428544D02*
X428740D01*
G01X427481D02*
X427677D01*
G01X425394D02*
X425591D01*
G01X424331D02*
X424528D01*
G01X422244D02*
X422441D01*
G01X421181D02*
X421378D01*
G01X419095D02*
X419292D01*
G01X418032D02*
X418229D01*
G01X415945D02*
X416142D01*
G01X414882D02*
X415079D01*
G01X412796D02*
X412992D01*
G01X430827Y212684D02*
X431693D01*
G01X427677D02*
X428544D01*
G01X424528D02*
X425394D01*
G01X421378D02*
X422244D01*
G01X418229D02*
X419095D01*
G01X415079D02*
X415945D01*
G01X430827Y212028D02*
X431693D01*
G01X427677D02*
X428544D01*
G01X424528D02*
X425394D01*
G01X421378D02*
X422244D01*
G01X418229D02*
X419095D01*
G01X415079D02*
X415945D01*
G01X434941Y209140D02*
X433681D01*
G01X434941Y208513D02*
X433681D01*
G01X508130Y207756D02*
X431674D01*
G01X509311Y206575D02*
X432855D01*
G01X429922Y260630D02*
Y266536D01*
G01X425985Y256693D02*
G03X429922Y260630I0J3937D01*
G01Y266536D02*
G03X425985Y270473I-3937J0D01*
G01X430374Y302529D02*
X430473Y302510D01*
G01X430302Y302580D02*
X430374Y302529D01*
G01X430276Y302650D02*
X430302Y302580D01*
G01X425374Y302529D02*
X425473Y302510D01*
G01X425302Y302580D02*
X425374Y302529D01*
G01X425276Y302650D02*
X425302Y302580D01*
G01X420374Y302529D02*
X420473Y302510D01*
G01X420302Y302580D02*
X420374Y302529D01*
G01X420276Y302650D02*
X420302Y302580D01*
G01X417520Y298321D02*
X417618Y298339D01*
G01X417448Y298271D02*
X417520Y298321D01*
G01X417422Y298202D02*
X417448Y298271D01*
G01X414370Y298321D02*
X414469Y298339D01*
G01X414298Y298271D02*
X414370Y298321D01*
G01X414272Y298202D02*
X414298Y298271D01*
G01X418655D02*
X418681Y298202D01*
G01X418583Y298321D02*
X418655Y298271D01*
G01X418485Y298339D02*
X418583Y298321D01*
G01X415505Y298271D02*
X415532Y298202D01*
G01X415433Y298321D02*
X415505Y298271D01*
G01X415335Y298339D02*
X415433Y298321D01*
G01X412356Y298271D02*
X412382Y298202D01*
G01X412284Y298321D02*
X412356Y298271D01*
G01X421903Y302580D02*
X421929Y302650D01*
G01X421831Y302529D02*
X421903Y302580D01*
G01X421733Y302510D02*
X421831Y302529D01*
G01X426903Y302580D02*
X426929Y302650D01*
G01X426831Y302529D02*
X426903Y302580D01*
G01X426733Y302510D02*
X426831Y302529D01*
G01X431903Y302580D02*
X431929Y302650D01*
G01X431831Y302529D02*
X431903Y302580D01*
G01X431733Y302510D02*
X431831Y302529D01*
G01X412382Y298799D02*
G03X412185Y298996I-197J0D01*
G01X415532Y298799D02*
G03X415335Y298996I-197J0D01*
G01X414469D02*
G03X414272Y298799I0J-197D01*
G01X418681D02*
G03X418485Y298996I-197J0D01*
G01X417618D02*
G03X417422Y298799I1J-197D01*
G01X430276Y302081D02*
G03X430473Y301884I197J0D01*
G01X431733D02*
G03X431929Y302081I-1J197D01*
G01X425276D02*
G03X425473Y301884I197J0D01*
G01X426733D02*
G03X426929Y302081I-1J197D01*
G01X420276D02*
G03X420473Y301884I197J0D01*
G01X421733D02*
G03X421929Y302081I-1J197D01*
G01X457599Y294803D02*
X421259D01*
G01X459843Y295394D02*
X421418D01*
G01X412382Y297952D02*
X412185D01*
G01X414469D02*
X414272D01*
G01X415532D02*
X415335D01*
G01X417618D02*
X417422D01*
G01X418681D02*
X418485D01*
G01X415335Y298339D02*
X414469D01*
G01X418485D02*
X417618D01*
G01X415335Y298996D02*
X414469D01*
G01X418485D02*
X417618D01*
G01X430473Y301884D02*
X431733D01*
G01X425473D02*
X426733D01*
G01X420473D02*
X421733D01*
G01X430473Y302510D02*
X431733D01*
G01X425473D02*
X426733D01*
G01X420473D02*
X421733D01*
G01X418465Y303268D02*
X454922D01*
G01X419646Y304449D02*
X456103D01*
G01X418465Y307205D02*
X419646Y308386D01*
G01X418465Y303268D02*
X419646Y304449D01*
G01X421418Y295394D02*
X420363Y291457D01*
G01X412185Y297952D02*
Y298996D01*
G01X412382Y297756D02*
Y298799D01*
G01X414272D02*
Y297756D01*
G01X414469Y298996D02*
Y297952D01*
G01X415335D02*
Y298996D01*
G01X415532Y297756D02*
Y298799D01*
G01X417422D02*
Y297756D01*
G01X417618Y298996D02*
Y297952D01*
G01X418465Y307205D02*
Y303268D01*
G01X418485Y297952D02*
Y298996D01*
G01X418681Y297756D02*
Y298799D01*
G01X419646Y308386D02*
Y304449D01*
G01X420276Y303268D02*
Y302081D01*
G01X420473Y303268D02*
Y301884D01*
G01X421733Y303268D02*
Y301884D01*
G01X421929Y302081D02*
Y303268D01*
G01X425276D02*
Y302081D01*
G01X425473Y303268D02*
Y301884D01*
G01X426733Y303268D02*
Y301884D01*
G01X426929Y302081D02*
Y303268D01*
G01X430276D02*
Y302081D01*
G01X430473Y303268D02*
Y301884D01*
G01X431733Y303268D02*
Y301884D01*
G01X431929Y302081D02*
Y303268D01*
G01X430374Y347017D02*
X430473Y346998D01*
G01X430302Y347068D02*
X430374Y347017D01*
G01X430276Y347138D02*
X430302Y347068D01*
G01X425374Y347017D02*
X425473Y346998D01*
G01X425302Y347068D02*
X425374Y347017D01*
G01X425276Y347138D02*
X425302Y347068D01*
G01X420374Y347017D02*
X420473Y346998D01*
G01X420302Y347068D02*
X420374Y347017D01*
G01X420276Y347138D02*
X420302Y347068D01*
G01X418655Y342759D02*
X418681Y342690D01*
G01X418583Y342809D02*
X418655Y342759D01*
G01X418485Y342828D02*
X418583Y342809D01*
G01X415505Y342759D02*
X415532Y342690D01*
G01X415433Y342809D02*
X415505Y342759D01*
G01X415335Y342828D02*
X415433Y342809D01*
G01X412356Y342759D02*
X412382Y342690D01*
G01X412284Y342809D02*
X412356Y342759D01*
G01X417520Y342809D02*
X417618Y342828D01*
G01X417448Y342759D02*
X417520Y342809D01*
G01X417422Y342690D02*
X417448Y342759D01*
G01X414370Y342809D02*
X414469Y342828D01*
G01X414298Y342759D02*
X414370Y342809D01*
G01X414272Y342690D02*
X414298Y342759D01*
G01X421903Y347068D02*
X421929Y347138D01*
G01X421831Y347017D02*
X421903Y347068D01*
G01X421733Y346998D02*
X421831Y347017D01*
G01X426903Y347068D02*
X426929Y347138D01*
G01X426831Y347017D02*
X426903Y347068D01*
G01X426733Y346998D02*
X426831Y347017D01*
G01X431903Y347068D02*
X431929Y347138D01*
G01X431831Y347017D02*
X431903Y347068D01*
G01X431733Y346998D02*
X431831Y347017D01*
G01X412382Y343287D02*
G03X412185Y343484I-197J0D01*
G01X415532Y343287D02*
G03X415335Y343484I-197J0D01*
G01X414469D02*
G03X414272Y343287I0J-197D01*
G01X418681D02*
G03X418485Y343484I-197J0D01*
G01X417618D02*
G03X417422Y343287I1J-197D01*
G01X430276Y346569D02*
G03X430473Y346372I197J0D01*
G01X431733D02*
G03X431929Y346569I-1J197D01*
G01X425276D02*
G03X425473Y346372I197J0D01*
G01X426733D02*
G03X426929Y346569I-1J197D01*
G01X420276D02*
G03X420473Y346372I197J0D01*
G01X421733D02*
G03X421929Y346569I-1J197D01*
G01X418465Y351693D02*
X419646Y352874D01*
G01X418465Y347756D02*
X419646Y348937D01*
G01X457599Y339291D02*
X421259D01*
G01X459843Y339882D02*
X421418D01*
G01X412382Y342441D02*
X412185D01*
G01X414469D02*
X414272D01*
G01X415532D02*
X415335D01*
G01X417618D02*
X417422D01*
G01X418681D02*
X418485D01*
G01X415335Y342828D02*
X414469D01*
G01X418485D02*
X417618D01*
G01X415335Y343484D02*
X414469D01*
G01X418485D02*
X417618D01*
G01X430473Y346372D02*
X431733D01*
G01X425473D02*
X426733D01*
G01X420473D02*
X421733D01*
G01X430473Y346998D02*
X431733D01*
G01X425473D02*
X426733D01*
G01X420473D02*
X421733D01*
G01X418465Y347756D02*
X454922D01*
G01X419646Y348937D02*
X456103D01*
G01X421418Y339882D02*
X420363Y335945D01*
G01X412185Y342441D02*
Y343484D01*
G01X412382Y342244D02*
Y343287D01*
G01X414272D02*
Y342244D01*
G01X414469Y343484D02*
Y342441D01*
G01X415335D02*
Y343484D01*
G01X415532Y342244D02*
Y343287D01*
G01X417422D02*
Y342244D01*
G01X417618Y343484D02*
Y342441D01*
G01X418465Y351693D02*
Y347756D01*
G01X418485Y342441D02*
Y343484D01*
G01X418681Y342244D02*
Y343287D01*
G01X419646Y352874D02*
Y348937D01*
G01X420276Y347756D02*
Y346569D01*
G01X420473Y347756D02*
Y346372D01*
G01X421733Y347756D02*
Y346372D01*
G01X421929Y346569D02*
Y347756D01*
G01X425276D02*
Y346569D01*
G01X425473Y347756D02*
Y346372D01*
G01X426733Y347756D02*
Y346372D01*
G01X426929Y346569D02*
Y347756D01*
G01X430276D02*
Y346569D01*
G01X430473Y347756D02*
Y346372D01*
G01X431733Y347756D02*
Y346372D01*
G01X431929Y346569D02*
Y347756D01*
G01X429922Y630315D02*
Y636221D01*
G01X425985Y626378D02*
G03X429922Y630315I0J3937D01*
G01Y636221D02*
G03X425985Y640158I-3937J0D01*
G01X430787Y970112D02*
Y952789D01*
G01X453511Y142696D02*
X453485Y142626D01*
G01X453583Y142747D02*
X453511Y142696D01*
G01X453681Y142765D02*
X453583Y142747D01*
G01X448511Y142696D02*
X448485Y142626D01*
G01X448583Y142747D02*
X448511Y142696D01*
G01X448681Y142765D02*
X448583Y142747D01*
G01X443511Y142696D02*
X443485Y142626D01*
G01X443583Y142747D02*
X443511Y142696D01*
G01X443681Y142765D02*
X443583Y142747D01*
G01X438511Y142696D02*
X438485Y142626D01*
G01X438583Y142747D02*
X438511Y142696D01*
G01X438681Y142765D02*
X438583Y142747D01*
G01X435040D02*
X434941Y142765D01*
G01X435112Y142696D02*
X435040Y142747D01*
G01X435138Y142626D02*
X435112Y142696D01*
G01X440040Y142747D02*
X439941Y142765D01*
G01X440112Y142696D02*
X440040Y142747D01*
G01X440138Y142626D02*
X440112Y142696D01*
G01X445040Y142747D02*
X444941Y142765D01*
G01X445112Y142696D02*
X445040Y142747D01*
G01X445138Y142626D02*
X445112Y142696D01*
G01X450040Y142747D02*
X449941Y142765D01*
G01X450112Y142696D02*
X450040Y142747D01*
G01X450138Y142626D02*
X450112Y142696D01*
G01X455040Y142747D02*
X454941Y142765D01*
G01X455112Y142696D02*
X455040Y142747D01*
G01X455138Y142626D02*
X455112Y142696D01*
G01X450138Y143195D02*
G03X449941Y143392I-197J0D01*
G01X448681D02*
G03X448485Y143195I1J-197D01*
G01X435138D02*
G03X434941Y143392I-197J0D01*
G01X440138Y143195D02*
G03X439941Y143392I-197J0D01*
G01X438681D02*
G03X438485Y143195I1J-197D01*
G01X445138D02*
G03X444941Y143392I-197J0D01*
G01X443681D02*
G03X443485Y143195I1J-197D01*
G01X455138D02*
G03X454941Y143392I-197J0D01*
G01X453681D02*
G03X453485Y143195I1J-197D01*
G01X455138Y142008D02*
Y143194D01*
G01X454941Y142008D02*
Y143392D01*
G01X453681Y142008D02*
Y143392D01*
G01X453485Y143194D02*
Y142008D01*
G01X450138D02*
Y143194D01*
G01X449941Y142008D02*
Y143392D01*
G01X448681Y142008D02*
Y143392D01*
G01X448485Y143194D02*
Y142008D01*
G01X445138D02*
Y143194D01*
G01X444941Y142008D02*
Y143392D01*
G01X443681Y142008D02*
Y143392D01*
G01X443485Y143194D02*
Y142008D01*
G01X440138D02*
Y143194D01*
G01X439941Y142008D02*
Y143392D01*
G01X438681Y142008D02*
Y143392D01*
G01X438485Y143194D02*
Y142008D01*
G01X435138D02*
Y143194D01*
G01X434941Y142008D02*
Y143392D01*
G01X439941D02*
X438681D01*
G01X444941D02*
X443681D01*
G01X449941D02*
X448681D01*
G01X454941D02*
X453681D01*
G01X439941Y142765D02*
X438681D01*
G01X444941D02*
X443681D01*
G01X449941D02*
X448681D01*
G01X454941D02*
X453681D01*
G01X453511Y208444D02*
X453485Y208374D01*
G01X453583Y208495D02*
X453511Y208444D01*
G01X453681Y208513D02*
X453583Y208495D01*
G01X448511Y208444D02*
X448485Y208374D01*
G01X448583Y208495D02*
X448511Y208444D01*
G01X448681Y208513D02*
X448583Y208495D01*
G01X443511Y208444D02*
X443485Y208374D01*
G01X443583Y208495D02*
X443511Y208444D01*
G01X443681Y208513D02*
X443583Y208495D01*
G01X438511Y208444D02*
X438485Y208374D01*
G01X438583Y208495D02*
X438511Y208444D01*
G01X438681Y208513D02*
X438583Y208495D01*
G01X435040D02*
X434941Y208513D01*
G01X435112Y208444D02*
X435040Y208495D01*
G01X435138Y208374D02*
X435112Y208444D01*
G01X440040Y208495D02*
X439941Y208513D01*
G01X440112Y208444D02*
X440040Y208495D01*
G01X440138Y208374D02*
X440112Y208444D01*
G01X445040Y208495D02*
X444941Y208513D01*
G01X445112Y208444D02*
X445040Y208495D01*
G01X445138Y208374D02*
X445112Y208444D01*
G01X450040Y208495D02*
X449941Y208513D01*
G01X450112Y208444D02*
X450040Y208495D01*
G01X450138Y208374D02*
X450112Y208444D01*
G01X455040Y208495D02*
X454941Y208513D01*
G01X455112Y208444D02*
X455040Y208495D01*
G01X455138Y208374D02*
X455112Y208444D01*
G01X450138Y208943D02*
G03X449941Y209140I-197J0D01*
G01X448681D02*
G03X448485Y208943I1J-197D01*
G01X435138D02*
G03X434941Y209140I-197J0D01*
G01X440138Y208943D02*
G03X439941Y209140I-197J0D01*
G01X438681D02*
G03X438485Y208943I1J-197D01*
G01X445138D02*
G03X444941Y209140I-197J0D01*
G01X443681D02*
G03X443485Y208943I1J-197D01*
G01X455138D02*
G03X454941Y209140I-197J0D01*
G01X453681D02*
G03X453485Y208943I1J-197D01*
G01X455138Y207756D02*
Y208942D01*
G01X454941Y207756D02*
Y209140D01*
G01X453681Y207756D02*
Y209140D01*
G01X453485Y208942D02*
Y207756D01*
G01X450138D02*
Y208942D01*
G01X449941Y207756D02*
Y209140D01*
G01X448681Y207756D02*
Y209140D01*
G01X448485Y208942D02*
Y207756D01*
G01X445138D02*
Y208942D01*
G01X444941Y207756D02*
Y209140D01*
G01X443681Y207756D02*
Y209140D01*
G01X443485Y208942D02*
Y207756D01*
G01X440138D02*
Y208942D01*
G01X439941Y207756D02*
Y209140D01*
G01X438681Y207756D02*
Y209140D01*
G01X438485Y208942D02*
Y207756D01*
G01X435138D02*
Y208942D01*
G01X434941Y207756D02*
Y209140D01*
G01X439941D02*
X438681D01*
G01X444941D02*
X443681D01*
G01X449941D02*
X448681D01*
G01X454941D02*
X453681D01*
G01X439941Y208513D02*
X438681D01*
G01X444941D02*
X443681D01*
G01X449941D02*
X448681D01*
G01X454941D02*
X453681D01*
G01X452756Y260630D02*
G03X456693Y256693I3937J0D01*
G01X452756Y260630D02*
Y266536D01*
G01X456693Y270473D02*
G03X452756Y266536I0J-3937D01*
G01X450374Y302529D02*
X450473Y302510D01*
G01X450302Y302580D02*
X450374Y302529D01*
G01X450276Y302650D02*
X450302Y302580D01*
G01X445374Y302529D02*
X445473Y302510D01*
G01X445302Y302580D02*
X445374Y302529D01*
G01X445276Y302650D02*
X445302Y302580D01*
G01X440374Y302529D02*
X440473Y302510D01*
G01X440302Y302580D02*
X440374Y302529D01*
G01X440276Y302650D02*
X440302Y302580D01*
G01X435374Y302529D02*
X435473Y302510D01*
G01X435302Y302580D02*
X435374Y302529D01*
G01X435276Y302650D02*
X435302Y302580D01*
G01X436903D02*
X436929Y302650D01*
G01X436831Y302529D02*
X436903Y302580D01*
G01X436733Y302510D02*
X436831Y302529D01*
G01X441903Y302580D02*
X441929Y302650D01*
G01X441831Y302529D02*
X441903Y302580D01*
G01X441733Y302510D02*
X441831Y302529D01*
G01X446903Y302580D02*
X446929Y302650D01*
G01X446831Y302529D02*
X446903Y302580D01*
G01X446733Y302510D02*
X446831Y302529D01*
G01X451903Y302580D02*
X451929Y302650D01*
G01X451831Y302529D02*
X451903Y302580D01*
G01X451733Y302510D02*
X451831Y302529D01*
G01X450276Y302081D02*
G03X450473Y301884I197J0D01*
G01X451733D02*
G03X451929Y302081I-1J197D01*
G01X445276D02*
G03X445473Y301884I197J0D01*
G01X446733D02*
G03X446929Y302081I-1J197D01*
G01X440276D02*
G03X440473Y301884I197J0D01*
G01X441733D02*
G03X441929Y302081I-1J197D01*
G01X435276D02*
G03X435473Y301884I197J0D01*
G01X436733D02*
G03X436929Y302081I-1J197D01*
G01X450473Y301884D02*
X451733D01*
G01X445473D02*
X446733D01*
G01X440473D02*
X441733D01*
G01X435473D02*
X436733D01*
G01X450473Y302510D02*
X451733D01*
G01X445473D02*
X446733D01*
G01X440473D02*
X441733D01*
G01X435473D02*
X436733D01*
G01X454922Y303268D02*
X456103Y304449D01*
G01X435276Y303268D02*
Y302081D01*
G01X435473Y303268D02*
Y301884D01*
G01X436733Y303268D02*
Y301884D01*
G01X436929Y302081D02*
Y303268D01*
G01X440276D02*
Y302081D01*
G01X460945Y291457D02*
X457599Y294803D01*
G01X454922Y297756D02*
X456103Y296575D01*
G01X440473Y303268D02*
Y301884D01*
G01X441733Y303268D02*
Y301884D01*
G01X441929Y302081D02*
Y303268D01*
G01X445276D02*
Y302081D01*
G01X445473Y303268D02*
Y301884D01*
G01X446733Y303268D02*
Y301884D01*
G01X446929Y302081D02*
Y303268D01*
G01X450276D02*
Y302081D01*
G01X450473Y303268D02*
Y301884D01*
G01X451733Y303268D02*
Y301884D01*
G01X451929Y302081D02*
Y303268D01*
G01X454922D02*
Y297756D01*
G01X456103Y304449D02*
Y296575D01*
G01X458662Y318504D02*
G03X456693Y320473I-1969J0D01*
G01Y314567D02*
G03X458662Y316536I0J1969D01*
G01X457599Y309764D02*
X460945Y313110D01*
G01X450374Y347017D02*
X450473Y346998D01*
G01X450302Y347068D02*
X450374Y347017D01*
G01X450276Y347138D02*
X450302Y347068D01*
G01X445374Y347017D02*
X445473Y346998D01*
G01X445302Y347068D02*
X445374Y347017D01*
G01X445276Y347138D02*
X445302Y347068D01*
G01X440374Y347017D02*
X440473Y346998D01*
G01X440302Y347068D02*
X440374Y347017D01*
G01X440276Y347138D02*
X440302Y347068D01*
G01X435374Y347017D02*
X435473Y346998D01*
G01X435302Y347068D02*
X435374Y347017D01*
G01X435276Y347138D02*
X435302Y347068D01*
G01X436903D02*
X436929Y347138D01*
G01X436831Y347017D02*
X436903Y347068D01*
G01X436733Y346998D02*
X436831Y347017D01*
G01X441903Y347068D02*
X441929Y347138D01*
G01X441831Y347017D02*
X441903Y347068D01*
G01X441733Y346998D02*
X441831Y347017D01*
G01X446903Y347068D02*
X446929Y347138D01*
G01X446831Y347017D02*
X446903Y347068D01*
G01X446733Y346998D02*
X446831Y347017D01*
G01X451903Y347068D02*
X451929Y347138D01*
G01X451831Y347017D02*
X451903Y347068D01*
G01X451733Y346998D02*
X451831Y347017D01*
G01X450276Y346569D02*
G03X450473Y346372I197J0D01*
G01X451733D02*
G03X451929Y346569I-1J197D01*
G01X445276D02*
G03X445473Y346372I197J0D01*
G01X446733D02*
G03X446929Y346569I-1J197D01*
G01X440276D02*
G03X440473Y346372I197J0D01*
G01X441733D02*
G03X441929Y346569I-1J197D01*
G01X435276D02*
G03X435473Y346372I197J0D01*
G01X436733D02*
G03X436929Y346569I-1J197D01*
G01X454922Y347756D02*
X456103Y348937D01*
G01X450473Y346372D02*
X451733D01*
G01X445473D02*
X446733D01*
G01X440473D02*
X441733D01*
G01X435473D02*
X436733D01*
G01X450473Y346998D02*
X451733D01*
G01X445473D02*
X446733D01*
G01X440473D02*
X441733D01*
G01X435473D02*
X436733D01*
G01X435276Y347756D02*
Y346569D01*
G01X435473Y347756D02*
Y346372D01*
G01X436733Y347756D02*
Y346372D01*
G01X436929Y346569D02*
Y347756D01*
G01X440276D02*
Y346569D01*
G01X440473Y347756D02*
Y346372D01*
G01X441733Y347756D02*
Y346372D01*
G01X441929Y346569D02*
Y347756D01*
G01X445276D02*
Y346569D01*
G01X445473Y347756D02*
Y346372D01*
G01X446733Y347756D02*
Y346372D01*
G01X446929Y346569D02*
Y347756D01*
G01X450276D02*
Y346569D01*
G01X450473Y347756D02*
Y346372D01*
G01X451733Y347756D02*
Y346372D01*
G01X451929Y346569D02*
Y347756D01*
G01X454922D02*
Y342244D01*
G01X456103Y348937D02*
Y341063D01*
G01X460945Y335945D02*
X457599Y339291D01*
G01X454922Y342244D02*
X456103Y341063D01*
G01X457599Y354252D02*
X460945Y357599D01*
G01X452756Y630315D02*
G03X456693Y626378I3937J0D01*
G01X452756Y630315D02*
Y636221D01*
G01X456693Y640158D02*
G03X452756Y636221I0J-3937D01*
G01X458662Y688189D02*
G03X456693Y690158I-1969J0D01*
G01Y684252D02*
G03X458662Y686221I0J1969D01*
G01X469882Y67126D02*
X525591D01*
G01X458071Y78937D02*
G03X469882Y67126I11811J0D01*
G01X458071Y90551D02*
Y78937D01*
G01X465945D02*
G03X469882Y75000I3937J0D01*
G01X465945Y94488D02*
Y78937D01*
G01X469882Y75000D02*
X529528D01*
G01X465945Y94488D02*
G03X462008Y98425I-3937J0D01*
G01X478511Y142696D02*
X478485Y142626D01*
G01X478583Y142747D02*
X478511Y142696D01*
G01X478681Y142765D02*
X478583Y142747D01*
G01X473511Y142696D02*
X473485Y142626D01*
G01X473583Y142747D02*
X473511Y142696D01*
G01X473681Y142765D02*
X473583Y142747D01*
G01X468511Y142696D02*
X468485Y142626D01*
G01X468583Y142747D02*
X468511Y142696D01*
G01X468681Y142765D02*
X468583Y142747D01*
G01X463511Y142696D02*
X463485Y142626D01*
G01X463583Y142747D02*
X463511Y142696D01*
G01X463681Y142765D02*
X463583Y142747D01*
G01X458511Y142696D02*
X458485Y142626D01*
G01X458583Y142747D02*
X458511Y142696D01*
G01X458681Y142765D02*
X458583Y142747D01*
G01X460040D02*
X459941Y142765D01*
G01X460112Y142696D02*
X460040Y142747D01*
G01X460138Y142626D02*
X460112Y142696D01*
G01X465040Y142747D02*
X464941Y142765D01*
G01X465112Y142696D02*
X465040Y142747D01*
G01X465138Y142626D02*
X465112Y142696D01*
G01X470040Y142747D02*
X469941Y142765D01*
G01X470112Y142696D02*
X470040Y142747D01*
G01X470138Y142626D02*
X470112Y142696D01*
G01X475040Y142747D02*
X474941Y142765D01*
G01X475112Y142696D02*
X475040Y142747D01*
G01X475138Y142626D02*
X475112Y142696D01*
G01X480040Y142747D02*
X479941Y142765D01*
G01X480112Y142696D02*
X480040Y142747D01*
G01X480138Y142626D02*
X480112Y142696D01*
G01X460138Y143195D02*
G03X459941Y143392I-197J0D01*
G01X458681D02*
G03X458485Y143195I1J-197D01*
G01X465138D02*
G03X464941Y143392I-197J0D01*
G01X463681D02*
G03X463485Y143195I1J-197D01*
G01X470138D02*
G03X469941Y143392I-197J0D01*
G01X468681D02*
G03X468485Y143195I1J-197D01*
G01X475138D02*
G03X474941Y143392I-197J0D01*
G01X473681D02*
G03X473485Y143195I1J-197D01*
G01X480138D02*
G03X479941Y143392I-197J0D01*
G01X478681D02*
G03X478485Y143195I1J-197D01*
G01X480138Y142008D02*
Y143194D01*
G01X479941Y142008D02*
Y143392D01*
G01X478681Y142008D02*
Y143392D01*
G01X478485Y143194D02*
Y142008D01*
G01X475138D02*
Y143194D01*
G01X474941Y142008D02*
Y143392D01*
G01X473681Y142008D02*
Y143392D01*
G01X473485Y143194D02*
Y142008D01*
G01X470138D02*
Y143194D01*
G01X469941Y142008D02*
Y143392D01*
G01X468681Y142008D02*
Y143392D01*
G01X468485Y143194D02*
Y142008D01*
G01X465138D02*
Y143194D01*
G01X464941Y142008D02*
Y143392D01*
G01X463681Y142008D02*
Y143392D01*
G01X463485Y143194D02*
Y142008D01*
G01X460138D02*
Y143194D01*
G01X459941Y142008D02*
Y143392D01*
G01X458681Y142008D02*
Y143392D01*
G01X458485Y143194D02*
Y142008D01*
G01X459941Y143392D02*
X458681D01*
G01X464941D02*
X463681D01*
G01X469941D02*
X468681D01*
G01X474941D02*
X473681D01*
G01X479941D02*
X478681D01*
G01X459941Y142765D02*
X458681D01*
G01X464941D02*
X463681D01*
G01X469941D02*
X468681D01*
G01X474941D02*
X473681D01*
G01X479941D02*
X478681D01*
G01X478511Y208444D02*
X478485Y208374D01*
G01X478583Y208495D02*
X478511Y208444D01*
G01X478681Y208513D02*
X478583Y208495D01*
G01X473511Y208444D02*
X473485Y208374D01*
G01X473583Y208495D02*
X473511Y208444D01*
G01X473681Y208513D02*
X473583Y208495D01*
G01X468511Y208444D02*
X468485Y208374D01*
G01X468583Y208495D02*
X468511Y208444D01*
G01X468681Y208513D02*
X468583Y208495D01*
G01X463511Y208444D02*
X463485Y208374D01*
G01X463583Y208495D02*
X463511Y208444D01*
G01X463681Y208513D02*
X463583Y208495D01*
G01X458511Y208444D02*
X458485Y208374D01*
G01X458583Y208495D02*
X458511Y208444D01*
G01X458681Y208513D02*
X458583Y208495D01*
G01X460040D02*
X459941Y208513D01*
G01X460112Y208444D02*
X460040Y208495D01*
G01X460138Y208374D02*
X460112Y208444D01*
G01X465040Y208495D02*
X464941Y208513D01*
G01X465112Y208444D02*
X465040Y208495D01*
G01X465138Y208374D02*
X465112Y208444D01*
G01X470040Y208495D02*
X469941Y208513D01*
G01X470112Y208444D02*
X470040Y208495D01*
G01X470138Y208374D02*
X470112Y208444D01*
G01X475040Y208495D02*
X474941Y208513D01*
G01X475112Y208444D02*
X475040Y208495D01*
G01X475138Y208374D02*
X475112Y208444D01*
G01X480040Y208495D02*
X479941Y208513D01*
G01X480112Y208444D02*
X480040Y208495D01*
G01X480138Y208374D02*
X480112Y208444D01*
G01X460138Y208943D02*
G03X459941Y209140I-197J0D01*
G01X458681D02*
G03X458485Y208943I1J-197D01*
G01X465138D02*
G03X464941Y209140I-197J0D01*
G01X463681D02*
G03X463485Y208943I1J-197D01*
G01X470138D02*
G03X469941Y209140I-197J0D01*
G01X468681D02*
G03X468485Y208943I1J-197D01*
G01X475138D02*
G03X474941Y209140I-197J0D01*
G01X473681D02*
G03X473485Y208943I1J-197D01*
G01X480138D02*
G03X479941Y209140I-197J0D01*
G01X478681D02*
G03X478485Y208943I1J-197D01*
G01X480138Y207756D02*
Y208942D01*
G01X479941Y207756D02*
Y209140D01*
G01X478681Y207756D02*
Y209140D01*
G01X478485Y208942D02*
Y207756D01*
G01X475138D02*
Y208942D01*
G01X474941Y207756D02*
Y209140D01*
G01X473681Y207756D02*
Y209140D01*
G01X473485Y208942D02*
Y207756D01*
G01X470138D02*
Y208942D01*
G01X469941Y207756D02*
Y209140D01*
G01X468681Y207756D02*
Y209140D01*
G01X468485Y208942D02*
Y207756D01*
G01X465138D02*
Y208942D01*
G01X464941Y207756D02*
Y209140D01*
G01X463681Y207756D02*
Y209140D01*
G01X463485Y208942D02*
Y207756D01*
G01X460138D02*
Y208942D01*
G01X459941Y207756D02*
Y209140D01*
G01X458681Y207756D02*
Y209140D01*
G01X458485Y208942D02*
Y207756D01*
G01X459941Y209140D02*
X458681D01*
G01X464941D02*
X463681D01*
G01X469941D02*
X468681D01*
G01X474941D02*
X473681D01*
G01X479941D02*
X478681D01*
G01X459941Y208513D02*
X458681D01*
G01X464941D02*
X463681D01*
G01X469941D02*
X468681D01*
G01X474941D02*
X473681D01*
G01X479941D02*
X478681D01*
G01X468189Y304843D02*
G03X467008Y306024I-1181J0D01*
G01Y298543D02*
G03X468189Y299725I0J1181D01*
G01X476693Y291457D02*
G03X478662Y293425I0J1969D01*
G01X463504Y303465D02*
X467734Y305775D01*
G01X460945Y291457D02*
X476693D01*
G01X461811Y301102D02*
X459843Y299799D01*
G01X467008Y298543D02*
X458465D01*
G01X463504Y301102D02*
X461811D01*
G01Y303465D02*
X463504D01*
G01X467008Y306024D02*
X458465D01*
G01X467734Y298792D02*
X463504Y301102D01*
G01X459843Y304768D02*
X461811Y303465D01*
G01X458465Y306024D02*
Y309173D01*
G01Y295394D02*
Y298543D01*
G01X459843Y309173D02*
Y295394D01*
G01X461811Y303465D02*
Y301102D01*
G01X463504Y303465D02*
Y301102D01*
G01X468189Y304843D02*
Y299725D01*
G01X478662Y293425D02*
Y311142D01*
G01D02*
G03X476693Y313110I-1968J0D01*
G01D02*
X460945D01*
G01X458662Y316536D02*
Y318504D01*
G01X468189Y349331D02*
G03X467008Y350512I-1181J0D01*
G01Y343032D02*
G03X468189Y344213I0J1181D01*
G01X476693Y335945D02*
G03X478662Y337913I0J1969D01*
G01X463504Y347953D02*
X467734Y350263D01*
G01X461811Y345591D02*
X459843Y344287D01*
G01X460945Y335945D02*
X476693D01*
G01X467008Y343032D02*
X458465D01*
G01X463504Y345591D02*
X461811D01*
G01Y347953D02*
X463504D01*
G01X467008Y350512D02*
X458465D01*
G01X467734Y343280D02*
X463504Y345591D01*
G01X458465Y350512D02*
Y353662D01*
G01Y339882D02*
Y343032D01*
G01X459843Y353662D02*
Y339882D01*
G01Y349256D02*
X461811Y347953D01*
G01D02*
Y345591D01*
G01X463504Y347953D02*
Y345591D01*
G01X468189Y349331D02*
Y344213D01*
G01X478662Y337913D02*
Y355630D01*
G01D02*
G03X476693Y357599I-1969J0D01*
G01D02*
X460945D01*
G01X465355Y361811D02*
G03Y369685I0J3937D01*
G01X458071Y448622D02*
G03X469882Y436811I11811J0D01*
G01D02*
X525591D01*
G01X465945Y448622D02*
G03X469882Y444685I3937J0D01*
G01X465945Y464173D02*
G03X462008Y468110I-3937J0D01*
G01X458071Y460236D02*
Y448622D01*
G01X465945Y464173D02*
Y448622D01*
G01X469882Y444685D02*
X529528D01*
G01X458662Y686221D02*
Y688189D01*
G01X498511Y142696D02*
X498485Y142626D01*
G01X498583Y142747D02*
X498511Y142696D01*
G01X498681Y142765D02*
X498583Y142747D01*
G01X493511Y142696D02*
X493485Y142626D01*
G01X493583Y142747D02*
X493511Y142696D01*
G01X493681Y142765D02*
X493583Y142747D01*
G01X488511Y142696D02*
X488485Y142626D01*
G01X488583Y142747D02*
X488511Y142696D01*
G01X488681Y142765D02*
X488583Y142747D01*
G01X483511Y142696D02*
X483485Y142626D01*
G01X483583Y142747D02*
X483511Y142696D01*
G01X483681Y142765D02*
X483583Y142747D01*
G01X485040D02*
X484941Y142765D01*
G01X485112Y142696D02*
X485040Y142747D01*
G01X485138Y142626D02*
X485112Y142696D01*
G01X490040Y142747D02*
X489941Y142765D01*
G01X490112Y142696D02*
X490040Y142747D01*
G01X490138Y142626D02*
X490112Y142696D01*
G01X495040Y142747D02*
X494941Y142765D01*
G01X495112Y142696D02*
X495040Y142747D01*
G01X495138Y142626D02*
X495112Y142696D01*
G01X500040Y142747D02*
X499941Y142765D01*
G01X500112Y142696D02*
X500040Y142747D01*
G01X500138Y142626D02*
X500112Y142696D01*
G01X490138Y143195D02*
G03X489941Y143392I-197J0D01*
G01X488681D02*
G03X488485Y143195I1J-197D01*
G01X485138D02*
G03X484941Y143392I-197J0D01*
G01X483681D02*
G03X483485Y143195I1J-197D01*
G01X495138D02*
G03X494941Y143392I-197J0D01*
G01X493681D02*
G03X493485Y143195I1J-197D01*
G01X500138D02*
G03X499941Y143392I-197J0D01*
G01X498681D02*
G03X498485Y143195I1J-197D01*
G01X500138Y142008D02*
Y143194D01*
G01X499941Y142008D02*
Y143392D01*
G01X498681Y142008D02*
Y143392D01*
G01X498485Y143194D02*
Y142008D01*
G01X495138D02*
Y143194D01*
G01X494941Y142008D02*
Y143392D01*
G01X493681Y142008D02*
Y143392D01*
G01X493485Y143194D02*
Y142008D01*
G01X490138D02*
Y143194D01*
G01X489941Y142008D02*
Y143392D01*
G01X488681Y142008D02*
Y143392D01*
G01X488485Y143194D02*
Y142008D01*
G01X485138D02*
Y143194D01*
G01X484941Y142008D02*
Y143392D01*
G01X483681Y142008D02*
Y143392D01*
G01X483485Y143194D02*
Y142008D01*
G01X484941Y143392D02*
X483681D01*
G01X489941D02*
X488681D01*
G01X494941D02*
X493681D01*
G01X499941D02*
X498681D01*
G01X484941Y142765D02*
X483681D01*
G01X489941D02*
X488681D01*
G01X494941D02*
X493681D01*
G01X499941D02*
X498681D01*
G01X484252Y164365D02*
G03X486221Y166334I0J1969D01*
G01D02*
Y180113D01*
G01D02*
G03X484252Y182082I-1969J0D01*
G01X498511Y208444D02*
X498485Y208374D01*
G01X498583Y208495D02*
X498511Y208444D01*
G01X498681Y208513D02*
X498583Y208495D01*
G01X493511Y208444D02*
X493485Y208374D01*
G01X493583Y208495D02*
X493511Y208444D01*
G01X493681Y208513D02*
X493583Y208495D01*
G01X488511Y208444D02*
X488485Y208374D01*
G01X488583Y208495D02*
X488511Y208444D01*
G01X488681Y208513D02*
X488583Y208495D01*
G01X483511Y208444D02*
X483485Y208374D01*
G01X483583Y208495D02*
X483511Y208444D01*
G01X483681Y208513D02*
X483583Y208495D01*
G01X485040D02*
X484941Y208513D01*
G01X485112Y208444D02*
X485040Y208495D01*
G01X485138Y208374D02*
X485112Y208444D01*
G01X490040Y208495D02*
X489941Y208513D01*
G01X490112Y208444D02*
X490040Y208495D01*
G01X490138Y208374D02*
X490112Y208444D01*
G01X495040Y208495D02*
X494941Y208513D01*
G01X495112Y208444D02*
X495040Y208495D01*
G01X495138Y208374D02*
X495112Y208444D01*
G01X500040Y208495D02*
X499941Y208513D01*
G01X500112Y208444D02*
X500040Y208495D01*
G01X500138Y208374D02*
X500112Y208444D01*
G01X500138Y208943D02*
G03X499941Y209140I-197J0D01*
G01X498681D02*
G03X498485Y208943I1J-197D01*
G01X490138D02*
G03X489941Y209140I-197J0D01*
G01X488681D02*
G03X488485Y208943I1J-197D01*
G01X485138D02*
G03X484941Y209140I-197J0D01*
G01X483681D02*
G03X483485Y208943I1J-197D01*
G01X495138D02*
G03X494941Y209140I-197J0D01*
G01X493681D02*
G03X493485Y208943I1J-197D01*
G01X500138Y207756D02*
Y208942D01*
G01X499941Y207756D02*
Y209140D01*
G01X498681Y207756D02*
Y209140D01*
G01X498485Y208942D02*
Y207756D01*
G01X495138D02*
Y208942D01*
G01X494941Y207756D02*
Y209140D01*
G01X493681Y207756D02*
Y209140D01*
G01X493485Y208942D02*
Y207756D01*
G01X490138D02*
Y208942D01*
G01X489941Y207756D02*
Y209140D01*
G01X488681Y207756D02*
Y209140D01*
G01X488485Y208942D02*
Y207756D01*
G01X485138D02*
Y208942D01*
G01X484941Y207756D02*
Y209140D01*
G01X483681Y207756D02*
Y209140D01*
G01X483485Y208942D02*
Y207756D01*
G01X484941Y209140D02*
X483681D01*
G01X489941D02*
X488681D01*
G01X494941D02*
X493681D01*
G01X499941D02*
X498681D01*
G01X484941Y208513D02*
X483681D01*
G01X489941D02*
X488681D01*
G01X494941D02*
X493681D01*
G01X499941D02*
X498681D01*
G01X496063Y369685D02*
X525591D01*
G01X496063D02*
G03Y361811I0J-3937D01*
G01X484252Y534050D02*
G03X486221Y536019I0J1969D01*
G01Y549799D02*
G03X484252Y551767I-1969J-1D01*
G01X486221Y536019D02*
Y549799D01*
G01X523622Y0D02*
G03X525591Y1969I0J1969D01*
G01X512860Y15093D02*
G03I-4291J0D01*
G01X518356Y57612D02*
G03I-4000J0D01*
G01X516356D02*
G03I-2000J0D01*
G01X503511Y142696D02*
X503485Y142626D01*
G01X503583Y142747D02*
X503511Y142696D01*
G01X503681Y142765D02*
X503583Y142747D01*
G01X505040D02*
X504941Y142765D01*
G01X505112Y142696D02*
X505040Y142747D01*
G01X505138Y142626D02*
X505112Y142696D01*
G01X505138Y143195D02*
G03X504941Y143392I-197J0D01*
G01X503681D02*
G03X503485Y143195I1J-197D01*
G01X520217Y139252D02*
G03X521398Y140433I0J1181D01*
G01Y145551D02*
G03X520217Y146732I-1181J0D01*
G01X521398Y145551D02*
Y140433D01*
G01X516713Y144173D02*
Y141811D01*
G01X515020Y144173D02*
Y141811D01*
G01X513051Y136102D02*
Y149882D01*
G01X511674Y146732D02*
Y149882D01*
G01Y136102D02*
Y139252D01*
G01X509311Y148701D02*
Y140827D01*
G01X508130Y147520D02*
Y142008D01*
G01X505138D02*
Y143194D01*
G01X504941Y142008D02*
Y143392D01*
G01X503681Y142008D02*
Y143392D01*
G01X503485Y143194D02*
Y142008D01*
G01X508130D02*
X509311Y140827D01*
G01X514154Y132165D02*
X510807Y135512D01*
G01X513051Y145477D02*
X515020Y144173D01*
G01X509311Y148701D02*
X508130Y147520D01*
G01X520942Y139501D02*
X516713Y141811D01*
G01X515020D02*
X513051Y140507D01*
G01X516713Y144173D02*
X520942Y146483D01*
G01X511674Y146732D02*
X520217D01*
G01X515020Y144173D02*
X516713D01*
G01X504941Y143392D02*
X503681D01*
G01X504941Y142765D02*
X503681D01*
G01X516713Y141811D02*
X515020D01*
G01X511674Y139252D02*
X520217D01*
G01X514154Y132165D02*
X529902D01*
G01X510807Y150473D02*
X514154Y153819D01*
G01X529902D02*
X514154D01*
G01X503511Y208444D02*
X503485Y208374D01*
G01X503583Y208495D02*
X503511Y208444D01*
G01X503681Y208513D02*
X503583Y208495D01*
G01X505040D02*
X504941Y208513D01*
G01X505112Y208444D02*
X505040Y208495D01*
G01X505138Y208374D02*
X505112Y208444D01*
G01X505138Y208943D02*
G03X504941Y209140I-197J0D01*
G01X503681D02*
G03X503485Y208943I1J-197D01*
G01X520217Y205000D02*
G03X521398Y206181I0J1181D01*
G01Y211299D02*
G03X520217Y212480I-1181J0D01*
G01X521398Y211299D02*
Y206181D01*
G01X516713Y209921D02*
Y207559D01*
G01X515020Y209921D02*
Y207559D01*
G01X513051Y201850D02*
Y215630D01*
G01X508130Y207756D02*
X509311Y206575D01*
G01X514154Y197913D02*
X510807Y201260D01*
G01X511674Y212480D02*
Y215630D01*
G01Y201850D02*
Y205000D01*
G01X509311Y214449D02*
Y206575D01*
G01X508130Y213268D02*
Y207756D01*
G01X505138D02*
Y208942D01*
G01X504941Y207756D02*
Y209140D01*
G01X503681Y207756D02*
Y209140D01*
G01X503485Y208942D02*
Y207756D01*
G01X513051Y211225D02*
X515020Y209921D01*
G01X520942Y205249D02*
X516713Y207559D01*
G01X509311Y214449D02*
X508130Y213268D01*
G01X510807Y216221D02*
X514154Y219567D01*
G01X511674Y212480D02*
X520217D01*
G01X515020Y209921D02*
X516713D01*
G01X504941Y209140D02*
X503681D01*
G01X504941Y208513D02*
X503681D01*
G01X516713Y207559D02*
X515020D01*
G01X511674Y205000D02*
X520217D01*
G01X514154Y197913D02*
X529902D01*
G01X515020Y207559D02*
X513051Y206255D01*
G01X516713Y209921D02*
X520942Y212231D01*
G01X529882Y240945D02*
G03I-4291J0D01*
G01X529902Y219567D02*
X514154D01*
G01X530118Y294803D02*
G03I-6496J0D01*
G01X525945Y317717D02*
G03I-4291J0D01*
G01X531890Y345984D02*
G03I-8268J0D01*
G01X529882Y610630D02*
G03I-4291J0D01*
G01X530118Y664488D02*
G03I-6496J0D01*
G01X525945Y687402D02*
G03I-4291J0D01*
G01X531890Y715669D02*
G03I-8268J0D01*
G01X525591Y1969D02*
Y20965D01*
G01X533465Y3937D02*
G03X537402Y0I3937J0D01*
G01X557677Y13780D02*
G03I-6496J0D01*
G01X533465Y3937D02*
Y71063D01*
G01X537402Y0D02*
X561024D01*
G01X533465Y20965D02*
G03X525591I-3937J0D01*
G01Y46162D02*
Y67126D01*
G01Y46162D02*
G03X533465I3937J0D01*
G01Y71063D02*
G03X529528Y75000I-3937J0D01*
G01X529902Y132165D02*
G03X531870Y134134I-1J1969D01*
G01D02*
Y151850D01*
G01D02*
G03X529902Y153819I-1968J1D01*
G01Y197913D02*
G03X531870Y199882I-1J1969D01*
G01D02*
Y217599D01*
G01X559449Y242913D02*
G03I-8268J0D01*
G01X531870Y217599D02*
G03X529902Y219567I-1968J0D01*
G01X535433Y270473D02*
G03X539370Y274410I0J3937D01*
G01D02*
Y357874D01*
G01X547244Y270473D02*
X562992D01*
G01X547244D02*
Y303543D01*
G01D02*
G03X539370I-3937J0D01*
G01Y328740D02*
G03X547244I3937J0D01*
G01D02*
Y361811D01*
G01X539370Y357874D02*
G03X535433Y361811I-3937J0D01*
G01X547244D02*
X562992D01*
G01X533465Y373622D02*
G03X537402Y369685I3937J0D01*
G01X525591D02*
Y390650D01*
G01X533465Y373622D02*
Y440748D01*
G01X537402Y369685D02*
X561024D01*
G01X533465Y390650D02*
G03X525591I-3937J0D01*
G01X557677Y383465D02*
G03I-6496J0D01*
G01X525591Y415847D02*
G03X533465I3937J0D01*
G01X525591D02*
Y436811D01*
G01X533465Y440748D02*
G03X529528Y444685I-3937J0D01*
G01X559449Y612599D02*
G03I-8268J0D01*
G01X535433Y640158D02*
G03X539370Y644095I0J3937D01*
G01D02*
Y727559D01*
G01X547244Y640158D02*
X562992D01*
G01X547244D02*
Y673228D01*
G01D02*
G03X539370I-3937J0D01*
G01Y698425D02*
G03X547244I3937J0D01*
G01D02*
Y727559D01*
G01X539370Y731496D02*
Y769168D01*
G01X551181Y731496D02*
G03X547244Y727559I0J-3937D01*
G01X539370D02*
G03X535433Y731496I-3937J0D01*
G01X561024Y0D02*
G03X564961Y3937I0J3937D01*
G01D02*
Y252756D01*
G01X557087Y40158D02*
G03I-4291J0D01*
G01X564961Y252756D02*
G03X561024Y256693I-3937J0D01*
G01X562992Y270473D02*
G03X564961Y272441I1J1968D01*
G01D02*
Y359843D01*
G01X558417Y315939D02*
G03I-4291J0D01*
G01X564961Y359843D02*
G03X562992Y361811I-1968J0D01*
G01X561024Y369685D02*
G03X564961Y373622I0J3937D01*
G01D02*
Y622441D01*
G01X557087Y409843D02*
G03I-4291J0D01*
G01X564961Y622441D02*
G03X561024Y626378I-3937J0D01*
G01X564961D02*
Y769168D01*
G01X562992Y640158D02*
G03X564961Y642126I1J1968D01*
G01D02*
Y721654D01*
G01X558417Y685624D02*
G03I-4291J0D01*
G01X564961Y721654D02*
G03X555118Y731496I-9842J0D01*
G01X551181D02*
X555118D01*
G01X604015Y-390518D02*
Y-407840D01*
G01Y970112D02*
Y952789D01*
G01X728425Y-374770D02*
Y-118864D01*
G01Y-374770D02*
X1673307D01*
G01Y-314506D02*
X728425D01*
G01Y-269380D02*
X1259652D01*
G01X728425Y-224254D02*
X1673307D01*
G01X728425Y-179128D02*
X1673307D01*
G01X728425Y-118864D02*
X1673307D01*
G01X777244Y-390518D02*
Y-407840D01*
G01Y970112D02*
Y952789D01*
G01X842294Y164048D02*
Y155386D01*
G01X839104Y186961D02*
Y178300D01*
G01X843224Y503206D02*
X844199Y503928D01*
G01X842737Y502484D02*
X843224Y503206D01*
G01X842250Y501041D02*
X842737Y502484D01*
G01X842250Y498154D02*
Y501041D01*
G01X842737Y496710D02*
X842250Y498154D01*
G01X843224Y495988D02*
X842737Y496710D01*
G01X844199Y495266D02*
X843224Y495988D01*
G01X842712Y586605D02*
X846609D01*
G01X843199Y588770D02*
X842712Y586605D01*
G01X844173Y590214D02*
X843199Y588770D01*
G01Y594545D02*
X844173Y595266D01*
G01X842712Y593823D02*
X843199Y594545D01*
G01X850709Y112014D02*
X849735Y111292D01*
G01X851196Y112736D02*
X850709Y112014D01*
G01X851683Y114179D02*
X851196Y112736D01*
G01X851683Y117066D02*
Y114179D01*
G01X851196Y118510D02*
X851683Y117066D01*
G01X850709Y119232D02*
X851196Y118510D01*
G01X849735Y119953D02*
X850709Y119232D01*
G01X848760D02*
X849735Y119953D01*
G01X848273Y118510D02*
X848760Y119232D01*
G01X847786Y117066D02*
X848273Y118510D01*
G01X847786Y114179D02*
Y117066D01*
G01X848273Y112736D02*
X847786Y114179D01*
G01X848760Y112014D02*
X848273Y112736D01*
G01X849735Y111292D02*
X848760Y112014D01*
G01X866300D02*
X865325Y111292D01*
G01Y119953D02*
X866300Y119232D01*
G01X864351D02*
X865325Y119953D01*
G01X863863Y118510D02*
X864351Y119232D01*
G01X863376Y117066D02*
X863863Y118510D01*
G01X863376Y114179D02*
Y117066D01*
G01X863863Y112736D02*
X863376Y114179D01*
G01X864351Y112014D02*
X863863Y112736D01*
G01X865325Y111292D02*
X864351Y112014D01*
G01X857042D02*
X857530Y111292D01*
G01X857042D02*
Y112014D01*
G01X857530Y111292D02*
X857042D01*
G01X847786Y129284D02*
X852171D01*
G01X851196Y135780D02*
X847786Y129284D01*
G01X851196Y127119D02*
Y135780D01*
G01X866300Y127841D02*
X865325Y127119D01*
G01Y135780D02*
X866300Y135058D01*
G01X864351D02*
X865325Y135780D01*
G01X863863Y134337D02*
X864351Y135058D01*
G01X863376Y132893D02*
X863863Y134337D01*
G01X863376Y130006D02*
Y132893D01*
G01X863863Y128562D02*
X863376Y130006D01*
G01X864351Y127841D02*
X863863Y128562D01*
G01X865325Y127119D02*
X864351Y127841D01*
G01X857042D02*
X857530Y127119D01*
G01X857042D02*
Y127841D01*
G01X857530Y127119D02*
X857042D01*
G01X863731Y155386D02*
X867629D01*
G01X864218Y157552D02*
X863731Y155386D01*
G01X865192Y158995D02*
X864218Y157552D01*
G01X866167Y159717D02*
X865192Y158995D01*
G01Y164048D02*
X866167D01*
G01X864218Y163326D02*
X865192Y164048D01*
G01X863731Y162604D02*
X864218Y163326D01*
G01X857397Y156108D02*
X857885Y155386D01*
G01X857397D02*
Y156108D01*
G01X857885Y155386D02*
X857397D01*
G01X850089Y164048D02*
Y155386D01*
G01X847387Y181909D02*
X847874Y184074D01*
G01X846900Y178300D02*
X847387Y181909D01*
G01X848848Y186961D02*
X844951D01*
G01X847874Y184074D02*
X848848Y186961D01*
G01X863464Y179022D02*
X862490Y178300D01*
G01X863951Y179743D02*
X863464Y179022D01*
G01X864439Y181187D02*
X863951Y179743D01*
G01X864439Y184074D02*
Y181187D01*
G01X863951Y185518D02*
X864439Y184074D01*
G01X863464Y186239D02*
X863951Y185518D01*
G01X862490Y186961D02*
X863464Y186239D01*
G01X861516D02*
X862490Y186961D01*
G01X861028Y185518D02*
X861516Y186239D01*
G01X860541Y184074D02*
X861028Y185518D01*
G01X860541Y181187D02*
Y184074D01*
G01X861028Y179743D02*
X860541Y181187D01*
G01X861516Y179022D02*
X861028Y179743D01*
G01X862490Y178300D02*
X861516Y179022D01*
G01X854207D02*
X854695Y178300D01*
G01X854207D02*
Y179022D01*
G01X854695Y178300D02*
X854207D01*
G01X845173Y495988D02*
X844199Y495266D01*
G01X845660Y496710D02*
X845173Y495988D01*
G01X846148Y498154D02*
X845660Y496710D01*
G01X846148Y501041D02*
Y498154D01*
G01X845660Y502484D02*
X846148Y501041D01*
G01X845173Y503206D02*
X845660Y502484D01*
G01X844199Y503928D02*
X845173Y503206D01*
G01X860764Y495988D02*
X859789Y495266D01*
G01X861251Y496710D02*
X860764Y495988D01*
G01X861738Y498154D02*
X861251Y496710D01*
G01X861738Y501041D02*
Y498154D01*
G01X861251Y502484D02*
X861738Y501041D01*
G01X860764Y503206D02*
X861251Y502484D01*
G01X859789Y503928D02*
X860764Y503206D01*
G01X858815D02*
X859789Y503928D01*
G01X858327Y502484D02*
X858815Y503206D01*
G01X857840Y501041D02*
X858327Y502484D01*
G01X857840Y498154D02*
Y501041D01*
G01X858327Y496710D02*
X857840Y498154D01*
G01X858815Y495988D02*
X858327Y496710D01*
G01X859789Y495266D02*
X858815Y495988D01*
G01X865636Y501041D02*
X866123Y502484D01*
G01X865636Y498154D02*
Y501041D01*
G01X866123Y496710D02*
X865636Y498154D01*
G01X851507Y495988D02*
X851994Y495266D01*
G01X851507D02*
Y495988D01*
G01X851994Y495266D02*
X851507D01*
G01X845148Y590936D02*
X844173Y590214D01*
G01X846122Y591658D02*
X845148Y590936D01*
G01X846609Y592379D02*
X846122Y591658D01*
G01X846609Y593823D02*
Y592379D01*
G01X846122Y594545D02*
X846609Y593823D01*
G01X845148Y595266D02*
X846122Y594545D01*
G01X844173Y595266D02*
X845148D01*
G01X850994Y587327D02*
X850507Y588049D01*
G01X851968Y586605D02*
X850994Y587327D01*
G01X852943Y586605D02*
X851968D01*
G01X853917Y587327D02*
X852943Y586605D01*
G01X854405Y588049D02*
X853917Y587327D01*
G01X854892Y588770D02*
X854405Y588049D01*
G01X854892Y589492D02*
Y588770D01*
G01X854405Y590214D02*
X854892Y589492D01*
G01X853917Y590936D02*
X854405Y590214D01*
G01X852943Y591658D02*
X853917Y590936D01*
G01Y592379D02*
X852943Y591658D01*
G01X854405Y593101D02*
X853917Y592379D01*
G01X854405Y593823D02*
Y593101D01*
G01X853917Y594545D02*
X854405Y593823D01*
G01X852943Y595266D02*
X853917Y594545D01*
G01X851968Y595266D02*
X852943D01*
G01X850994Y594545D02*
X851968Y595266D01*
G01X859764Y587327D02*
X860251Y586605D01*
G01X859764D02*
Y587327D01*
G01X860251Y586605D02*
X859764D01*
G01X851968Y591658D02*
X852943D01*
G01X882596Y80215D02*
X881874Y81189D01*
G01X883318Y79728D02*
X882596Y80215D01*
G01X884761Y79240D02*
X883318Y79728D01*
G01X887649Y79240D02*
X884761D01*
G01X889092Y79728D02*
X887649Y79240D01*
G01Y67547D02*
X889092Y67060D01*
G01X884761Y67547D02*
X887649D01*
G01X883318Y67060D02*
X884761Y67547D01*
G01X882596Y66573D02*
X883318Y67060D01*
G01X881874Y65599D02*
X882596Y66573D01*
G01Y64624D02*
X881874Y65599D01*
G01X883318Y64137D02*
X882596Y64624D01*
G01X884761Y63650D02*
X883318Y64137D01*
G01X887649Y63650D02*
X884761D01*
G01X889092Y64137D02*
X887649Y63650D01*
G01Y90933D02*
X889092Y90446D01*
G01X884761Y90933D02*
X887649D01*
G01X883318Y90446D02*
X884761Y90933D01*
G01X882596Y89959D02*
X883318Y90446D01*
G01X881874Y88984D02*
X882596Y89959D01*
G01Y88010D02*
X881874Y88984D01*
G01X883318Y87523D02*
X882596Y88010D01*
G01X884761Y87036D02*
X883318Y87523D01*
G01X887649Y87036D02*
X884761D01*
G01X889092Y87523D02*
X887649Y87036D01*
G01Y83138D02*
X889092Y82651D01*
G01X884761Y83138D02*
X887649D01*
G01X883318Y82651D02*
X884761Y83138D01*
G01X882596Y82163D02*
X883318Y82651D01*
G01X881874Y81189D02*
X882596Y82163D01*
G01X896244Y124953D02*
X881349D01*
G01X892701Y109126D02*
X881349D01*
G01X866787Y112736D02*
X866300Y112014D01*
G01X867274Y114179D02*
X866787Y112736D01*
G01X867274Y117066D02*
Y114179D01*
G01X866787Y118510D02*
X867274Y117066D01*
G01X866300Y119232D02*
X866787Y118510D01*
G01X874095Y112014D02*
X873120Y111292D01*
G01X874582Y112736D02*
X874095Y112014D01*
G01X875069Y114179D02*
X874582Y112736D01*
G01X875069Y117066D02*
Y114179D01*
G01X874582Y118510D02*
X875069Y117066D01*
G01X874095Y119232D02*
X874582Y118510D01*
G01X873120Y119953D02*
X874095Y119232D01*
G01X872146D02*
X873120Y119953D01*
G01X871659Y118510D02*
X872146Y119232D01*
G01X871172Y117066D02*
X871659Y118510D01*
G01X871172Y114179D02*
Y117066D01*
G01X871659Y112736D02*
X871172Y114179D01*
G01X872146Y112014D02*
X871659Y112736D01*
G01X873120Y111292D02*
X872146Y112014D01*
G01X866787Y128562D02*
X866300Y127841D01*
G01X867274Y130006D02*
X866787Y128562D01*
G01X867274Y132893D02*
Y130006D01*
G01X866787Y134337D02*
X867274Y132893D01*
G01X866300Y135058D02*
X866787Y134337D01*
G01X875069Y132893D02*
X874582Y132171D01*
G01X875069Y134337D02*
Y132893D01*
G01X874582Y135058D02*
X875069Y134337D01*
G01X873607Y135780D02*
X874582Y135058D01*
G01X872633Y135780D02*
X873607D01*
G01X871659Y135058D02*
X872633Y135780D01*
G01X871172Y134337D02*
X871659Y135058D01*
G01X871172Y127119D02*
X875069D01*
G01X871659Y129284D02*
X871172Y127119D01*
G01X872633Y130728D02*
X871659Y129284D01*
G01X874582Y132171D02*
X872633Y130728D01*
G01X912736Y153221D02*
X881703D01*
G01X874450Y156108D02*
X873475Y155386D01*
G01X874937Y156830D02*
X874450Y156108D01*
G01X875424Y158274D02*
X874937Y156830D01*
G01X875424Y161161D02*
Y158274D01*
G01X874937Y162604D02*
X875424Y161161D01*
G01X874450Y163326D02*
X874937Y162604D01*
G01X873475Y164048D02*
X874450Y163326D01*
G01X872501D02*
X873475Y164048D01*
G01X872013Y162604D02*
X872501Y163326D01*
G01X871526Y161161D02*
X872013Y162604D01*
G01X871526Y158274D02*
Y161161D01*
G01X872013Y156830D02*
X871526Y158274D01*
G01X872501Y156108D02*
X872013Y156830D01*
G01X873475Y155386D02*
X872501Y156108D01*
G01X867141Y160439D02*
X866167Y159717D01*
G01X867629Y161161D02*
X867141Y160439D01*
G01X867629Y162604D02*
Y161161D01*
G01X867141Y163326D02*
X867629Y162604D01*
G01X866167Y164048D02*
X867141Y163326D01*
G01X904512Y176134D02*
X878514D01*
G01X868337Y178300D02*
X872234D01*
G01X868824Y180465D02*
X868337Y178300D01*
G01X869798Y181909D02*
X868824Y180465D01*
G01X870772Y182630D02*
X869798Y181909D01*
G01X871747Y183352D02*
X870772Y182630D01*
G01X872234Y184074D02*
X871747Y183352D01*
G01X872234Y185518D02*
Y184074D01*
G01X871747Y186239D02*
X872234Y185518D01*
G01X870772Y186961D02*
X871747Y186239D01*
G01X869798Y186961D02*
X870772D01*
G01X868824Y186239D02*
X869798Y186961D01*
G01X868337Y185518D02*
X868824Y186239D01*
G01X886627Y456303D02*
X887350Y456791D01*
G01Y456303D02*
X886627D01*
G01X887350Y456791D02*
Y456303D01*
G01X886627Y465560D02*
X887350Y464586D01*
G01X885906Y466047D02*
X886627Y465560D01*
G01X884462Y466535D02*
X885906Y466047D01*
G01X881575Y466535D02*
X884462D01*
G01X880131Y466047D02*
X881575Y466535D01*
G01X879410Y465560D02*
X880131Y466047D01*
G01X878688Y464586D02*
X879410Y465560D01*
G01Y463612D02*
X878688Y464586D01*
G01X880131Y463124D02*
X879410Y463612D01*
G01X881575Y462637D02*
X880131Y463124D01*
G01X884462Y462637D02*
X881575D01*
G01X885906Y463124D02*
X884462Y462637D01*
G01X886627Y463612D02*
X885906Y463124D01*
G01X887350Y464586D02*
X886627Y463612D01*
G01Y449970D02*
X887350Y448995D01*
G01X885906Y450457D02*
X886627Y449970D01*
G01X884462Y450944D02*
X885906Y450457D01*
G01X881575Y450944D02*
X884462D01*
G01X880131Y450457D02*
X881575Y450944D01*
G01X879410Y449970D02*
X880131Y450457D01*
G01X878688Y448995D02*
X879410Y449970D01*
G01Y448021D02*
X878688Y448995D01*
G01X880131Y447534D02*
X879410Y448021D01*
G01X881575Y447047D02*
X880131Y447534D01*
G01X884462Y447047D02*
X881575D01*
G01X885906Y447534D02*
X884462Y447047D01*
G01X886627Y448021D02*
X885906Y447534D01*
G01X887350Y448995D02*
X886627Y448021D01*
G01Y473356D02*
X887350Y472381D01*
G01X885906Y473843D02*
X886627Y473356D01*
G01X884462Y474330D02*
X885906Y473843D01*
G01X881575Y474330D02*
X884462D01*
G01X880131Y473843D02*
X881575Y474330D01*
G01X879410Y473356D02*
X880131Y473843D01*
G01X878688Y472381D02*
X879410Y473356D01*
G01Y471407D02*
X878688Y472381D01*
G01X880131Y470919D02*
X879410Y471407D01*
G01X881575Y470432D02*
X880131Y470919D01*
G01X884462Y470432D02*
X881575D01*
G01X885906Y470919D02*
X884462Y470432D01*
G01X886627Y471407D02*
X885906Y470919D01*
G01X887350Y472381D02*
X886627Y471407D01*
G01X889515Y493101D02*
X875813D01*
G01X868559Y495988D02*
X867585Y495266D01*
G01X869046Y496710D02*
X868559Y495988D01*
G01X869533Y498154D02*
X869046Y496710D01*
G01X869533Y501041D02*
Y498154D01*
G01X869046Y502484D02*
X869533Y501041D01*
G01X868559Y503206D02*
X869046Y502484D01*
G01X867585Y503928D02*
X868559Y503206D01*
G01X866610D02*
X867585Y503928D01*
G01X866123Y502484D02*
X866610Y503206D01*
G01Y495988D02*
X866123Y496710D01*
G01X867585Y495266D02*
X866610Y495988D01*
G01X889515Y584439D02*
X884070D01*
G01X866098Y586605D02*
X869995D01*
G01X866585Y588770D02*
X866098Y586605D01*
G01X867559Y590214D02*
X866585Y588770D01*
G01X868533Y590936D02*
X867559Y590214D01*
G01X869508Y591658D02*
X868533Y590936D01*
G01X869995Y592379D02*
X869508Y591658D01*
G01X869995Y593823D02*
Y592379D01*
G01X869508Y594545D02*
X869995Y593823D01*
G01X868533Y595266D02*
X869508Y594545D01*
G01X867559Y595266D02*
X868533D01*
G01X866585Y594545D02*
X867559Y595266D01*
G01X866098Y593823D02*
X866585Y594545D01*
G01X876816Y587327D02*
X875842Y586605D01*
G01X877303Y588049D02*
X876816Y587327D01*
G01X877790Y589492D02*
X877303Y588049D01*
G01X877790Y592379D02*
Y589492D01*
G01X877303Y593823D02*
X877790Y592379D01*
G01X876816Y594545D02*
X877303Y593823D01*
G01X875842Y595266D02*
X876816Y594545D01*
G01X874867D02*
X875842Y595266D01*
G01X874380Y593823D02*
X874867Y594545D01*
G01X873893Y592379D02*
X874380Y593823D01*
G01X873893Y589492D02*
Y592379D01*
G01X874380Y588049D02*
X873893Y589492D01*
G01X874867Y587327D02*
X874380Y588049D01*
G01X875842Y586605D02*
X874867Y587327D01*
G01X889814Y72907D02*
X890536Y73394D01*
G01Y72907D02*
X889814D01*
G01X890536Y73394D02*
Y72907D01*
G01X907531Y79576D02*
X906809Y79089D01*
G01X908252Y80550D02*
X907531Y79576D01*
G01X908252Y81525D02*
Y80550D01*
G01X902478D02*
Y81525D01*
G01X903200Y79576D02*
X902478Y80550D01*
G01X899591Y80063D02*
X903200Y79576D01*
G01X899591Y82986D02*
Y80063D01*
G01X907531Y72755D02*
X908252Y73242D01*
G01Y72755D02*
X907531D01*
G01X908252Y73242D02*
Y72755D01*
G01X906087Y63498D02*
Y67883D01*
G01X899591Y66908D02*
X906087Y63498D01*
G01X908252Y66908D02*
X899591D01*
G01X889814Y80215D02*
X889092Y79728D01*
G01X890536Y81189D02*
X889814Y80215D01*
G01Y66573D02*
X890536Y65599D01*
G01X889092Y67060D02*
X889814Y66573D01*
G01Y64624D02*
X889092Y64137D01*
G01X890536Y65599D02*
X889814Y64624D01*
G01X892701Y109126D02*
Y97213D01*
G01X910418Y149284D02*
Y97061D01*
G01X907531Y82499D02*
X908252Y81525D01*
G01X906809Y82986D02*
X907531Y82499D01*
G01X905365Y83473D02*
X906809Y82986D01*
G01X903922D02*
X905365Y83473D01*
G01X903200Y82499D02*
X903922Y82986D01*
G01X902478Y81525D02*
X903200Y82499D01*
G01X889814Y89959D02*
X890536Y88984D01*
G01X889092Y90446D02*
X889814Y89959D01*
G01Y88010D02*
X889092Y87523D01*
G01X890536Y88984D02*
X889814Y88010D01*
G01Y82163D02*
X890536Y81189D01*
G01X889092Y82651D02*
X889814Y82163D01*
G01X907531Y89807D02*
X908252Y88833D01*
G01X906809Y90294D02*
X907531Y89807D01*
G01X905365Y90782D02*
X906809Y90294D01*
G01X902478Y90782D02*
X905365D01*
G01X901034Y90294D02*
X902478Y90782D01*
G01X900313Y89807D02*
X901034Y90294D01*
G01X899591Y88833D02*
X900313Y89807D01*
G01Y87858D02*
X899591Y88833D01*
G01X901034Y87371D02*
X900313Y87858D01*
G01X902478Y86884D02*
X901034Y87371D01*
G01X905365Y86884D02*
X902478D01*
G01X906809Y87371D02*
X905365Y86884D01*
G01X907531Y87858D02*
X906809Y87371D01*
G01X908252Y88833D02*
X907531Y87858D01*
G01X892701Y113063D02*
G03X896638Y109126I3937J0D01*
G01X892701Y113063D02*
G03X896638Y109126I3937J0D01*
G01X916717Y124953D02*
G03I-8268J0D01*
G01X920260D02*
G03I-11811J0D01*
G01X896638Y109126D02*
X1264748D01*
G01X896638D02*
X1264748D01*
G01X892701Y196528D02*
Y113063D01*
G01Y196528D02*
Y113063D01*
G01X914709Y153221D02*
G03I-4291J0D01*
G01X914945Y176134D02*
G03I-6496J0D01*
G01X920260D02*
G03I-11811J0D01*
G01X908449Y180071D02*
Y221862D01*
G01X896638Y200465D02*
G03X892701Y196528I0J-3937D01*
G01X896638Y200465D02*
G03X892701Y196528I0J-3937D01*
G01X1085614Y200465D02*
X896638D01*
G01X1085615D02*
X896638D01*
G01X901231Y231551D02*
X902675Y229602D01*
G01X900509Y232039D02*
X901231Y231551D01*
G01X899066Y232039D02*
X900509D01*
G01X898344Y231551D02*
X899066Y232039D01*
G01X897622Y230577D02*
X898344Y231551D01*
G01X897622Y229602D02*
Y230577D01*
G01X898344Y228628D02*
X897622Y229602D01*
G01X899066Y228141D02*
X898344Y228628D01*
G01X906284Y228141D02*
Y232039D01*
G01X904118Y228628D02*
X906284Y228141D01*
G01X902675Y229602D02*
X904118Y228628D01*
G01X906284Y235936D02*
X897622Y239834D01*
G01Y235936D02*
X906284Y239834D01*
G01X905562Y252988D02*
X906284Y253476D01*
G01Y252988D02*
X905562D01*
G01X906284Y253476D02*
Y252988D01*
G01X905562Y262245D02*
X906284Y261271D01*
G01X904840Y262732D02*
X905562Y262245D01*
G01X898344D02*
X899066Y262732D01*
G01X897622Y261271D02*
X898344Y262245D01*
G01Y260297D02*
X897622Y261271D01*
G01X899066Y259809D02*
X898344Y260297D01*
G01X900509Y259322D02*
X899066Y259809D01*
G01X903397Y259322D02*
X900509D01*
G01X904840Y259809D02*
X903397Y259322D01*
G01X905562Y260297D02*
X904840Y259809D01*
G01X906284Y261271D02*
X905562Y260297D01*
G01X904118Y243732D02*
Y248116D01*
G01X897622Y247142D02*
X904118Y243732D01*
G01X906284Y247142D02*
X897622D01*
G01X905562Y270041D02*
X906284Y269066D01*
G01X904840Y270528D02*
X905562Y270041D01*
G01X903397Y271015D02*
X904840Y270528D01*
G01X900509Y271015D02*
X903397D01*
G01X899066Y270528D02*
X900509Y271015D01*
G01X898344Y270041D02*
X899066Y270528D01*
G01X897622Y269066D02*
X898344Y270041D01*
G01Y268092D02*
X897622Y269066D01*
G01X899066Y267604D02*
X898344Y268092D01*
G01X900509Y267117D02*
X899066Y267604D01*
G01X903397Y267117D02*
X900509D01*
G01X904840Y267604D02*
X903397Y267117D01*
G01X905562Y268092D02*
X904840Y267604D01*
G01X906284Y269066D02*
X905562Y268092D01*
G01X903397Y263220D02*
X904840Y262732D01*
G01X900509Y263220D02*
X903397D01*
G01X899066Y262732D02*
X900509Y263220D01*
G01X889515Y493101D02*
Y480610D01*
G01Y497038D02*
G03X893452Y493101I3937J0D01*
G01X889515Y497038D02*
G03X893452Y493101I3937J0D01*
G01X913531Y508928D02*
G03I-8268J0D01*
G01X916090D02*
G03I-10827J0D01*
G01X893452Y493101D02*
X1261562D01*
G01X893452D02*
X1261562D01*
G01X889515Y580502D02*
Y497038D01*
G01Y580502D02*
Y497038D01*
G01X911523Y537195D02*
G03I-4292J0D01*
G01X909392Y519399D02*
X909515Y519441D01*
G01X908859Y519274D02*
X908735Y519232D01*
G01Y519399D02*
X908859Y519441D01*
G01X907546Y519399D02*
X907669Y519441D01*
G01X907013Y519274D02*
X906890Y519232D01*
G01Y519399D02*
X907013Y519441D01*
G01X909474Y519274D02*
X909392Y519232D01*
G01X907628Y519274D02*
X907546Y519232D01*
G01X904470Y519399D02*
X903896Y519106D01*
G01X903609D02*
X904388Y519525D01*
G01X905537Y520069D02*
X905290Y520028D01*
G01X905537Y518101D02*
X905783Y518143D01*
G01X905537Y519860D02*
X905332Y519818D01*
G01X905537Y518310D02*
X905742Y518352D01*
G01X905783Y518143D02*
X905988Y518269D01*
G01X905290Y520028D02*
X905086Y519902D01*
G01X905742Y518352D02*
X905865Y518436D01*
G01X905332Y519818D02*
X905209Y519734D01*
G01X903035Y520069D02*
X903281D01*
G01X901641D02*
X901887D01*
G01X909515Y519441D02*
X909679D01*
G01X908448D02*
X908653D01*
G01X908859D02*
X909023D01*
G01X907669D02*
X907833D01*
G01X906603D02*
X906808D01*
G01X907013D02*
X907177D01*
G01X901887Y519274D02*
X903035D01*
G01X907095D02*
X907013D01*
G01X908940D02*
X908859D01*
G01X907751D02*
X907628D01*
G01X909597D02*
X909474D01*
G01X903035Y519023D02*
X901887D01*
G01Y518101D02*
X901641D01*
G01X903281D02*
X903035D01*
G01X906808D02*
X906603D01*
G01X907464D02*
X907259D01*
G01X908653D02*
X908448D01*
G01X908120D02*
X907915D01*
G01X909966D02*
X909761D01*
G01X909310D02*
X909105D01*
G01X909392Y519232D02*
X909351Y519190D01*
G01X909269Y519274D02*
X909392Y519399D01*
G01X908735Y519232D02*
X908653Y519148D01*
G01Y519316D02*
X908735Y519399D01*
G01X907546Y519232D02*
X907505Y519190D01*
G01X907423Y519274D02*
X907546Y519399D01*
G01X905988Y518269D02*
X906111Y518394D01*
G01X906890Y519232D02*
X906808Y519148D01*
G01Y519316D02*
X906890Y519399D01*
G01X905086Y519902D02*
X904963Y519776D01*
G01X905742Y519818D02*
X905537Y519860D01*
G01X905332Y518352D02*
X905537Y518310D01*
G01X905783Y520028D02*
X905537Y520069D01*
G01X905290Y518143D02*
X905537Y518101D01*
G01X909679Y519441D02*
X909802Y519399D01*
G01X909023Y519441D02*
X909146Y519399D01*
G01X907833Y519441D02*
X907956Y519399D01*
G01X907177Y519441D02*
X907300Y519399D01*
G01X905865Y518436D02*
X906029Y518687D01*
G01X905209Y519734D02*
X905044Y519483D01*
G01X904470Y518813D02*
X904388Y518687D01*
G01X909351Y519190D02*
X909310Y519106D01*
G01X907505Y519190D02*
X907464Y519106D01*
G01X906111Y518394D02*
X906193Y518562D01*
G01X904963Y519776D02*
X904881Y519609D01*
G01X904388Y518687D02*
X903609Y519106D01*
G01X909679Y519232D02*
X909597Y519274D01*
G01X909023Y519232D02*
X908940Y519274D01*
G01X907833Y519232D02*
X907751Y519274D01*
G01X907177Y519232D02*
X907095Y519274D01*
G01X903896Y519106D02*
X904470Y518813D01*
G01X906193Y518562D02*
X906234Y518687D01*
G01X904881Y519609D02*
X904840Y519483D01*
G01X905865Y519734D02*
X905742Y519818D01*
G01X905209Y518436D02*
X905332Y518352D01*
G01X905988Y519902D02*
X905783Y520028D01*
G01X905086Y518269D02*
X905290Y518143D01*
G01X906234Y518687D02*
X906275Y518897D01*
G01X904840Y519483D02*
X904798Y519274D01*
G01X909802Y519399D02*
X909884Y519316D01*
G01X909720Y519190D02*
X909679Y519232D01*
G01X909146Y519399D02*
X909269Y519274D01*
G01X909064Y519190D02*
X909023Y519232D01*
G01X907956Y519399D02*
X908038Y519316D01*
G01X907874Y519190D02*
X907833Y519232D01*
G01X907300Y519399D02*
X907423Y519274D01*
G01X907218Y519190D02*
X907177Y519232D01*
G01X906111Y519776D02*
X905988Y519902D01*
G01X904963Y518394D02*
X905086Y518269D01*
G01X906029Y518687D02*
X906070Y518939D01*
G01X905044Y519483D02*
X905003Y519232D01*
G01X909966Y519106D02*
Y518101D01*
G01X909761D02*
Y519106D01*
G01X909310D02*
Y518101D01*
G01X909105D02*
Y519106D01*
G01X908653Y519441D02*
Y519316D01*
G01Y519148D02*
Y518101D01*
G01X908448D02*
Y519441D01*
G01X908120Y519106D02*
Y518101D01*
G01X907915D02*
Y519106D01*
G01X907464D02*
Y518101D01*
G01X907259D02*
Y519106D01*
G01X906808Y519441D02*
Y519316D01*
G01Y519148D02*
Y518101D01*
G01X906603D02*
Y519441D01*
G01X906275Y518897D02*
Y519274D01*
G01X906070Y518939D02*
Y519232D01*
G01D02*
X906029Y519483D01*
G01X905003Y518939D02*
X905044Y518687D01*
G01X906275Y519274D02*
X906234Y519483D01*
G01X904798Y518897D02*
X904840Y518687D01*
G01X906234Y519483D02*
X906193Y519609D01*
G01X904840Y518687D02*
X904881Y518562D01*
G01X909884Y519316D02*
X909966Y519106D01*
G01X908038Y519316D02*
X908120Y519106D01*
G01X909761D02*
X909720Y519190D01*
G01X909105Y519106D02*
X909064Y519190D01*
G01X907915Y519106D02*
X907874Y519190D01*
G01X907259Y519106D02*
X907218Y519190D01*
G01X906193Y519609D02*
X906111Y519776D01*
G01X904881Y518562D02*
X904963Y518394D01*
G01X906029Y519483D02*
X905865Y519734D01*
G01X905044Y518687D02*
X905209Y518436D01*
G01X904388Y519525D02*
X904470Y519399D01*
G01X905003Y519232D02*
Y518939D01*
G01X904798Y519274D02*
Y518897D01*
G01X903281Y520069D02*
Y518101D01*
G01X903035Y519274D02*
Y520069D01*
G01Y518101D02*
Y519023D01*
G01X901887D02*
Y518101D01*
G01Y520069D02*
Y519274D01*
G01X901641Y518101D02*
Y520069D01*
G01X911759Y560109D02*
G03I-6496J0D01*
G01X916090D02*
G03I-10827J0D01*
G01X905615Y570069D02*
X905369Y570028D01*
G01X905615Y568101D02*
X905861Y568143D01*
G01X905615Y569860D02*
X905411Y569818D01*
G01X905615Y568310D02*
X905820Y568352D01*
G01X909470Y569399D02*
X909594Y569441D01*
G01X908937Y569274D02*
X908814Y569232D01*
G01Y569399D02*
X908937Y569441D01*
G01X907625Y569399D02*
X907748Y569441D01*
G01X907092Y569274D02*
X906969Y569232D01*
G01Y569399D02*
X907092Y569441D01*
G01X903114Y570069D02*
X903360D01*
G01X901720D02*
X901966D01*
G01X909594Y569441D02*
X909757D01*
G01X908527D02*
X908732D01*
G01X908937D02*
X909101D01*
G01X907748D02*
X907912D01*
G01X906682D02*
X906887D01*
G01X907092D02*
X907256D01*
G01X901966Y569274D02*
X903114D01*
G01X907174D02*
X907092D01*
G01X909019D02*
X908937D01*
G01X907830D02*
X907707D01*
G01X909676D02*
X909552D01*
G01X903114Y569023D02*
X901966D01*
G01Y568101D02*
X901720D01*
G01X903360D02*
X903114D01*
G01X906887D02*
X906682D01*
G01X907543D02*
X907338D01*
G01X908732D02*
X908527D01*
G01X908199D02*
X907994D01*
G01X910044D02*
X909840D01*
G01X909388D02*
X909183D01*
G01X909552Y569274D02*
X909470Y569232D01*
G01X907707Y569274D02*
X907625Y569232D01*
G01X904549Y569399D02*
X903975Y569106D01*
G01X905861Y570028D02*
X905615Y570069D01*
G01X905369Y568143D02*
X905615Y568101D01*
G01X903688Y569106D02*
X904467Y569525D01*
G01X905861Y568143D02*
X906066Y568269D01*
G01X905369Y570028D02*
X905164Y569902D01*
G01X905820Y569818D02*
X905615Y569860D01*
G01X905411Y568352D02*
X905615Y568310D01*
G01X905820Y568352D02*
X905944Y568436D01*
G01X905411Y569818D02*
X905287Y569734D01*
G01X909757Y569441D02*
X909881Y569399D01*
G01X909101Y569441D02*
X909224Y569399D01*
G01X907912Y569441D02*
X908035Y569399D01*
G01X907256Y569441D02*
X907379Y569399D01*
G01X909470Y569232D02*
X909429Y569190D01*
G01X909348Y569274D02*
X909470Y569399D01*
G01X908814Y569232D02*
X908732Y569148D01*
G01Y569316D02*
X908814Y569399D01*
G01X907625Y569232D02*
X907584Y569190D01*
G01X907502Y569274D02*
X907625Y569399D01*
G01X906066Y568269D02*
X906190Y568394D01*
G01X906969Y569232D02*
X906887Y569148D01*
G01Y569316D02*
X906969Y569399D01*
G01X905164Y569902D02*
X905041Y569776D01*
G01X906066Y569902D02*
X905861Y570028D01*
G01X904467Y568687D02*
X903688Y569106D01*
G01X909757Y569232D02*
X909676Y569274D01*
G01X909101Y569232D02*
X909019Y569274D01*
G01X907912Y569232D02*
X907830Y569274D01*
G01X907256Y569232D02*
X907174Y569274D01*
G01X903975Y569106D02*
X904549Y568813D01*
G01X905944Y569734D02*
X905820Y569818D01*
G01X905287Y568436D02*
X905411Y568352D01*
G01X905164Y568269D02*
X905369Y568143D01*
G01X905944Y568436D02*
X906107Y568687D01*
G01X905287Y569734D02*
X905123Y569483D01*
G01X904549Y568813D02*
X904467Y568687D01*
G01X909881Y569399D02*
X909963Y569316D01*
G01X909798Y569190D02*
X909757Y569232D01*
G01X909224Y569399D02*
X909348Y569274D01*
G01X909142Y569190D02*
X909101Y569232D01*
G01X909429Y569190D02*
X909388Y569106D01*
G01X907584Y569190D02*
X907543Y569106D01*
G01X906190Y568394D02*
X906272Y568562D01*
G01X905041Y569776D02*
X904959Y569609D01*
G01X908035Y569399D02*
X908117Y569316D01*
G01X907953Y569190D02*
X907912Y569232D01*
G01X907379Y569399D02*
X907502Y569274D01*
G01X907297Y569190D02*
X907256Y569232D01*
G01X906190Y569776D02*
X906066Y569902D01*
G01X905041Y568394D02*
X905164Y568269D01*
G01X906272Y568562D02*
X906313Y568687D01*
G01X904959Y569609D02*
X904918Y569483D01*
G01X909963Y569316D02*
X910044Y569106D01*
G01X908117Y569316D02*
X908199Y569106D01*
G01X909840D02*
X909798Y569190D01*
G01X909183Y569106D02*
X909142Y569190D01*
G01X907994Y569106D02*
X907953Y569190D01*
G01X907338Y569106D02*
X907297Y569190D01*
G01X906272Y569609D02*
X906190Y569776D01*
G01X904959Y568562D02*
X905041Y568394D01*
G01X906107Y569483D02*
X905944Y569734D01*
G01X905123Y568687D02*
X905287Y568436D01*
G01X904467Y569525D02*
X904549Y569399D01*
G01X906313Y568687D02*
X906353Y568897D01*
G01X904918Y569483D02*
X904877Y569274D01*
G01X906107Y568687D02*
X906149Y568939D01*
G01X905123Y569483D02*
X905082Y569232D01*
G01X910044Y569106D02*
Y568101D01*
G01X909840D02*
Y569106D01*
G01X909388D02*
Y568101D01*
G01X909183D02*
Y569106D01*
G01X908732Y569148D02*
Y568101D01*
G01Y569441D02*
Y569316D01*
G01X908527Y568101D02*
Y569441D01*
G01X908199Y569106D02*
Y568101D01*
G01X907994D02*
Y569106D01*
G01X907543D02*
Y568101D01*
G01X907338D02*
Y569106D01*
G01X906887Y569148D02*
Y568101D01*
G01Y569441D02*
Y569316D01*
G01X906682Y568101D02*
Y569441D01*
G01X906353Y568897D02*
Y569274D01*
G01X906149Y568939D02*
Y569232D01*
G01D02*
X906107Y569483D01*
G01X905082Y568939D02*
X905123Y568687D01*
G01X906353Y569274D02*
X906313Y569483D01*
G01X904877Y568897D02*
X904918Y568687D01*
G01X906313Y569483D02*
X906272Y569609D01*
G01X904918Y568687D02*
X904959Y568562D01*
G01X905082Y569232D02*
Y568939D01*
G01X904877Y569274D02*
Y568897D01*
G01X903360Y570069D02*
Y568101D01*
G01X903114Y569274D02*
Y570069D01*
G01Y568101D02*
Y569023D01*
G01X901966D02*
Y568101D01*
G01Y570069D02*
Y569274D01*
G01X901720Y568101D02*
Y570069D01*
G01X897873Y568021D02*
X901758Y683536D01*
G01X893452Y584439D02*
G03X889515Y580502I0J-3937D01*
G01X893452Y584439D02*
G03X889515Y580502I0J-3937D01*
G01X1082428Y584439D02*
X893452D01*
G01X1082428D02*
X893452D01*
G01X901758Y683536D02*
X913569D01*
G01X917401Y-314506D02*
Y-118985D01*
G01X912371Y117675D02*
X956528Y35732D01*
G01X935024Y171331D02*
X930300D01*
G01X931677Y169560D02*
X936205D01*
G01X936402Y169363D02*
X931874D01*
G01Y164441D02*
X930300D01*
G01Y163457D02*
X930221D01*
G01X931874Y163260D02*
X930300D01*
G01Y162945D02*
X930221D01*
G01X930300Y160032D02*
X930221D01*
G01X930300Y159717D02*
X931874D01*
G01X930300Y159520D02*
X930221D01*
G01X931874Y158536D02*
X930300D01*
G01X931874Y153615D02*
X936402D01*
G01X936205Y153418D02*
X931677D01*
G01X930300Y151646D02*
X935024D01*
G01X931874Y153615D02*
X931677Y153418D01*
G01X931874Y169363D02*
X931677Y169560D01*
G01X931874Y169363D02*
Y153615D01*
G01X931677Y153418D02*
Y169560D01*
G01X931481Y158536D02*
Y164441D01*
G01X930300Y171331D02*
Y151646D01*
G01X930221Y163457D02*
Y159520D01*
G01X914463Y186300D02*
X938458Y226859D01*
G01X929881Y687867D02*
X929160Y690032D01*
G01X931325Y686423D02*
X929881Y687867D01*
G01X933490Y685702D02*
X931325Y686423D01*
G01X935656D02*
X933490Y685702D01*
G01X929881Y692197D02*
X931325Y693641D01*
G01X929160Y690032D02*
X929881Y692197D01*
G01X918441Y693641D02*
X918928Y692919D01*
G01X916005D02*
X916492Y693641D01*
G01X915518Y691476D02*
X916005Y692919D01*
G01X915518Y688589D02*
Y691476D01*
G01X916005Y687145D02*
X915518Y688589D01*
G01X916492Y686423D02*
X916005Y687145D01*
G01X917467Y685702D02*
X916492Y686423D01*
G01X918441D02*
X917467Y685702D01*
G01X918928Y687145D02*
X918441Y686423D01*
G01X919416Y688589D02*
X918928Y687145D01*
G01Y690032D02*
X919416Y688589D01*
G01X917467Y690754D02*
X918928Y690032D01*
G01X916005D02*
X917467Y690754D01*
G01X915518Y688589D02*
X916005Y690032D01*
G01X923313Y694363D02*
X927211Y685702D01*
G01X929881Y683536D02*
X937099Y696528D01*
G01X923313Y685702D02*
X927211Y694363D01*
G01X913569Y683536D02*
X1143385D01*
G01X933490Y694363D02*
X935656Y693641D01*
G01X931325D02*
X933490Y694363D01*
G01X917467D02*
X918441Y693641D01*
G01X916492D02*
X917467Y694363D01*
G01X950472Y-390518D02*
Y-407840D01*
G01X956528Y35732D02*
X959678D01*
G01X939540Y134201D02*
X939551Y134126D01*
G01X939511Y134269D02*
X939540Y134201D01*
G01X939469Y134323D02*
X939511Y134269D01*
G01X940744Y133658D02*
X940733Y133733D01*
G01X940773Y133591D02*
X940744Y133658D01*
G01X940815Y133536D02*
X940773Y133591D01*
G01X939540Y138138D02*
X939551Y138063D01*
G01X939511Y138206D02*
X939540Y138138D01*
G01X939469Y138260D02*
X939511Y138206D01*
G01X940744Y137595D02*
X940733Y137670D01*
G01X940773Y137528D02*
X940744Y137595D01*
G01X940815Y137473D02*
X940773Y137528D01*
G01X943871Y134201D02*
X943882Y134126D01*
G01X943842Y134269D02*
X943871Y134201D01*
G01X943800Y134323D02*
X943842Y134269D01*
G01X939953Y134321D02*
X939950Y134323D01*
G01X939955Y134316D02*
X939953Y134321D01*
G01X939958Y134306D02*
X939955Y134316D01*
G01X940961Y133538D02*
X940964Y133536D01*
G01X940959Y133544D02*
X940961Y133538D01*
G01X940956Y133554D02*
X940959Y133544D01*
G01X939953Y138258D02*
X939950Y138260D01*
G01X939955Y138253D02*
X939953Y138258D01*
G01X939958Y138243D02*
X939955Y138253D01*
G01X940961Y137475D02*
X940964Y137473D01*
G01X940959Y137481D02*
X940961Y137475D01*
G01X940956Y137491D02*
X940959Y137481D01*
G01X939953Y142195D02*
X939950Y142197D01*
G01X939955Y142190D02*
X939953Y142195D01*
G01X939958Y142180D02*
X939955Y142190D01*
G01X940961Y141412D02*
X940964Y141410D01*
G01X940959Y141418D02*
X940961Y141412D01*
G01X940956Y141428D02*
X940959Y141418D01*
G01X939953Y146132D02*
X939950Y146134D01*
G01X939955Y146127D02*
X939953Y146132D01*
G01X939958Y146117D02*
X939955Y146127D01*
G01X940961Y145349D02*
X940964Y145347D01*
G01X940959Y145355D02*
X940961Y145349D01*
G01X940956Y145365D02*
X940959Y145355D01*
G01X945074Y133658D02*
X945063Y133733D01*
G01X945103Y133591D02*
X945074Y133658D01*
G01X945146Y133536D02*
X945103Y133591D01*
G01X939540Y142075D02*
X939551Y142000D01*
G01X939511Y142143D02*
X939540Y142075D01*
G01X939469Y142197D02*
X939511Y142143D01*
G01X940744Y141532D02*
X940733Y141607D01*
G01X940773Y141465D02*
X940744Y141532D01*
G01X940815Y141410D02*
X940773Y141465D01*
G01X943871Y138138D02*
X943882Y138063D01*
G01X943842Y138206D02*
X943871Y138138D01*
G01X943800Y138260D02*
X943842Y138206D01*
G01X945074Y137595D02*
X945063Y137670D01*
G01X945103Y137528D02*
X945074Y137595D01*
G01X945146Y137473D02*
X945103Y137528D01*
G01X939540Y146012D02*
X939551Y145937D01*
G01X939511Y146080D02*
X939540Y146012D01*
G01X939469Y146134D02*
X939511Y146080D01*
G01X940744Y145469D02*
X940733Y145544D01*
G01X940773Y145402D02*
X940744Y145469D01*
G01X940815Y145347D02*
X940773Y145402D01*
G01X943871Y142075D02*
X943882Y142000D01*
G01X943842Y142143D02*
X943871Y142075D01*
G01X943800Y142197D02*
X943842Y142143D01*
G01X945074Y141532D02*
X945063Y141607D01*
G01X945103Y141465D02*
X945074Y141532D01*
G01X945146Y141410D02*
X945103Y141465D01*
G01X943871Y146012D02*
X943882Y145937D01*
G01X943842Y146080D02*
X943871Y146012D01*
G01X943800Y146134D02*
X943842Y146080D01*
G01X945074Y145469D02*
X945063Y145544D01*
G01X945103Y145402D02*
X945074Y145469D01*
G01X945146Y145347D02*
X945103Y145402D01*
G01X939511D02*
X939469Y145347D01*
G01X939540Y145469D02*
X939511Y145402D01*
G01X939551Y145544D02*
X939540Y145469D01*
G01X939511Y141465D02*
X939469Y141410D01*
G01X939540Y141532D02*
X939511Y141465D01*
G01X939551Y141607D02*
X939540Y141532D01*
G01X940773Y146080D02*
X940815Y146134D01*
G01X940744Y146012D02*
X940773Y146080D01*
G01X940733Y145937D02*
X940744Y146012D01*
G01X939511Y137528D02*
X939469Y137473D01*
G01X939540Y137595D02*
X939511Y137528D01*
G01X939551Y137670D02*
X939540Y137595D01*
G01X940773Y142143D02*
X940815Y142197D01*
G01X940744Y142075D02*
X940773Y142143D01*
G01X940733Y142000D02*
X940744Y142075D01*
G01X939511Y133591D02*
X939469Y133536D01*
G01X939540Y133658D02*
X939511Y133591D01*
G01X939551Y133733D02*
X939540Y133658D01*
G01X940773Y138206D02*
X940815Y138260D01*
G01X940744Y138138D02*
X940773Y138206D01*
G01X940733Y138063D02*
X940744Y138138D01*
G01X940773Y134269D02*
X940815Y134323D01*
G01X940744Y134201D02*
X940773Y134269D01*
G01X940733Y134126D02*
X940744Y134201D01*
G01X943842Y145402D02*
X943800Y145347D01*
G01X943871Y145469D02*
X943842Y145402D01*
G01X943882Y145544D02*
X943871Y145469D01*
G01X943842Y141465D02*
X943800Y141410D01*
G01X943871Y141532D02*
X943842Y141465D01*
G01X943882Y141607D02*
X943871Y141532D01*
G01X945103Y146080D02*
X945146Y146134D01*
G01X945074Y146012D02*
X945103Y146080D01*
G01X945063Y145937D02*
X945074Y146012D01*
G01X943842Y137528D02*
X943800Y137473D01*
G01X943871Y137595D02*
X943842Y137528D01*
G01X943882Y137670D02*
X943871Y137595D01*
G01X945103Y142143D02*
X945146Y142197D01*
G01X945074Y142075D02*
X945103Y142143D01*
G01X945063Y142000D02*
X945074Y142075D01*
G01X943842Y133591D02*
X943800Y133536D01*
G01X943871Y133658D02*
X943842Y133591D01*
G01X943882Y133733D02*
X943871Y133658D01*
G01X945103Y138206D02*
X945146Y138260D01*
G01X945074Y138138D02*
X945103Y138206D01*
G01X945063Y138063D02*
X945074Y138138D01*
G01X945103Y134269D02*
X945146Y134323D01*
G01X945074Y134201D02*
X945103Y134269D01*
G01X945063Y134126D02*
X945074Y134201D01*
G01X940566Y133822D02*
X940735Y133794D01*
G01X940513Y133835D02*
X940566Y133822D01*
G01X940457Y133851D02*
X940513Y133835D01*
G01X940347Y134037D02*
X940179Y134066D01*
G01X940401Y134025D02*
X940347Y134037D01*
G01X940457Y134008D02*
X940401Y134025D01*
G01X940900Y133726D02*
X940928Y133686D01*
G01X940834Y133764D02*
X940900Y133726D01*
G01X940735Y133794D02*
X940834Y133764D01*
G01X940014Y134134D02*
X939985Y134174D01*
G01X940079Y134096D02*
X940014Y134134D01*
G01X940179Y134066D02*
X940079Y134096D01*
G01X940900Y137663D02*
X940928Y137623D01*
G01X940834Y137701D02*
X940900Y137663D01*
G01X940735Y137731D02*
X940834Y137701D01*
G01X940014Y138071D02*
X939985Y138111D01*
G01X940079Y138033D02*
X940014Y138071D01*
G01X940179Y138003D02*
X940079Y138033D01*
G01X940566Y137759D02*
X940735Y137731D01*
G01X940513Y137772D02*
X940566Y137759D01*
G01X940457Y137788D02*
X940513Y137772D01*
G01X940566Y141696D02*
X940735Y141668D01*
G01X940513Y141709D02*
X940566Y141696D01*
G01X940457Y141725D02*
X940513Y141709D01*
G01X940566Y145633D02*
X940735Y145605D01*
G01X940513Y145646D02*
X940566Y145633D01*
G01X940457Y145662D02*
X940513Y145646D01*
G01X940347Y137975D02*
X940179Y138003D01*
G01X940401Y137962D02*
X940347Y137975D01*
G01X940457Y137945D02*
X940401Y137962D01*
G01X940347Y141912D02*
X940179Y141940D01*
G01X940401Y141899D02*
X940347Y141912D01*
G01X940457Y141882D02*
X940401Y141899D01*
G01X940347Y145849D02*
X940179Y145877D01*
G01X940401Y145836D02*
X940347Y145849D01*
G01X940457Y145819D02*
X940401Y145836D01*
G01X940900Y141600D02*
X940928Y141560D01*
G01X940834Y141638D02*
X940900Y141600D01*
G01X940735Y141668D02*
X940834Y141638D01*
G01X940014Y142008D02*
X939985Y142048D01*
G01X940079Y141970D02*
X940014Y142008D01*
G01X940179Y141940D02*
X940079Y141970D01*
G01X940900Y145537D02*
X940928Y145497D01*
G01X940834Y145575D02*
X940900Y145537D01*
G01X940735Y145605D02*
X940834Y145575D01*
G01X940014Y145945D02*
X939985Y145985D01*
G01X940079Y145907D02*
X940014Y145945D01*
G01X940179Y145877D02*
X940079Y145907D01*
G01X940183Y145606D02*
X940298Y145625D01*
G01X940084Y145576D02*
X940183Y145606D01*
G01X940015Y145539D02*
X940084Y145576D01*
G01X939985Y145497D02*
X940015Y145539D01*
G01X940731Y145876D02*
X940616Y145857D01*
G01X940830Y145905D02*
X940731Y145876D01*
G01X940898Y145943D02*
X940830Y145905D01*
G01X940928Y145985D02*
X940898Y145943D01*
G01X940183Y141669D02*
X940298Y141687D01*
G01X940084Y141639D02*
X940183Y141669D01*
G01X940015Y141602D02*
X940084Y141639D01*
G01X939985Y141560D02*
X940015Y141602D01*
G01X940731Y141939D02*
X940616Y141920D01*
G01X940830Y141968D02*
X940731Y141939D01*
G01X940898Y142006D02*
X940830Y141968D01*
G01X940928Y142048D02*
X940898Y142006D01*
G01X940183Y137732D02*
X940298Y137750D01*
G01X940084Y137702D02*
X940183Y137732D01*
G01X940015Y137665D02*
X940084Y137702D01*
G01X939985Y137623D02*
X940015Y137665D01*
G01X940731Y138002D02*
X940616Y137983D01*
G01X940830Y138031D02*
X940731Y138002D01*
G01X940898Y138069D02*
X940830Y138031D01*
G01X940928Y138111D02*
X940898Y138069D01*
G01X940183Y133795D02*
X940298Y133813D01*
G01X940084Y133765D02*
X940183Y133795D01*
G01X940015Y133728D02*
X940084Y133765D01*
G01X939985Y133686D02*
X940015Y133728D01*
G01X940731Y134065D02*
X940616Y134046D01*
G01X940830Y134094D02*
X940731Y134065D01*
G01X940898Y134132D02*
X940830Y134094D01*
G01X940928Y134174D02*
X940898Y134132D01*
G01X940959Y146127D02*
X940956Y146117D01*
G01X940961Y146132D02*
X940959Y146127D01*
G01X940964Y146134D02*
X940961Y146132D01*
G01X939955Y145355D02*
X939958Y145365D01*
G01X939953Y145349D02*
X939955Y145355D01*
G01X939950Y145347D02*
X939953Y145349D01*
G01X940959Y142190D02*
X940956Y142180D01*
G01X940961Y142195D02*
X940959Y142190D01*
G01X940964Y142197D02*
X940961Y142195D01*
G01X939955Y141418D02*
X939958Y141428D01*
G01X939953Y141412D02*
X939955Y141418D01*
G01X939950Y141410D02*
X939953Y141412D01*
G01X940959Y138253D02*
X940956Y138243D01*
G01X940961Y138258D02*
X940959Y138253D01*
G01X940964Y138260D02*
X940961Y138258D01*
G01X939955Y137481D02*
X939958Y137491D01*
G01X939953Y137475D02*
X939955Y137481D01*
G01X939950Y137473D02*
X939953Y137475D01*
G01X940959Y134316D02*
X940956Y134306D01*
G01X940961Y134321D02*
X940959Y134316D01*
G01X940964Y134323D02*
X940961Y134321D01*
G01X939955Y133544D02*
X939958Y133554D01*
G01X939953Y133538D02*
X939955Y133544D01*
G01X939950Y133536D02*
X939953Y133538D01*
G01X940401Y133835D02*
X940457Y133851D01*
G01X940347Y133822D02*
X940401Y133835D01*
G01X940298Y133813D02*
X940347Y133822D01*
G01X940513Y134025D02*
X940457Y134008D01*
G01X940566Y134037D02*
X940513Y134025D01*
G01X940616Y134046D02*
X940566Y134037D01*
G01X940401Y137772D02*
X940457Y137788D01*
G01X940347Y137759D02*
X940401Y137772D01*
G01X940298Y137750D02*
X940347Y137759D01*
G01X940513Y137962D02*
X940457Y137945D01*
G01X940566Y137975D02*
X940513Y137962D01*
G01X940616Y137983D02*
X940566Y137975D01*
G01X940401Y141709D02*
X940457Y141725D01*
G01X940347Y141696D02*
X940401Y141709D01*
G01X940298Y141687D02*
X940347Y141696D01*
G01X940513Y141899D02*
X940457Y141882D01*
G01X940566Y141912D02*
X940513Y141899D01*
G01X940616Y141920D02*
X940566Y141912D01*
G01X940401Y145646D02*
X940457Y145662D01*
G01X940347Y145633D02*
X940401Y145646D01*
G01X940298Y145625D02*
X940347Y145633D01*
G01X940513Y145836D02*
X940457Y145819D01*
G01X940566Y145849D02*
X940513Y145836D01*
G01X940616Y145857D02*
X940566Y145849D01*
G01X942701Y128645D02*
X942307Y128418D01*
G01X938764Y128645D02*
X938370Y128418D01*
G01X937583Y148841D02*
X946638D01*
G01X946441Y147709D02*
X945654D01*
G01X937583Y146577D02*
X946638D01*
G01X937977Y146184D02*
X946638D01*
G01X938488Y146134D02*
X949788D01*
G01X940956Y146117D02*
X939958D01*
G01X943882Y145937D02*
X945063D01*
G01X939551D02*
X940733D01*
G01X940298Y145857D02*
X940616D01*
G01Y145625D02*
X940298D01*
G01X940733Y145544D02*
X939551D01*
G01X945063D02*
X943882D01*
G01X939958Y145365D02*
X940956D01*
G01X938488Y145347D02*
X949788D01*
G01X946638Y145298D02*
X937977D01*
G01X937583Y144904D02*
X946638D01*
G01X945654Y143772D02*
X946441D01*
G01X937583Y142640D02*
X946638D01*
G01X937977Y142247D02*
X946638D01*
G01X938488Y142197D02*
X949788D01*
G01X940956Y142180D02*
X939958D01*
G01X943882Y142000D02*
X945063D01*
G01X939551D02*
X940733D01*
G01X940298Y141920D02*
X940616D01*
G01Y141687D02*
X940298D01*
G01X940733Y141607D02*
X939551D01*
G01X945063D02*
X943882D01*
G01X939958Y141428D02*
X940956D01*
G01X938488Y141410D02*
X949788D01*
G01X946638Y141361D02*
X937977D01*
G01X937583Y140967D02*
X946638D01*
G01X946441Y139835D02*
X945654D01*
G01X937583Y138703D02*
X946638D01*
G01X937977Y138310D02*
X946638D01*
G01X938488Y138260D02*
X949788D01*
G01X940956Y138243D02*
X939958D01*
G01X943882Y138063D02*
X945063D01*
G01X939551D02*
X940733D01*
G01X940298Y137983D02*
X940616D01*
G01Y137750D02*
X940298D01*
G01X940733Y137670D02*
X939551D01*
G01X945063D02*
X943882D01*
G01X939958Y137491D02*
X940956D01*
G01X938488Y137473D02*
X949788D01*
G01X946638Y137424D02*
X937977D01*
G01X937583Y137030D02*
X946638D01*
G01X943292Y128378D02*
X942977Y128063D01*
G01X938174Y129205D02*
X938370Y129402D01*
G01X936717Y128378D02*
X936402Y128063D01*
G01X938174Y130780D02*
X938370Y130977D01*
G01X935339Y128378D02*
X935024Y128063D01*
G01X934827Y129205D02*
X934630Y129008D01*
G01X936205Y130780D02*
X936402Y130977D01*
G01X937583Y133093D02*
X937977Y133487D01*
G01X937583Y137030D02*
X937977Y137424D01*
G01X937583Y140967D02*
X937977Y141361D01*
G01X945654Y135898D02*
X946441D01*
G01X937583Y134766D02*
X946638D01*
G01X937977Y134373D02*
X946638D01*
G01X938488Y134323D02*
X949788D01*
G01X940956Y134306D02*
X939958D01*
G01X943882Y134126D02*
X945063D01*
G01X939551D02*
X940733D01*
G01X940298Y134046D02*
X940616D01*
G01Y133813D02*
X940298D01*
G01X940733Y133733D02*
X939551D01*
G01X945063D02*
X943882D01*
G01X939958Y133554D02*
X940956D01*
G01X938488Y133536D02*
X949788D01*
G01X946638Y133487D02*
X937977D01*
G01X937583Y133093D02*
X946638D01*
G01X941126Y131567D02*
X939158D01*
G01X945457D02*
X943488D01*
G01X941126Y130977D02*
X945654D01*
G01X936402D02*
X938370D01*
G01X938174Y130780D02*
X936205D01*
G01X945851D02*
X941323D01*
G01X944276Y129953D02*
X935024D01*
G01X946048D02*
X945260D01*
G01X946048Y129560D02*
X947032D01*
G01X944276D02*
X945260D01*
G01X938370Y129402D02*
X941126D01*
G01X935339Y129245D02*
X940339D01*
G01X945260D02*
X944276D01*
G01X947032D02*
X946048D01*
G01X934433Y129205D02*
X942307D01*
G01X934433Y128418D02*
X942307D01*
G01X943292Y128378D02*
X947032D01*
G01X935339D02*
X943095D01*
G01X947032Y128063D02*
X942977D01*
G01X947032Y127237D02*
X935024D01*
G01X937583Y144904D02*
X937977Y145298D01*
G01X937583Y148841D02*
X937977Y149235D01*
G01X942307Y129205D02*
X942701Y128978D01*
G01X938764D02*
X938370Y129205D01*
G01X940956Y134306D02*
X940928Y134174D01*
G01X940956Y138243D02*
X940928Y138111D01*
G01X939958Y133554D02*
X939985Y133686D01*
G01X940956Y142180D02*
X940928Y142048D01*
G01X939958Y137491D02*
X939985Y137623D01*
G01X940956Y146117D02*
X940928Y145985D01*
G01X939958Y141428D02*
X939985Y141560D01*
G01X939958Y145365D02*
X939985Y145497D01*
G01X937977Y146184D02*
X937583Y146577D01*
G01X937977Y142247D02*
X937583Y142640D01*
G01X945851Y130780D02*
X945654Y130977D01*
G01X937977Y138310D02*
X937583Y138703D01*
G01X937977Y134373D02*
X937583Y134766D01*
G01X941323Y130780D02*
X941126Y130977D01*
G01X941323Y129205D02*
X941126Y129402D01*
G01X936717Y129245D02*
X936402Y129560D01*
G01X949788Y134323D02*
Y133536D01*
G01Y138260D02*
Y137473D01*
G01Y142197D02*
Y141410D01*
G01Y146134D02*
Y145347D01*
G01X949197Y134323D02*
Y133536D01*
G01Y138260D02*
Y137473D01*
G01Y142197D02*
Y141410D01*
G01Y146134D02*
Y145347D01*
G01X947762D02*
Y146134D01*
G01Y141410D02*
Y142197D01*
G01Y137473D02*
Y138260D01*
G01Y133536D02*
Y134323D01*
G01X947032Y151056D02*
Y127237D01*
G01X946638Y195741D02*
Y127237D01*
G01X946561Y145347D02*
Y146134D01*
G01Y141410D02*
Y142197D01*
G01Y137473D02*
Y138260D01*
G01Y133536D02*
Y134323D01*
G01X946441Y143772D02*
Y147709D01*
G01Y135898D02*
Y139835D01*
G01X946048Y128378D02*
Y129953D01*
G01Y134373D02*
Y133487D01*
G01Y138310D02*
Y137424D01*
G01Y142247D02*
Y141361D01*
G01Y146184D02*
Y145298D01*
G01X945851Y135898D02*
Y130780D01*
G01Y143772D02*
Y139835D01*
G01Y192197D02*
Y147709D01*
G01X945677Y145347D02*
Y146134D01*
G01Y141410D02*
Y142197D01*
G01Y137473D02*
Y138260D01*
G01Y133536D02*
Y134323D01*
G01X945654Y147709D02*
Y192000D01*
G01Y139835D02*
Y143772D01*
G01Y130977D02*
Y135898D01*
G01Y138310D02*
Y137424D01*
G01Y146184D02*
Y145298D01*
G01X945605Y145347D02*
Y146134D01*
G01Y141410D02*
Y142197D01*
G01Y137473D02*
Y138260D01*
G01Y133536D02*
Y134323D01*
G01X945457Y133487D02*
Y131567D01*
G01Y137424D02*
Y134373D01*
G01Y141361D02*
Y138310D01*
G01Y145298D02*
Y142247D01*
G01Y149235D02*
Y146184D01*
G01X945426Y145347D02*
Y146134D01*
G01Y141410D02*
Y142197D01*
G01Y137473D02*
Y138260D01*
G01Y133536D02*
Y134323D01*
G01X945260Y128378D02*
Y129953D01*
G01X945063Y134126D02*
Y133733D01*
G01Y138063D02*
Y137670D01*
G01Y142000D02*
Y141607D01*
G01Y145937D02*
Y145544D01*
G01X944945Y128378D02*
Y129245D01*
G01X944591D02*
Y128378D01*
G01X944276D02*
Y129953D01*
G01X944057Y145347D02*
Y146134D01*
G01Y141410D02*
Y142197D01*
G01Y137473D02*
Y138260D01*
G01Y133536D02*
Y134323D01*
G01X943882Y145544D02*
Y145937D01*
G01Y141607D02*
Y142000D01*
G01Y137670D02*
Y138063D01*
G01Y133733D02*
Y134126D01*
G01X943685Y134323D02*
Y133536D01*
G01Y138260D02*
Y137473D01*
G01Y142197D02*
Y141410D01*
G01Y146134D02*
Y145347D01*
G01X943528Y134373D02*
Y133487D01*
G01Y138310D02*
Y137424D01*
G01Y142247D02*
Y141361D01*
G01Y146184D02*
Y145298D01*
G01X943488Y146184D02*
Y149235D01*
G01Y145347D02*
Y146134D01*
G01Y142247D02*
Y145298D01*
G01Y141410D02*
Y142197D01*
G01Y138310D02*
Y141361D01*
G01Y137473D02*
Y138260D01*
G01Y134373D02*
Y137424D01*
G01Y133536D02*
Y134323D01*
G01Y131567D02*
Y133487D01*
G01X943340Y134323D02*
Y133536D01*
G01Y138260D02*
Y137473D01*
G01Y142197D02*
Y141410D01*
G01Y146134D02*
Y145347D01*
G01X943292Y129953D02*
Y128378D01*
G01X943268Y134323D02*
Y133536D01*
G01Y138260D02*
Y137473D01*
G01Y142197D02*
Y141410D01*
G01Y146134D02*
Y145347D01*
G01X943134Y134373D02*
Y133487D01*
G01Y138310D02*
Y137424D01*
G01Y142247D02*
Y141361D01*
G01Y146184D02*
Y145298D01*
G01X943095Y128378D02*
Y129953D01*
G01X942977Y128063D02*
Y129953D01*
G01X942701Y128978D02*
Y128645D01*
G01X941906Y129205D02*
Y128418D01*
G01X941796Y145298D02*
Y146184D01*
G01Y137424D02*
Y138310D01*
G01Y134373D02*
Y133487D01*
G01Y142247D02*
Y141361D01*
G01X941559Y128418D02*
Y129205D01*
G01X941546D02*
Y128418D01*
G01X941441Y134323D02*
Y133536D01*
G01Y138260D02*
Y137473D01*
G01Y142197D02*
Y141410D01*
G01Y146134D02*
Y145347D01*
G01X941402Y134373D02*
Y133487D01*
G01Y138310D02*
Y137424D01*
G01Y142247D02*
Y141361D01*
G01Y146184D02*
Y145298D01*
G01X941376Y129205D02*
Y128418D01*
G01X941346Y145347D02*
Y146134D01*
G01Y141410D02*
Y142197D01*
G01Y137473D02*
Y138260D01*
G01Y133536D02*
Y134323D01*
G01X941323Y130780D02*
Y129205D01*
G01X941274Y145347D02*
Y146134D01*
G01Y141410D02*
Y142197D01*
G01Y137473D02*
Y138260D01*
G01Y133536D02*
Y134323D01*
G01X941244D02*
Y133536D01*
G01Y138260D02*
Y137473D01*
G01Y142197D02*
Y141410D01*
G01Y146134D02*
Y145347D01*
G01X941126Y129402D02*
Y130977D01*
G01Y133487D02*
Y131567D01*
G01Y137424D02*
Y134373D01*
G01Y141361D02*
Y138310D01*
G01Y145298D02*
Y142247D01*
G01Y149235D02*
Y146184D01*
G01X940928Y134174D02*
Y133686D01*
G01Y138111D02*
Y137623D01*
G01Y142048D02*
Y141560D01*
G01Y145985D02*
Y145497D01*
G01X940733Y134126D02*
Y133733D01*
G01Y138063D02*
Y137670D01*
G01Y142000D02*
Y141607D01*
G01Y145937D02*
Y145544D01*
G01X940536Y128418D02*
Y129205D01*
G01X940355D02*
Y128418D01*
G01X940339Y129245D02*
Y128378D01*
G01X939985Y145497D02*
Y145985D01*
G01Y141560D02*
Y142048D01*
G01Y137623D02*
Y138111D01*
G01Y133686D02*
Y134174D01*
G01X939748Y129205D02*
Y128418D01*
G01X939670Y134373D02*
Y133487D01*
G01Y138310D02*
Y137424D01*
G01Y142247D02*
Y141361D01*
G01Y146184D02*
Y145298D01*
G01X939551Y145544D02*
Y145937D01*
G01Y141607D02*
Y142000D01*
G01Y137670D02*
Y138063D01*
G01Y133733D02*
Y134126D01*
G01X939473Y145347D02*
Y146134D01*
G01Y141410D02*
Y142197D01*
G01Y137473D02*
Y138260D01*
G01Y133536D02*
Y134323D01*
G01X939276Y134373D02*
Y133487D01*
G01Y138310D02*
Y137424D01*
G01Y142247D02*
Y141361D01*
G01Y146184D02*
Y145298D01*
G01X939158Y146184D02*
Y149235D01*
G01Y142247D02*
Y145298D01*
G01Y138310D02*
Y141361D01*
G01Y134373D02*
Y137424D01*
G01Y131567D02*
Y133487D01*
G01Y128378D02*
Y129953D01*
G01X939010Y134323D02*
Y133536D01*
G01Y138260D02*
Y137473D01*
G01Y142197D02*
Y141410D01*
G01Y146134D02*
Y145347D01*
G01X938938Y134323D02*
Y133536D01*
G01Y138260D02*
Y137473D01*
G01Y142197D02*
Y141410D01*
G01Y146134D02*
Y145347D01*
G01X938764Y128978D02*
Y128645D01*
G01X938488Y145347D02*
Y146134D01*
G01Y141410D02*
Y142197D01*
G01Y137473D02*
Y138260D01*
G01Y133536D02*
Y134323D01*
G01X938370Y130977D02*
Y129402D01*
G01X938174Y128418D02*
Y130780D01*
G01X938128Y129205D02*
Y128418D01*
G01X938029D02*
Y129205D01*
G01X937977Y145298D02*
Y146184D01*
G01Y141361D02*
Y142247D01*
G01Y137424D02*
Y138310D01*
G01Y133487D02*
Y134373D01*
G01X937583Y134766D02*
Y133093D01*
G01Y138703D02*
Y137030D01*
G01Y142640D02*
Y140967D01*
G01Y146577D02*
Y144904D01*
G01Y150514D02*
Y148841D01*
G01X937574Y128418D02*
Y129205D01*
G01X937394D02*
Y128418D01*
G01X936717Y129245D02*
Y128378D01*
G01X936599Y129205D02*
Y128418D01*
G01X936402Y129245D02*
Y128378D01*
G01Y128063D02*
Y127237D01*
G01Y193418D02*
Y129560D01*
G01X936205Y130780D02*
Y153418D01*
G01X935339Y128378D02*
Y129953D01*
G01X935024Y153418D02*
Y127237D01*
G01X934827Y128418D02*
Y129205D01*
G01X934729D02*
Y128418D01*
G01X934630Y129008D02*
Y128615D01*
G01X934433Y129205D02*
Y128418D01*
G01X940928Y145497D02*
X940956Y145365D01*
G01X940928Y141560D02*
X940956Y141428D01*
G01X939985Y145985D02*
X939958Y146117D01*
G01X940928Y137623D02*
X940956Y137491D01*
G01X939985Y142048D02*
X939958Y142180D01*
G01X940928Y133686D02*
X940956Y133554D01*
G01X939985Y138111D02*
X939958Y138243D01*
G01X939985Y134174D02*
X939958Y134306D01*
G01X935339Y129245D02*
X935024Y129560D01*
G01X934827Y128418D02*
X934630Y128615D01*
G01X939953Y150069D02*
X939950Y150071D01*
G01X939955Y150064D02*
X939953Y150069D01*
G01X939958Y150054D02*
X939955Y150064D01*
G01X940961Y149286D02*
X940964Y149284D01*
G01X940959Y149292D02*
X940961Y149286D01*
G01X940956Y149302D02*
X940959Y149292D01*
G01X939953Y154006D02*
X939950Y154008D01*
G01X939955Y154001D02*
X939953Y154006D01*
G01X939958Y153991D02*
X939955Y154001D01*
G01X940961Y153223D02*
X940964Y153221D01*
G01X940959Y153229D02*
X940961Y153223D01*
G01X940956Y153239D02*
X940959Y153229D01*
G01X939953Y157943D02*
X939950Y157945D01*
G01X939955Y157938D02*
X939953Y157943D01*
G01X939958Y157928D02*
X939955Y157938D01*
G01X940961Y157160D02*
X940964Y157158D01*
G01X940959Y157166D02*
X940961Y157160D01*
G01X940956Y157176D02*
X940959Y157166D01*
G01X939953Y161880D02*
X939950Y161882D01*
G01X939955Y161875D02*
X939953Y161880D01*
G01X939958Y161865D02*
X939955Y161875D01*
G01X940961Y161097D02*
X940964Y161095D01*
G01X940959Y161103D02*
X940961Y161097D01*
G01X940956Y161113D02*
X940959Y161103D01*
G01X939953Y165817D02*
X939950Y165819D01*
G01X939955Y165812D02*
X939953Y165817D01*
G01X939958Y165802D02*
X939955Y165812D01*
G01X939540Y149949D02*
X939551Y149875D01*
G01X939511Y150017D02*
X939540Y149949D01*
G01X939469Y150071D02*
X939511Y150017D01*
G01X940744Y149406D02*
X940733Y149481D01*
G01X940773Y149339D02*
X940744Y149406D01*
G01X940815Y149284D02*
X940773Y149339D01*
G01X939540Y153886D02*
X939551Y153812D01*
G01X939511Y153954D02*
X939540Y153886D01*
G01X939469Y154008D02*
X939511Y153954D01*
G01X940744Y153343D02*
X940733Y153418D01*
G01X940773Y153276D02*
X940744Y153343D01*
G01X940815Y153221D02*
X940773Y153276D01*
G01X943871Y149949D02*
X943882Y149875D01*
G01X943842Y150017D02*
X943871Y149949D01*
G01X943800Y150071D02*
X943842Y150017D01*
G01X945074Y149406D02*
X945063Y149481D01*
G01X945103Y149339D02*
X945074Y149406D01*
G01X945146Y149284D02*
X945103Y149339D01*
G01X939540Y157823D02*
X939551Y157749D01*
G01X939511Y157891D02*
X939540Y157823D01*
G01X939469Y157945D02*
X939511Y157891D01*
G01X940744Y157280D02*
X940733Y157355D01*
G01X940773Y157213D02*
X940744Y157280D01*
G01X940815Y157158D02*
X940773Y157213D01*
G01X943871Y153886D02*
X943882Y153812D01*
G01X943842Y153954D02*
X943871Y153886D01*
G01X943800Y154008D02*
X943842Y153954D01*
G01X945074Y153343D02*
X945063Y153418D01*
G01X945103Y153276D02*
X945074Y153343D01*
G01X945146Y153221D02*
X945103Y153276D01*
G01X939540Y161760D02*
X939551Y161686D01*
G01X939511Y161828D02*
X939540Y161760D01*
G01X939469Y161882D02*
X939511Y161828D01*
G01X940744Y161217D02*
X940733Y161292D01*
G01X940773Y161150D02*
X940744Y161217D01*
G01X940815Y161095D02*
X940773Y161150D01*
G01X943871Y157823D02*
X943882Y157749D01*
G01X943842Y157891D02*
X943871Y157823D01*
G01X943800Y157945D02*
X943842Y157891D01*
G01X945074Y157280D02*
X945063Y157355D01*
G01X945103Y157213D02*
X945074Y157280D01*
G01X945146Y157158D02*
X945103Y157213D01*
G01X939540Y165697D02*
X939551Y165623D01*
G01X939511Y165765D02*
X939540Y165697D01*
G01X939469Y165819D02*
X939511Y165765D01*
G01X940744Y165154D02*
X940733Y165229D01*
G01X940773Y165087D02*
X940744Y165154D01*
G01X940815Y165032D02*
X940773Y165087D01*
G01X943871Y161760D02*
X943882Y161686D01*
G01X943842Y161828D02*
X943871Y161760D01*
G01X943800Y161882D02*
X943842Y161828D01*
G01X945074Y161217D02*
X945063Y161292D01*
G01X945103Y161150D02*
X945074Y161217D01*
G01X945146Y161095D02*
X945103Y161150D01*
G01X939540Y169634D02*
X939551Y169560D01*
G01X939511Y169702D02*
X939540Y169634D01*
G01X939469Y169756D02*
X939511Y169702D01*
G01X940744Y169091D02*
X940733Y169166D01*
G01X940773Y169024D02*
X940744Y169091D01*
G01X940815Y168969D02*
X940773Y169024D01*
G01X943871Y165697D02*
X943882Y165623D01*
G01X943842Y165765D02*
X943871Y165697D01*
G01X943800Y165819D02*
X943842Y165765D01*
G01X945074Y165154D02*
X945063Y165229D01*
G01X945103Y165087D02*
X945074Y165154D01*
G01X945146Y165032D02*
X945103Y165087D01*
G01X940961Y165034D02*
X940964Y165032D01*
G01X940959Y165040D02*
X940961Y165034D01*
G01X940956Y165050D02*
X940959Y165040D01*
G01X939953Y169754D02*
X939950Y169756D01*
G01X939955Y169749D02*
X939953Y169754D01*
G01X939958Y169739D02*
X939955Y169749D01*
G01X940961Y168971D02*
X940964Y168969D01*
G01X940959Y168977D02*
X940961Y168971D01*
G01X940956Y168987D02*
X940959Y168977D01*
G01X939511Y169024D02*
X939469Y168969D01*
G01X939540Y169091D02*
X939511Y169024D01*
G01X939551Y169166D02*
X939540Y169091D01*
G01X939511Y165087D02*
X939469Y165032D01*
G01X939540Y165154D02*
X939511Y165087D01*
G01X939551Y165229D02*
X939540Y165154D01*
G01X940773Y169702D02*
X940815Y169756D01*
G01X940744Y169634D02*
X940773Y169702D01*
G01X940733Y169560D02*
X940744Y169634D01*
G01X939511Y161150D02*
X939469Y161095D01*
G01X939540Y161217D02*
X939511Y161150D01*
G01X939551Y161292D02*
X939540Y161217D01*
G01X940773Y165765D02*
X940815Y165819D01*
G01X940744Y165697D02*
X940773Y165765D01*
G01X940733Y165623D02*
X940744Y165697D01*
G01X939511Y157213D02*
X939469Y157158D01*
G01X939540Y157280D02*
X939511Y157213D01*
G01X939551Y157355D02*
X939540Y157280D01*
G01X940773Y161828D02*
X940815Y161882D01*
G01X940744Y161760D02*
X940773Y161828D01*
G01X940733Y161686D02*
X940744Y161760D01*
G01X939511Y153276D02*
X939469Y153221D01*
G01X939540Y153343D02*
X939511Y153276D01*
G01X939551Y153418D02*
X939540Y153343D01*
G01X940773Y157891D02*
X940815Y157945D01*
G01X940744Y157823D02*
X940773Y157891D01*
G01X940733Y157749D02*
X940744Y157823D01*
G01X939511Y149339D02*
X939469Y149284D01*
G01X939540Y149406D02*
X939511Y149339D01*
G01X939551Y149481D02*
X939540Y149406D01*
G01X940773Y153954D02*
X940815Y154008D01*
G01X940744Y153886D02*
X940773Y153954D01*
G01X940733Y153812D02*
X940744Y153886D01*
G01X940773Y150017D02*
X940815Y150071D01*
G01X940744Y149949D02*
X940773Y150017D01*
G01X940733Y149875D02*
X940744Y149949D01*
G01X943842Y169024D02*
X943800Y168969D01*
G01X943871Y169091D02*
X943842Y169024D01*
G01X943882Y169166D02*
X943871Y169091D01*
G01X943842Y165087D02*
X943800Y165032D01*
G01X943871Y165154D02*
X943842Y165087D01*
G01X943882Y165229D02*
X943871Y165154D01*
G01X945103Y169702D02*
X945146Y169756D01*
G01X945074Y169634D02*
X945103Y169702D01*
G01X945063Y169560D02*
X945074Y169634D01*
G01X943842Y161150D02*
X943800Y161095D01*
G01X943871Y161217D02*
X943842Y161150D01*
G01X943882Y161292D02*
X943871Y161217D01*
G01X945103Y165765D02*
X945146Y165819D01*
G01X945074Y165697D02*
X945103Y165765D01*
G01X945063Y165623D02*
X945074Y165697D01*
G01X943842Y157213D02*
X943800Y157158D01*
G01X943871Y157280D02*
X943842Y157213D01*
G01X943882Y157355D02*
X943871Y157280D01*
G01X945103Y161828D02*
X945146Y161882D01*
G01X945074Y161760D02*
X945103Y161828D01*
G01X945063Y161686D02*
X945074Y161760D01*
G01X943842Y153276D02*
X943800Y153221D01*
G01X943871Y153343D02*
X943842Y153276D01*
G01X943882Y153418D02*
X943871Y153343D01*
G01X945103Y157891D02*
X945146Y157945D01*
G01X945074Y157823D02*
X945103Y157891D01*
G01X945063Y157749D02*
X945074Y157823D01*
G01X943842Y149339D02*
X943800Y149284D01*
G01X943871Y149406D02*
X943842Y149339D01*
G01X943882Y149481D02*
X943871Y149406D01*
G01X945103Y153954D02*
X945146Y154008D01*
G01X945074Y153886D02*
X945103Y153954D01*
G01X945063Y153812D02*
X945074Y153886D01*
G01X945103Y150017D02*
X945146Y150071D01*
G01X945074Y149949D02*
X945103Y150017D01*
G01X945063Y149875D02*
X945074Y149949D01*
G01X943871Y169634D02*
X943882Y169560D01*
G01X943842Y169702D02*
X943871Y169634D01*
G01X943800Y169756D02*
X943842Y169702D01*
G01X945074Y169091D02*
X945063Y169166D01*
G01X945103Y169024D02*
X945074Y169091D01*
G01X945146Y168969D02*
X945103Y169024D01*
G01X940183Y169228D02*
X940298Y169247D01*
G01X940084Y169199D02*
X940183Y169228D01*
G01X940015Y169161D02*
X940084Y169199D01*
G01X939985Y169119D02*
X940015Y169161D01*
G01X940731Y169498D02*
X940616Y169479D01*
G01X940830Y169527D02*
X940731Y169498D01*
G01X940898Y169565D02*
X940830Y169527D01*
G01X940928Y169607D02*
X940898Y169565D01*
G01X940183Y165291D02*
X940298Y165310D01*
G01X940084Y165262D02*
X940183Y165291D01*
G01X940015Y165224D02*
X940084Y165262D01*
G01X939985Y165182D02*
X940015Y165224D01*
G01X940731Y165561D02*
X940616Y165542D01*
G01X940830Y165590D02*
X940731Y165561D01*
G01X940898Y165628D02*
X940830Y165590D01*
G01X940928Y165670D02*
X940898Y165628D01*
G01X940183Y161354D02*
X940298Y161373D01*
G01X940084Y161325D02*
X940183Y161354D01*
G01X940015Y161287D02*
X940084Y161325D01*
G01X939985Y161245D02*
X940015Y161287D01*
G01X940731Y161624D02*
X940616Y161605D01*
G01X940830Y161653D02*
X940731Y161624D01*
G01X940898Y161691D02*
X940830Y161653D01*
G01X940928Y161733D02*
X940898Y161691D01*
G01X940183Y157417D02*
X940298Y157436D01*
G01X940084Y157387D02*
X940183Y157417D01*
G01X940015Y157350D02*
X940084Y157387D01*
G01X939985Y157308D02*
X940015Y157350D01*
G01X940731Y157687D02*
X940616Y157668D01*
G01X940830Y157716D02*
X940731Y157687D01*
G01X940898Y157754D02*
X940830Y157716D01*
G01X940928Y157796D02*
X940898Y157754D01*
G01X940183Y153480D02*
X940298Y153499D01*
G01X940084Y153450D02*
X940183Y153480D01*
G01X940015Y153413D02*
X940084Y153450D01*
G01X939985Y153371D02*
X940015Y153413D01*
G01X940731Y153750D02*
X940616Y153731D01*
G01X940830Y153779D02*
X940731Y153750D01*
G01X940898Y153817D02*
X940830Y153779D01*
G01X940928Y153859D02*
X940898Y153817D01*
G01X940566Y149570D02*
X940735Y149542D01*
G01X940513Y149583D02*
X940566Y149570D01*
G01X940457Y149599D02*
X940513Y149583D01*
G01X940566Y153507D02*
X940616Y153499D01*
G01X940513Y153520D02*
X940566Y153507D01*
G01X940457Y153536D02*
X940513Y153520D01*
G01X940347Y149786D02*
X940179Y149814D01*
G01X940401Y149773D02*
X940347Y149786D01*
G01X940457Y149756D02*
X940401Y149773D01*
G01X940347Y153723D02*
X940298Y153731D01*
G01X940401Y153710D02*
X940347Y153723D01*
G01X940457Y153693D02*
X940401Y153710D01*
G01X940900Y149474D02*
X940928Y149434D01*
G01X940834Y149512D02*
X940900Y149474D01*
G01X940735Y149542D02*
X940834Y149512D01*
G01X940014Y149882D02*
X939985Y149922D01*
G01X940079Y149844D02*
X940014Y149882D01*
G01X940179Y149814D02*
X940079Y149844D01*
G01X940900Y157348D02*
X940928Y157308D01*
G01X940834Y157386D02*
X940900Y157348D01*
G01X940735Y157416D02*
X940834Y157386D01*
G01X940014Y157756D02*
X939985Y157796D01*
G01X940079Y157718D02*
X940014Y157756D01*
G01X940179Y157688D02*
X940079Y157718D01*
G01X940183Y149543D02*
X940298Y149562D01*
G01X940084Y149513D02*
X940183Y149543D01*
G01X940015Y149476D02*
X940084Y149513D01*
G01X939985Y149434D02*
X940015Y149476D01*
G01X940731Y149813D02*
X940616Y149794D01*
G01X940830Y149842D02*
X940731Y149813D01*
G01X940898Y149880D02*
X940830Y149842D01*
G01X940928Y149922D02*
X940898Y149880D01*
G01X940566Y157444D02*
X940735Y157416D01*
G01X940513Y157457D02*
X940566Y157444D01*
G01X940457Y157473D02*
X940513Y157457D01*
G01X940566Y161381D02*
X940735Y161353D01*
G01X940513Y161394D02*
X940566Y161381D01*
G01X940457Y161410D02*
X940513Y161394D01*
G01X940566Y165318D02*
X940735Y165290D01*
G01X940513Y165331D02*
X940566Y165318D01*
G01X940457Y165347D02*
X940513Y165331D01*
G01X940566Y169255D02*
X940735Y169227D01*
G01X940513Y169268D02*
X940566Y169255D01*
G01X940457Y169284D02*
X940513Y169268D01*
G01X940347Y157660D02*
X940179Y157688D01*
G01X940401Y157647D02*
X940347Y157660D01*
G01X940457Y157630D02*
X940401Y157647D01*
G01X940347Y161597D02*
X940179Y161625D01*
G01X940401Y161584D02*
X940347Y161597D01*
G01X940457Y161567D02*
X940401Y161584D01*
G01X940347Y165534D02*
X940179Y165562D01*
G01X940401Y165521D02*
X940347Y165534D01*
G01X940457Y165504D02*
X940401Y165521D01*
G01X940347Y169471D02*
X940179Y169499D01*
G01X940401Y169458D02*
X940347Y169471D01*
G01X940457Y169441D02*
X940401Y169458D01*
G01X940900Y161285D02*
X940928Y161245D01*
G01X940834Y161323D02*
X940900Y161285D01*
G01X940735Y161353D02*
X940834Y161323D01*
G01X940014Y161693D02*
X939985Y161733D01*
G01X940079Y161655D02*
X940014Y161693D01*
G01X940179Y161625D02*
X940079Y161655D01*
G01X940900Y165222D02*
X940928Y165182D01*
G01X940834Y165260D02*
X940900Y165222D01*
G01X940735Y165290D02*
X940834Y165260D01*
G01X940014Y165630D02*
X939985Y165670D01*
G01X940079Y165592D02*
X940014Y165630D01*
G01X940179Y165562D02*
X940079Y165592D01*
G01X940900Y169159D02*
X940928Y169119D01*
G01X940834Y169197D02*
X940900Y169159D01*
G01X940735Y169227D02*
X940834Y169197D01*
G01X940014Y169567D02*
X939985Y169607D01*
G01X940079Y169529D02*
X940014Y169567D01*
G01X940179Y169499D02*
X940079Y169529D01*
G01X940900Y153411D02*
X940928Y153371D01*
G01X940834Y153449D02*
X940900Y153411D01*
G01X940735Y153479D02*
X940834Y153449D01*
G01X940616Y153499D02*
X940735Y153479D01*
G01X940014Y153819D02*
X939985Y153859D01*
G01X940079Y153781D02*
X940014Y153819D01*
G01X940179Y153751D02*
X940079Y153781D01*
G01X940298Y153731D02*
X940179Y153751D01*
G01X940959Y169749D02*
X940956Y169739D01*
G01X940961Y169754D02*
X940959Y169749D01*
G01X940964Y169756D02*
X940961Y169754D01*
G01X939955Y168977D02*
X939958Y168987D01*
G01X939953Y168971D02*
X939955Y168977D01*
G01X939950Y168969D02*
X939953Y168971D01*
G01X940959Y165812D02*
X940956Y165802D01*
G01X940961Y165817D02*
X940959Y165812D01*
G01X940964Y165819D02*
X940961Y165817D01*
G01X939955Y165040D02*
X939958Y165050D01*
G01X939953Y165034D02*
X939955Y165040D01*
G01X939950Y165032D02*
X939953Y165034D01*
G01X940959Y161875D02*
X940956Y161865D01*
G01X940961Y161880D02*
X940959Y161875D01*
G01X940964Y161882D02*
X940961Y161880D01*
G01X939955Y161103D02*
X939958Y161113D01*
G01X939953Y161097D02*
X939955Y161103D01*
G01X939950Y161095D02*
X939953Y161097D01*
G01X940959Y157938D02*
X940956Y157928D01*
G01X940961Y157943D02*
X940959Y157938D01*
G01X940964Y157945D02*
X940961Y157943D01*
G01X939955Y157166D02*
X939958Y157176D01*
G01X939953Y157160D02*
X939955Y157166D01*
G01X939950Y157158D02*
X939953Y157160D01*
G01X940959Y154001D02*
X940956Y153991D01*
G01X940961Y154006D02*
X940959Y154001D01*
G01X940964Y154008D02*
X940961Y154006D01*
G01X939955Y153229D02*
X939958Y153239D01*
G01X939953Y153223D02*
X939955Y153229D01*
G01X939950Y153221D02*
X939953Y153223D01*
G01X940959Y150064D02*
X940956Y150054D01*
G01X940961Y150069D02*
X940959Y150064D01*
G01X940964Y150071D02*
X940961Y150069D01*
G01X939955Y149292D02*
X939958Y149302D01*
G01X939953Y149286D02*
X939955Y149292D01*
G01X939950Y149284D02*
X939953Y149286D01*
G01X940401Y149583D02*
X940457Y149599D01*
G01X940347Y149570D02*
X940401Y149583D01*
G01X940298Y149562D02*
X940347Y149570D01*
G01X940513Y149773D02*
X940457Y149756D01*
G01X940566Y149786D02*
X940513Y149773D01*
G01X940616Y149794D02*
X940566Y149786D01*
G01X940401Y153520D02*
X940457Y153536D01*
G01X940347Y153507D02*
X940401Y153520D01*
G01X940298Y153499D02*
X940347Y153507D01*
G01X940513Y153710D02*
X940457Y153693D01*
G01X940566Y153723D02*
X940513Y153710D01*
G01X940616Y153731D02*
X940566Y153723D01*
G01X940401Y157457D02*
X940457Y157473D01*
G01X940347Y157444D02*
X940401Y157457D01*
G01X940298Y157436D02*
X940347Y157444D01*
G01X940513Y157647D02*
X940457Y157630D01*
G01X940566Y157660D02*
X940513Y157647D01*
G01X940616Y157668D02*
X940566Y157660D01*
G01X940401Y161394D02*
X940457Y161410D01*
G01X940347Y161381D02*
X940401Y161394D01*
G01X940298Y161373D02*
X940347Y161381D01*
G01X940513Y161584D02*
X940457Y161567D01*
G01X940566Y161597D02*
X940513Y161584D01*
G01X940616Y161605D02*
X940566Y161597D01*
G01X940401Y165331D02*
X940457Y165347D01*
G01X940347Y165318D02*
X940401Y165331D01*
G01X940298Y165310D02*
X940347Y165318D01*
G01X940513Y165521D02*
X940457Y165504D01*
G01X940566Y165534D02*
X940513Y165521D01*
G01X940616Y165542D02*
X940566Y165534D01*
G01X940401Y169268D02*
X940457Y169284D01*
G01X940347Y169255D02*
X940401Y169268D01*
G01X940298Y169247D02*
X940347Y169255D01*
G01X940513Y169458D02*
X940457Y169441D01*
G01X940566Y169471D02*
X940513Y169458D01*
G01X940616Y169479D02*
X940566Y169471D01*
G01X947426Y170741D02*
X947032D01*
G01X937583Y170199D02*
X946638D01*
G01X937977Y169806D02*
X946638D01*
G01X938488Y169756D02*
X949788D01*
G01X940956Y169739D02*
X939958D01*
G01X943882Y169560D02*
X945063D01*
G01X939551D02*
X940733D01*
G01X940298Y169479D02*
X940616D01*
G01Y169247D02*
X940298D01*
G01X940733Y169166D02*
X939551D01*
G01X945063D02*
X943882D01*
G01X939958Y168987D02*
X940956D01*
G01X938488Y168969D02*
X949788D01*
G01X946638Y168920D02*
X937977D01*
G01X937583Y168526D02*
X946638D01*
G01X947032Y167985D02*
X947426D01*
G01Y166804D02*
X947032D01*
G01X937583Y166262D02*
X946638D01*
G01X937977Y165869D02*
X946638D01*
G01X938488Y165819D02*
X949788D01*
G01X940956Y165802D02*
X939958D01*
G01X943882Y165623D02*
X945063D01*
G01X939551D02*
X940733D01*
G01X940298Y165542D02*
X940616D01*
G01Y165310D02*
X940298D01*
G01X940733Y165229D02*
X939551D01*
G01X945063D02*
X943882D01*
G01X939958Y165050D02*
X940956D01*
G01X938488Y165032D02*
X949788D01*
G01X946638Y164983D02*
X937977D01*
G01X937583Y164589D02*
X946638D01*
G01X947032Y164048D02*
X947426D01*
G01Y162867D02*
X947032D01*
G01X937583Y162325D02*
X946638D01*
G01X937977Y161932D02*
X946638D01*
G01X938488Y161882D02*
X949788D01*
G01X940956Y161865D02*
X939958D01*
G01X943882Y161686D02*
X945063D01*
G01X939551D02*
X940733D01*
G01X940298Y161605D02*
X940616D01*
G01Y161373D02*
X940298D01*
G01X940733Y161292D02*
X939551D01*
G01X945063D02*
X943882D01*
G01X939958Y161113D02*
X940956D01*
G01X938488Y161095D02*
X949788D01*
G01X946638Y161046D02*
X937977D01*
G01X937583Y160652D02*
X946638D01*
G01X947032Y160111D02*
X947426D01*
G01Y158930D02*
X947032D01*
G01X937583Y158388D02*
X946638D01*
G01X937977Y157995D02*
X946638D01*
G01X938488Y157945D02*
X949788D01*
G01X940956Y157928D02*
X939958D01*
G01X943882Y157749D02*
X945063D01*
G01X939551D02*
X940733D01*
G01X940298Y157668D02*
X940616D01*
G01X934709Y169363D02*
X935024Y169560D01*
G01X940616Y157436D02*
X940298D01*
G01X940733Y157355D02*
X939551D01*
G01X945063D02*
X943882D01*
G01X939958Y157176D02*
X940956D01*
G01X938488Y157158D02*
X949788D01*
G01X946638Y157109D02*
X937977D01*
G01X937583Y156715D02*
X946638D01*
G01X947032Y156174D02*
X947426D01*
G01Y154993D02*
X947032D01*
G01X937583Y154451D02*
X946638D01*
G01X937977Y154058D02*
X946638D01*
G01X938488Y154008D02*
X949788D01*
G01X940956Y153991D02*
X939958D01*
G01X943882Y153812D02*
X945063D01*
G01X939551D02*
X940733D01*
G01X940298Y153731D02*
X940616D01*
G01Y153499D02*
X940298D01*
G01X940733Y153418D02*
X939551D01*
G01X945063D02*
X943882D01*
G01X939958Y153239D02*
X940956D01*
G01X938488Y153221D02*
X949788D01*
G01X946638Y153172D02*
X937977D01*
G01X937583Y152778D02*
X946638D01*
G01X947032Y152237D02*
X947426D01*
G01X947819Y151056D02*
X947032D01*
G01X937583Y150514D02*
X946638D01*
G01X937977Y150121D02*
X946638D01*
G01X938488Y150071D02*
X949788D01*
G01X940956Y150054D02*
X939958D01*
G01X943882Y149875D02*
X945063D01*
G01X939551D02*
X940733D01*
G01X940298Y149794D02*
X940616D01*
G01Y149562D02*
X940298D01*
G01X940733Y149481D02*
X939551D01*
G01X945063D02*
X943882D01*
G01X939958Y149302D02*
X940956D01*
G01X938488Y149284D02*
X949788D01*
G01X946638Y149235D02*
X937977D01*
G01X937583Y152778D02*
X937977Y153172D01*
G01X936205Y153418D02*
X936402Y153615D01*
G01X937583Y156715D02*
X937977Y157109D01*
G01X937583Y160652D02*
X937977Y161046D01*
G01X937583Y164589D02*
X937977Y164983D01*
G01X937583Y168526D02*
X937977Y168920D01*
G01X935024Y153418D02*
X934709Y153615D01*
G01X937977Y169806D02*
X937583Y170199D01*
G01X936402Y169363D02*
X936205Y169560D01*
G01X937977Y165869D02*
X937583Y166262D01*
G01X937977Y161932D02*
X937583Y162325D01*
G01X937977Y157995D02*
X937583Y158388D01*
G01X940956Y150054D02*
X940928Y149922D01*
G01X940956Y153991D02*
X940928Y153859D01*
G01X939958Y149302D02*
X939985Y149434D01*
G01X940956Y157928D02*
X940928Y157796D01*
G01X939958Y153239D02*
X939985Y153371D01*
G01X940956Y161865D02*
X940928Y161733D01*
G01X939958Y157176D02*
X939985Y157308D01*
G01X940956Y165802D02*
X940928Y165670D01*
G01X939958Y161113D02*
X939985Y161245D01*
G01X940956Y169739D02*
X940928Y169607D01*
G01X939958Y165050D02*
X939985Y165182D01*
G01X939958Y168987D02*
X939985Y169119D01*
G01X940928D02*
X940956Y168987D01*
G01X940928Y165182D02*
X940956Y165050D01*
G01X939985Y169607D02*
X939958Y169739D01*
G01X940928Y161245D02*
X940956Y161113D01*
G01X939985Y165670D02*
X939958Y165802D01*
G01X937977Y154058D02*
X937583Y154451D01*
G01X937977Y150121D02*
X937583Y150514D01*
G01X949788Y150071D02*
Y149284D01*
G01Y154008D02*
Y153221D01*
G01Y157945D02*
Y157158D01*
G01Y161882D02*
Y161095D01*
G01Y165819D02*
Y165032D01*
G01Y169756D02*
Y168969D01*
G01X949197Y150071D02*
Y149284D01*
G01Y154008D02*
Y153221D01*
G01Y157945D02*
Y157158D01*
G01Y161882D02*
Y161095D01*
G01Y165819D02*
Y165032D01*
G01Y169756D02*
Y168969D01*
G01X947819Y171922D02*
Y151056D01*
G01X947762Y168969D02*
Y169756D01*
G01Y165032D02*
Y165819D01*
G01Y161095D02*
Y161882D01*
G01Y157158D02*
Y157945D01*
G01Y153221D02*
Y154008D01*
G01Y149284D02*
Y150071D01*
G01X947426Y152237D02*
Y151056D01*
G01Y156174D02*
Y154993D01*
G01Y160111D02*
Y158930D01*
G01Y164048D02*
Y162867D01*
G01Y167985D02*
Y166804D01*
G01Y171922D02*
Y170741D01*
G01X947032Y154993D02*
Y152237D01*
G01Y158930D02*
Y156174D01*
G01Y162867D02*
Y160111D01*
G01Y166804D02*
Y164048D01*
G01Y170741D02*
Y167985D01*
G01X946561Y168969D02*
Y169756D01*
G01Y165032D02*
Y165819D01*
G01Y161095D02*
Y161882D01*
G01Y157158D02*
Y157945D01*
G01Y153221D02*
Y154008D01*
G01Y149284D02*
Y150071D01*
G01X946048Y150121D02*
Y149235D01*
G01Y154058D02*
Y153172D01*
G01Y157995D02*
Y157109D01*
G01Y161932D02*
Y161046D01*
G01Y165869D02*
Y164983D01*
G01Y169806D02*
Y168920D01*
G01X945677Y168969D02*
Y169756D01*
G01Y165032D02*
Y165819D01*
G01Y161095D02*
Y161882D01*
G01Y157158D02*
Y157945D01*
G01Y153221D02*
Y154008D01*
G01Y149284D02*
Y150071D01*
G01X945605Y168969D02*
Y169756D01*
G01Y165032D02*
Y165819D01*
G01Y161095D02*
Y161882D01*
G01Y157158D02*
Y157945D01*
G01Y153221D02*
Y154008D01*
G01Y149284D02*
Y150071D01*
G01X945457Y153172D02*
Y150121D01*
G01Y157109D02*
Y154058D01*
G01Y161046D02*
Y157995D01*
G01Y164983D02*
Y161932D01*
G01Y168920D02*
Y165869D01*
G01Y172857D02*
Y169806D01*
G01X945426Y168969D02*
Y169756D01*
G01Y165032D02*
Y165819D01*
G01Y161095D02*
Y161882D01*
G01Y157158D02*
Y157945D01*
G01Y153221D02*
Y154008D01*
G01Y149284D02*
Y150071D01*
G01X945063Y149875D02*
Y149481D01*
G01Y153812D02*
Y153418D01*
G01Y157749D02*
Y157355D01*
G01Y161686D02*
Y161292D01*
G01Y165623D02*
Y165229D01*
G01Y169560D02*
Y169166D01*
G01X944057Y168969D02*
Y169756D01*
G01Y165032D02*
Y165819D01*
G01Y161095D02*
Y161882D01*
G01Y157158D02*
Y157945D01*
G01Y153221D02*
Y154008D01*
G01Y149284D02*
Y150071D01*
G01X943882Y169166D02*
Y169560D01*
G01Y165229D02*
Y165623D01*
G01Y161292D02*
Y161686D01*
G01Y157355D02*
Y157749D01*
G01Y153418D02*
Y153812D01*
G01Y149481D02*
Y149875D01*
G01X943685Y150071D02*
Y149284D01*
G01Y154008D02*
Y153221D01*
G01Y157945D02*
Y157158D01*
G01Y161882D02*
Y161095D01*
G01Y165819D02*
Y165032D01*
G01Y169756D02*
Y168969D01*
G01X943528Y150121D02*
Y149235D01*
G01Y154058D02*
Y153172D01*
G01Y157995D02*
Y157109D01*
G01Y161932D02*
Y161046D01*
G01Y165869D02*
Y164983D01*
G01Y169806D02*
Y168920D01*
G01X943488Y169806D02*
Y172857D01*
G01Y168969D02*
Y169756D01*
G01Y165869D02*
Y168920D01*
G01Y165032D02*
Y165819D01*
G01Y161932D02*
Y164983D01*
G01Y161095D02*
Y161882D01*
G01Y157995D02*
Y161046D01*
G01Y157158D02*
Y157945D01*
G01Y154058D02*
Y157109D01*
G01Y153221D02*
Y154008D01*
G01Y150121D02*
Y153172D01*
G01Y149284D02*
Y150071D01*
G01X943340D02*
Y149284D01*
G01Y154008D02*
Y153221D01*
G01Y157945D02*
Y157158D01*
G01Y161882D02*
Y161095D01*
G01Y165819D02*
Y165032D01*
G01Y169756D02*
Y168969D01*
G01X943268Y150071D02*
Y149284D01*
G01Y154008D02*
Y153221D01*
G01Y157945D02*
Y157158D01*
G01Y161882D02*
Y161095D01*
G01Y165819D02*
Y165032D01*
G01Y169756D02*
Y168969D01*
G01X943134Y150121D02*
Y149235D01*
G01Y154058D02*
Y153172D01*
G01Y157995D02*
Y157109D01*
G01Y161932D02*
Y161046D01*
G01Y165869D02*
Y164983D01*
G01Y169806D02*
Y168920D01*
G01X941796Y164983D02*
Y165869D01*
G01Y157109D02*
Y157995D01*
G01Y149235D02*
Y150121D01*
G01Y154058D02*
Y153172D01*
G01Y161932D02*
Y161046D01*
G01Y169806D02*
Y168920D01*
G01X941441Y150071D02*
Y149284D01*
G01Y154008D02*
Y153221D01*
G01Y157945D02*
Y157158D01*
G01Y161882D02*
Y161095D01*
G01Y165819D02*
Y165032D01*
G01Y169756D02*
Y168969D01*
G01X941402Y150121D02*
Y149235D01*
G01Y154058D02*
Y153172D01*
G01Y157995D02*
Y157109D01*
G01Y161932D02*
Y161046D01*
G01Y165869D02*
Y164983D01*
G01Y169806D02*
Y168920D01*
G01X941346Y168969D02*
Y169756D01*
G01Y165032D02*
Y165819D01*
G01Y161095D02*
Y161882D01*
G01Y157158D02*
Y157945D01*
G01Y153221D02*
Y154008D01*
G01Y149284D02*
Y150071D01*
G01X941274Y168969D02*
Y169756D01*
G01Y165032D02*
Y165819D01*
G01Y161095D02*
Y161882D01*
G01Y157158D02*
Y157945D01*
G01Y153221D02*
Y154008D01*
G01Y149284D02*
Y150071D01*
G01X941244D02*
Y149284D01*
G01Y154008D02*
Y153221D01*
G01Y157945D02*
Y157158D01*
G01Y161882D02*
Y161095D01*
G01Y165819D02*
Y165032D01*
G01Y169756D02*
Y168969D01*
G01X941126Y153172D02*
Y150121D01*
G01Y157109D02*
Y154058D01*
G01Y161046D02*
Y157995D01*
G01Y164983D02*
Y161932D01*
G01Y168920D02*
Y165869D01*
G01Y172857D02*
Y169806D01*
G01X940928Y149922D02*
Y149434D01*
G01Y153859D02*
Y153371D01*
G01Y157796D02*
Y157308D01*
G01Y161733D02*
Y161245D01*
G01Y165670D02*
Y165182D01*
G01Y169607D02*
Y169119D01*
G01X940733Y149875D02*
Y149481D01*
G01Y153812D02*
Y153418D01*
G01Y157749D02*
Y157355D01*
G01Y161686D02*
Y161292D01*
G01Y165623D02*
Y165229D01*
G01Y169560D02*
Y169166D01*
G01X939985Y169119D02*
Y169607D01*
G01Y165182D02*
Y165670D01*
G01Y161245D02*
Y161733D01*
G01Y157308D02*
Y157796D01*
G01Y153371D02*
Y153859D01*
G01Y149434D02*
Y149922D01*
G01X939670Y150121D02*
Y149235D01*
G01Y154058D02*
Y153172D01*
G01Y157995D02*
Y157109D01*
G01Y161932D02*
Y161046D01*
G01Y165869D02*
Y164983D01*
G01Y169806D02*
Y168920D01*
G01X939551Y169166D02*
Y169560D01*
G01Y165229D02*
Y165623D01*
G01Y161292D02*
Y161686D01*
G01Y157355D02*
Y157749D01*
G01Y153418D02*
Y153812D01*
G01Y149481D02*
Y149875D01*
G01X939473Y168969D02*
Y169756D01*
G01Y165032D02*
Y165819D01*
G01Y161095D02*
Y161882D01*
G01Y157158D02*
Y157945D01*
G01Y153221D02*
Y154008D01*
G01Y149284D02*
Y150071D01*
G01X939276Y150121D02*
Y149235D01*
G01Y154058D02*
Y153172D01*
G01Y157995D02*
Y157109D01*
G01Y161932D02*
Y161046D01*
G01Y165869D02*
Y164983D01*
G01Y169806D02*
Y168920D01*
G01X939158Y169806D02*
Y172857D01*
G01Y165869D02*
Y168920D01*
G01Y161932D02*
Y164983D01*
G01Y157995D02*
Y161046D01*
G01Y154058D02*
Y157109D01*
G01Y150121D02*
Y153172D01*
G01X939010Y150071D02*
Y149284D01*
G01Y154008D02*
Y153221D01*
G01Y157945D02*
Y157158D01*
G01Y161882D02*
Y161095D01*
G01Y165819D02*
Y165032D01*
G01Y169756D02*
Y168969D01*
G01X938938Y150071D02*
Y149284D01*
G01Y154008D02*
Y153221D01*
G01Y157945D02*
Y157158D01*
G01Y161882D02*
Y161095D01*
G01Y165819D02*
Y165032D01*
G01Y169756D02*
Y168969D01*
G01X938488D02*
Y169756D01*
G01Y165032D02*
Y165819D01*
G01Y161095D02*
Y161882D01*
G01Y157158D02*
Y157945D01*
G01Y153221D02*
Y154008D01*
G01Y149284D02*
Y150071D01*
G01X937977Y168920D02*
Y169806D01*
G01Y164983D02*
Y165869D01*
G01Y161046D02*
Y161932D01*
G01Y157109D02*
Y157995D01*
G01Y153172D02*
Y154058D01*
G01Y149235D02*
Y150121D01*
G01X937583Y154451D02*
Y152778D01*
G01Y158388D02*
Y156715D01*
G01Y162325D02*
Y160652D01*
G01Y166262D02*
Y164589D01*
G01Y170199D02*
Y168526D01*
G01X936205Y169560D02*
Y192197D01*
G01X935024Y195741D02*
Y169560D01*
G01X940928Y157308D02*
X940956Y157176D01*
G01X939985Y161733D02*
X939958Y161865D01*
G01X940928Y153371D02*
X940956Y153239D01*
G01X939985Y157796D02*
X939958Y157928D01*
G01X940928Y149434D02*
X940956Y149302D01*
G01X939985Y153859D02*
X939958Y153991D01*
G01X939985Y149922D02*
X939958Y150054D01*
G01X939511Y188709D02*
X939469Y188654D01*
G01X939540Y188776D02*
X939511Y188709D01*
G01X939551Y188851D02*
X939540Y188776D01*
G01X939511Y184772D02*
X939469Y184717D01*
G01X939540Y184839D02*
X939511Y184772D01*
G01X939551Y184914D02*
X939540Y184839D01*
G01X940773Y189387D02*
X940815Y189441D01*
G01X940744Y189319D02*
X940773Y189387D01*
G01X940733Y189245D02*
X940744Y189319D01*
G01X939511Y180835D02*
X939469Y180780D01*
G01X939540Y180902D02*
X939511Y180835D01*
G01X939551Y180977D02*
X939540Y180902D01*
G01Y173571D02*
X939551Y173497D01*
G01X939511Y173639D02*
X939540Y173571D01*
G01X939469Y173693D02*
X939511Y173639D01*
G01X939953Y173691D02*
X939950Y173693D01*
G01X939955Y173686D02*
X939953Y173691D01*
G01X939958Y173676D02*
X939955Y173686D01*
G01X940961Y172908D02*
X940964Y172906D01*
G01X940959Y172914D02*
X940961Y172908D01*
G01X940956Y172924D02*
X940959Y172914D01*
G01X939953Y177628D02*
X939950Y177630D01*
G01X939955Y177623D02*
X939953Y177628D01*
G01X939958Y177613D02*
X939955Y177623D01*
G01X940961Y176845D02*
X940964Y176843D01*
G01X940959Y176851D02*
X940961Y176845D01*
G01X940956Y176861D02*
X940959Y176851D01*
G01X939953Y181565D02*
X939950Y181567D01*
G01X939955Y181560D02*
X939953Y181565D01*
G01X939958Y181550D02*
X939955Y181560D01*
G01X940961Y180782D02*
X940964Y180780D01*
G01X940959Y180788D02*
X940961Y180782D01*
G01X940956Y180798D02*
X940959Y180788D01*
G01X939953Y185502D02*
X939950Y185504D01*
G01X939955Y185497D02*
X939953Y185502D01*
G01X939958Y185487D02*
X939955Y185497D01*
G01X940961Y184719D02*
X940964Y184717D01*
G01X940959Y184725D02*
X940961Y184719D01*
G01X940956Y184735D02*
X940959Y184725D01*
G01X939953Y189439D02*
X939950Y189441D01*
G01X939955Y189434D02*
X939953Y189439D01*
G01X939958Y189424D02*
X939955Y189434D01*
G01X940961Y188656D02*
X940964Y188654D01*
G01X940959Y188662D02*
X940961Y188656D01*
G01X940956Y188672D02*
X940959Y188662D01*
G01X940773Y185450D02*
X940815Y185504D01*
G01X940744Y185382D02*
X940773Y185450D01*
G01X940733Y185308D02*
X940744Y185382D01*
G01X939511Y176898D02*
X939469Y176843D01*
G01X939540Y176965D02*
X939511Y176898D01*
G01X939551Y177040D02*
X939540Y176965D01*
G01X940773Y181513D02*
X940815Y181567D01*
G01X940744Y181445D02*
X940773Y181513D01*
G01X940733Y181371D02*
X940744Y181445D01*
G01X939511Y172961D02*
X939469Y172906D01*
G01X939540Y173028D02*
X939511Y172961D01*
G01X939551Y173103D02*
X939540Y173028D01*
G01X940773Y177576D02*
X940815Y177630D01*
G01X940744Y177508D02*
X940773Y177576D01*
G01X940733Y177434D02*
X940744Y177508D01*
G01X940773Y173639D02*
X940815Y173693D01*
G01X940744Y173571D02*
X940773Y173639D01*
G01X940733Y173497D02*
X940744Y173571D01*
G01X943842Y188709D02*
X943800Y188654D01*
G01X943871Y188776D02*
X943842Y188709D01*
G01X943882Y188851D02*
X943871Y188776D01*
G01X943842Y184772D02*
X943800Y184717D01*
G01X943871Y184839D02*
X943842Y184772D01*
G01X943882Y184914D02*
X943871Y184839D01*
G01X945103Y189387D02*
X945146Y189441D01*
G01X945074Y189319D02*
X945103Y189387D01*
G01X945063Y189245D02*
X945074Y189319D01*
G01X943842Y180835D02*
X943800Y180780D01*
G01X943871Y180902D02*
X943842Y180835D01*
G01X943882Y180977D02*
X943871Y180902D01*
G01X945103Y185450D02*
X945146Y185504D01*
G01X945074Y185382D02*
X945103Y185450D01*
G01X945063Y185308D02*
X945074Y185382D01*
G01X943842Y176898D02*
X943800Y176843D01*
G01X943871Y176965D02*
X943842Y176898D01*
G01X943882Y177040D02*
X943871Y176965D01*
G01X945103Y181513D02*
X945146Y181567D01*
G01X945074Y181445D02*
X945103Y181513D01*
G01X945063Y181371D02*
X945074Y181445D01*
G01X943842Y172961D02*
X943800Y172906D01*
G01X943871Y173028D02*
X943842Y172961D01*
G01X943882Y173103D02*
X943871Y173028D01*
G01X945103Y177576D02*
X945146Y177630D01*
G01X945074Y177508D02*
X945103Y177576D01*
G01X945063Y177434D02*
X945074Y177508D01*
G01X945103Y173639D02*
X945146Y173693D01*
G01X945074Y173571D02*
X945103Y173639D01*
G01X945063Y173497D02*
X945074Y173571D01*
G01X940744Y173028D02*
X940733Y173103D01*
G01X940773Y172961D02*
X940744Y173028D01*
G01X940815Y172906D02*
X940773Y172961D01*
G01X939540Y177508D02*
X939551Y177434D01*
G01X939511Y177576D02*
X939540Y177508D01*
G01X939469Y177630D02*
X939511Y177576D01*
G01X940744Y176965D02*
X940733Y177040D01*
G01X940773Y176898D02*
X940744Y176965D01*
G01X940815Y176843D02*
X940773Y176898D01*
G01X943871Y173571D02*
X943882Y173497D01*
G01X943842Y173639D02*
X943871Y173571D01*
G01X943800Y173693D02*
X943842Y173639D01*
G01X945074Y173028D02*
X945063Y173103D01*
G01X945103Y172961D02*
X945074Y173028D01*
G01X945146Y172906D02*
X945103Y172961D01*
G01X939540Y181445D02*
X939551Y181371D01*
G01X939511Y181513D02*
X939540Y181445D01*
G01X939469Y181567D02*
X939511Y181513D01*
G01X940744Y180902D02*
X940733Y180977D01*
G01X940773Y180835D02*
X940744Y180902D01*
G01X940815Y180780D02*
X940773Y180835D01*
G01X943871Y177508D02*
X943882Y177434D01*
G01X943842Y177576D02*
X943871Y177508D01*
G01X943800Y177630D02*
X943842Y177576D01*
G01X945074Y176965D02*
X945063Y177040D01*
G01X945103Y176898D02*
X945074Y176965D01*
G01X945146Y176843D02*
X945103Y176898D01*
G01X939540Y185382D02*
X939551Y185308D01*
G01X939511Y185450D02*
X939540Y185382D01*
G01X939469Y185504D02*
X939511Y185450D01*
G01X940744Y184839D02*
X940733Y184914D01*
G01X940773Y184772D02*
X940744Y184839D01*
G01X940815Y184717D02*
X940773Y184772D01*
G01X943871Y181445D02*
X943882Y181371D01*
G01X943842Y181513D02*
X943871Y181445D01*
G01X943800Y181567D02*
X943842Y181513D01*
G01X945074Y180902D02*
X945063Y180977D01*
G01X945103Y180835D02*
X945074Y180902D01*
G01X945146Y180780D02*
X945103Y180835D01*
G01X939540Y189319D02*
X939551Y189245D01*
G01X939511Y189387D02*
X939540Y189319D01*
G01X939469Y189441D02*
X939511Y189387D01*
G01X940744Y188776D02*
X940733Y188851D01*
G01X940773Y188709D02*
X940744Y188776D01*
G01X940815Y188654D02*
X940773Y188709D01*
G01X943871Y185382D02*
X943882Y185308D01*
G01X943842Y185450D02*
X943871Y185382D01*
G01X943800Y185504D02*
X943842Y185450D01*
G01X945074Y184839D02*
X945063Y184914D01*
G01X945103Y184772D02*
X945074Y184839D01*
G01X945146Y184717D02*
X945103Y184772D01*
G01X943871Y189319D02*
X943882Y189245D01*
G01X943842Y189387D02*
X943871Y189319D01*
G01X943800Y189441D02*
X943842Y189387D01*
G01X945074Y188776D02*
X945063Y188851D01*
G01X945103Y188709D02*
X945074Y188776D01*
G01X945146Y188654D02*
X945103Y188709D01*
G01X940183Y188913D02*
X940298Y188932D01*
G01X940084Y188884D02*
X940183Y188913D01*
G01X940015Y188846D02*
X940084Y188884D01*
G01X939985Y188804D02*
X940015Y188846D01*
G01X940731Y189183D02*
X940616Y189164D01*
G01X940830Y189212D02*
X940731Y189183D01*
G01X940898Y189250D02*
X940830Y189212D01*
G01X940928Y189292D02*
X940898Y189250D01*
G01X940183Y184976D02*
X940298Y184995D01*
G01X940084Y184947D02*
X940183Y184976D01*
G01X940015Y184909D02*
X940084Y184947D01*
G01X939985Y184867D02*
X940015Y184909D01*
G01X940731Y185246D02*
X940616Y185227D01*
G01X940830Y185275D02*
X940731Y185246D01*
G01X940898Y185313D02*
X940830Y185275D01*
G01X940928Y185355D02*
X940898Y185313D01*
G01X940183Y181039D02*
X940298Y181058D01*
G01X940084Y181010D02*
X940183Y181039D01*
G01X940015Y180972D02*
X940084Y181010D01*
G01X939985Y180930D02*
X940015Y180972D01*
G01X940731Y181309D02*
X940616Y181290D01*
G01X940830Y181338D02*
X940731Y181309D01*
G01X940898Y181376D02*
X940830Y181338D01*
G01X940928Y181418D02*
X940898Y181376D01*
G01X940183Y177102D02*
X940298Y177121D01*
G01X940084Y177073D02*
X940183Y177102D01*
G01X940015Y177035D02*
X940084Y177073D01*
G01X939985Y176993D02*
X940015Y177035D01*
G01X940731Y177372D02*
X940616Y177353D01*
G01X940830Y177401D02*
X940731Y177372D01*
G01X940898Y177439D02*
X940830Y177401D01*
G01X940928Y177481D02*
X940898Y177439D01*
G01X940183Y173165D02*
X940298Y173184D01*
G01X940084Y173136D02*
X940183Y173165D01*
G01X940015Y173098D02*
X940084Y173136D01*
G01X939985Y173056D02*
X940015Y173098D01*
G01X940731Y173435D02*
X940616Y173416D01*
G01X940830Y173464D02*
X940731Y173435D01*
G01X940898Y173502D02*
X940830Y173464D01*
G01X940928Y173544D02*
X940898Y173502D01*
G01X940566Y173192D02*
X940735Y173164D01*
G01X940513Y173205D02*
X940566Y173192D01*
G01X940457Y173221D02*
X940513Y173205D01*
G01X940566Y177129D02*
X940735Y177101D01*
G01X940513Y177142D02*
X940566Y177129D01*
G01X940457Y177158D02*
X940513Y177142D01*
G01X940347Y173408D02*
X940179Y173436D01*
G01X940401Y173395D02*
X940347Y173408D01*
G01X940457Y173378D02*
X940401Y173395D01*
G01X940347Y177345D02*
X940179Y177373D01*
G01X940401Y177332D02*
X940347Y177345D01*
G01X940457Y177315D02*
X940401Y177332D01*
G01X940900Y173096D02*
X940928Y173056D01*
G01X940834Y173134D02*
X940900Y173096D01*
G01X940735Y173164D02*
X940834Y173134D01*
G01X940014Y173504D02*
X939985Y173544D01*
G01X940079Y173466D02*
X940014Y173504D01*
G01X940179Y173436D02*
X940079Y173466D01*
G01X940900Y177033D02*
X940928Y176993D01*
G01X940834Y177071D02*
X940900Y177033D01*
G01X940735Y177101D02*
X940834Y177071D01*
G01X940014Y177441D02*
X939985Y177481D01*
G01X940079Y177403D02*
X940014Y177441D01*
G01X940179Y177373D02*
X940079Y177403D01*
G01X940900Y180970D02*
X940928Y180930D01*
G01X940834Y181008D02*
X940900Y180970D01*
G01X940735Y181038D02*
X940834Y181008D01*
G01X940014Y181378D02*
X939985Y181418D01*
G01X940079Y181340D02*
X940014Y181378D01*
G01X940179Y181310D02*
X940079Y181340D01*
G01X940959Y189434D02*
X940956Y189424D01*
G01X940961Y189439D02*
X940959Y189434D01*
G01X940964Y189441D02*
X940961Y189439D01*
G01X939955Y188662D02*
X939958Y188672D01*
G01X939953Y188656D02*
X939955Y188662D01*
G01X939950Y188654D02*
X939953Y188656D01*
G01X940959Y185497D02*
X940956Y185487D01*
G01X940961Y185502D02*
X940959Y185497D01*
G01X940964Y185504D02*
X940961Y185502D01*
G01X939955Y184725D02*
X939958Y184735D01*
G01X939953Y184719D02*
X939955Y184725D01*
G01X939950Y184717D02*
X939953Y184719D01*
G01X940566Y181066D02*
X940735Y181038D01*
G01X940513Y181079D02*
X940566Y181066D01*
G01X940457Y181095D02*
X940513Y181079D01*
G01X940566Y185003D02*
X940735Y184975D01*
G01X940513Y185016D02*
X940566Y185003D01*
G01X940457Y185032D02*
X940513Y185016D01*
G01X940566Y188940D02*
X940735Y188912D01*
G01X940513Y188953D02*
X940566Y188940D01*
G01X940457Y188969D02*
X940513Y188953D01*
G01X940347Y181282D02*
X940179Y181310D01*
G01X940401Y181269D02*
X940347Y181282D01*
G01X940457Y181252D02*
X940401Y181269D01*
G01X940347Y185219D02*
X940179Y185247D01*
G01X940401Y185206D02*
X940347Y185219D01*
G01X940457Y185189D02*
X940401Y185206D01*
G01X940347Y189156D02*
X940179Y189184D01*
G01X940401Y189143D02*
X940347Y189156D01*
G01X940457Y189126D02*
X940401Y189143D01*
G01X940900Y184907D02*
X940928Y184867D01*
G01X940834Y184945D02*
X940900Y184907D01*
G01X940735Y184975D02*
X940834Y184945D01*
G01X940014Y185315D02*
X939985Y185355D01*
G01X940079Y185277D02*
X940014Y185315D01*
G01X940179Y185247D02*
X940079Y185277D01*
G01X940900Y188844D02*
X940928Y188804D01*
G01X940834Y188882D02*
X940900Y188844D01*
G01X940735Y188912D02*
X940834Y188882D01*
G01X940014Y189252D02*
X939985Y189292D01*
G01X940079Y189214D02*
X940014Y189252D01*
G01X940179Y189184D02*
X940079Y189214D01*
G01X940959Y181560D02*
X940956Y181550D01*
G01X940961Y181565D02*
X940959Y181560D01*
G01X940964Y181567D02*
X940961Y181565D01*
G01X939955Y180788D02*
X939958Y180798D01*
G01X939953Y180782D02*
X939955Y180788D01*
G01X939950Y180780D02*
X939953Y180782D01*
G01X940959Y177623D02*
X940956Y177613D01*
G01X940961Y177628D02*
X940959Y177623D01*
G01X940964Y177630D02*
X940961Y177628D01*
G01X939955Y176851D02*
X939958Y176861D01*
G01X939953Y176845D02*
X939955Y176851D01*
G01X939950Y176843D02*
X939953Y176845D01*
G01X940959Y173686D02*
X940956Y173676D01*
G01X940961Y173691D02*
X940959Y173686D01*
G01X940964Y173693D02*
X940961Y173691D01*
G01X939955Y172914D02*
X939958Y172924D01*
G01X939953Y172908D02*
X939955Y172914D01*
G01X939950Y172906D02*
X939953Y172908D01*
G01X940401Y173205D02*
X940457Y173221D01*
G01X940347Y173192D02*
X940401Y173205D01*
G01X940298Y173184D02*
X940347Y173192D01*
G01X940513Y173395D02*
X940457Y173378D01*
G01X940566Y173408D02*
X940513Y173395D01*
G01X940616Y173416D02*
X940566Y173408D01*
G01X940401Y177142D02*
X940457Y177158D01*
G01X940347Y177129D02*
X940401Y177142D01*
G01X940298Y177121D02*
X940347Y177129D01*
G01X940513Y177332D02*
X940457Y177315D01*
G01X940566Y177345D02*
X940513Y177332D01*
G01X940616Y177353D02*
X940566Y177345D01*
G01X940401Y181079D02*
X940457Y181095D01*
G01X940347Y181066D02*
X940401Y181079D01*
G01X940298Y181058D02*
X940347Y181066D01*
G01X940513Y181269D02*
X940457Y181252D01*
G01X940566Y181282D02*
X940513Y181269D01*
G01X940616Y181290D02*
X940566Y181282D01*
G01X940401Y185016D02*
X940457Y185032D01*
G01X940347Y185003D02*
X940401Y185016D01*
G01X940298Y184995D02*
X940347Y185003D01*
G01X940513Y185206D02*
X940457Y185189D01*
G01X940566Y185219D02*
X940513Y185206D01*
G01X940616Y185227D02*
X940566Y185219D01*
G01X940401Y188953D02*
X940457Y188969D01*
G01X940347Y188940D02*
X940401Y188953D01*
G01X940298Y188932D02*
X940347Y188940D01*
G01X940513Y189143D02*
X940457Y189126D01*
G01X940566Y189156D02*
X940513Y189143D01*
G01X940616Y189164D02*
X940566Y189156D01*
G01X947977Y193213D02*
X948100Y193253D01*
G01X948059Y193495D02*
X947936Y193454D01*
G01X942307Y193772D02*
X934433D01*
G01X944276Y193733D02*
X945260D01*
G01X940339D02*
X935339D01*
G01X947032D02*
X946048D01*
G01X941126Y193575D02*
X938370D01*
G01X947936Y193454D02*
X947813D01*
G01X945260Y193418D02*
X944276D01*
G01X947032D02*
X946048D01*
G01X947813Y193213D02*
X947977D01*
G01X944276Y193024D02*
X935024D01*
G01X946048D02*
X945260D01*
G01X947567Y192892D02*
X947361D01*
G01X949290D02*
X947977D01*
G01X935024Y192788D02*
X935103D01*
G01X947361Y192691D02*
X947567D01*
G01X947977D02*
X949290D01*
G01Y192369D02*
X947977D01*
G01X941323Y192197D02*
X945851D01*
G01X936205D02*
X938174D01*
G01X948346Y192168D02*
X949290D01*
G01X947977D02*
X948182D01*
G01X938370Y192000D02*
X936402D01*
G01X945654D02*
X941126D01*
G01X949290Y191445D02*
X948511D01*
G01X943488Y191410D02*
X945457D01*
G01X939158D02*
X941126D01*
G01X948511Y191244D02*
X949290D01*
G01X947977Y190923D02*
X947649D01*
G01X949290Y190681D02*
X947690D01*
G01X947361Y190440D02*
X949290D01*
G01X937583Y189884D02*
X946638D01*
G01X937977Y189491D02*
X946638D01*
G01X938488Y189441D02*
X949788D01*
G01X940956Y189424D02*
X939958D01*
G01X943882Y189245D02*
X945063D01*
G01X939551D02*
X940733D01*
G01X940298Y189164D02*
X940616D01*
G01Y188932D02*
X940298D01*
G01X940733Y188851D02*
X939551D01*
G01X945063D02*
X943882D01*
G01X939958Y188672D02*
X940956D01*
G01X938488Y188654D02*
X949788D01*
G01X946638Y188605D02*
X937977D01*
G01X937583Y188211D02*
X946638D01*
G01X937583Y185947D02*
X946638D01*
G01X937977Y185554D02*
X946638D01*
G01X938488Y185504D02*
X949788D01*
G01X940956Y185487D02*
X939958D01*
G01X943882Y185308D02*
X945063D01*
G01X939551D02*
X940733D01*
G01X940298Y185227D02*
X940616D01*
G01Y184995D02*
X940298D01*
G01X940733Y184914D02*
X939551D01*
G01X945063D02*
X943882D01*
G01X939958Y184735D02*
X940956D01*
G01X938488Y184717D02*
X949788D01*
G01X946638Y184668D02*
X937977D01*
G01X937583Y184274D02*
X946638D01*
G01X937583Y182010D02*
X946638D01*
G01X937977Y181617D02*
X946638D01*
G01X938488Y181567D02*
X949788D01*
G01X940956Y181550D02*
X939958D01*
G01X943882Y181371D02*
X945063D01*
G01X939551D02*
X940733D01*
G01X940298Y181290D02*
X940616D01*
G01Y181058D02*
X940298D01*
G01X940733Y180977D02*
X939551D01*
G01X945063D02*
X943882D01*
G01X939958Y180798D02*
X940956D01*
G01X938488Y180780D02*
X949788D01*
G01X946638Y180731D02*
X937977D01*
G01X937583Y180337D02*
X946638D01*
G01X937583Y178073D02*
X946638D01*
G01X937977Y177680D02*
X946638D01*
G01X938488Y177630D02*
X949788D01*
G01X940956Y177613D02*
X939958D01*
G01X943882Y177434D02*
X945063D01*
G01X939551D02*
X940733D01*
G01X940298Y177353D02*
X940616D01*
G01Y177121D02*
X940298D01*
G01X940733Y177040D02*
X939551D01*
G01X945063D02*
X943882D01*
G01X939958Y176861D02*
X940956D01*
G01X938488Y176843D02*
X949788D01*
G01X946638Y176794D02*
X937977D01*
G01X937583Y176400D02*
X946638D01*
G01X937583Y174136D02*
X946638D01*
G01X937977Y173743D02*
X946638D01*
G01X938488Y173693D02*
X949788D01*
G01X940956Y173676D02*
X939958D01*
G01X943882Y173497D02*
X945063D01*
G01X939551D02*
X940733D01*
G01X940298Y173416D02*
X940616D01*
G01Y173184D02*
X940298D01*
G01X940733Y173103D02*
X939551D01*
G01X945063D02*
X943882D01*
G01X939958Y172924D02*
X940956D01*
G01X938488Y172906D02*
X949788D01*
G01X946638Y172857D02*
X937977D01*
G01X937583Y172463D02*
X946638D01*
G01X947819Y171922D02*
X947032D01*
G01X942701Y194000D02*
X942307Y193772D01*
G01X948511Y191445D02*
X948305Y191485D01*
G01Y191284D02*
X948511Y191244D01*
G01X938764Y194000D02*
X938370Y193772D01*
G01X948100Y193253D02*
X948264Y193374D01*
G01X947813Y193454D02*
X947690Y193495D01*
G01Y193253D02*
X947813Y193213D01*
G01X948182Y191324D02*
X948305Y191284D01*
G01X947690Y190681D02*
X947977Y190923D01*
G01X947649D02*
X947361Y190681D01*
G01X948264Y192088D02*
X948346Y192168D01*
G01X948182D02*
X948100Y192088D01*
G01X948141Y193575D02*
X948059Y193495D01*
G01X937583Y172463D02*
X937977Y172857D01*
G01X937583Y176400D02*
X937977Y176794D01*
G01X937583Y180337D02*
X937977Y180731D01*
G01X945851Y192197D02*
X945654Y192000D01*
G01X937583Y184274D02*
X937977Y184668D01*
G01X937583Y188211D02*
X937977Y188605D01*
G01X941323Y192197D02*
X941126Y192000D01*
G01Y193575D02*
X941323Y193772D01*
G01X936717Y193733D02*
X936402Y193418D01*
G01X935339Y193733D02*
X935024Y193418D01*
G01X934827Y194560D02*
X934630Y194363D01*
G01X942307Y194560D02*
X942701Y194332D01*
G01X938764D02*
X938370Y194560D01*
G01X948264Y193374D02*
X948388Y193535D01*
G01X948182Y191967D02*
X948264Y192088D01*
G01X948100D02*
X948018Y191967D01*
G01X947526Y193374D02*
X947690Y193253D01*
G01X938370Y193575D02*
X938174Y193772D01*
G01X938370Y192000D02*
X938174Y192197D01*
G01X934827Y193772D02*
X934630Y193969D01*
G01X936402Y192000D02*
X936205Y192197D01*
G01X937977Y189491D02*
X937583Y189884D01*
G01X947690Y193495D02*
X947608Y193575D01*
G01X948305Y191485D02*
X948224Y191565D01*
G01X948100Y191405D02*
X948182Y191324D01*
G01Y193695D02*
X948141Y193575D01*
G01X948224Y191565D02*
X948182Y191646D01*
G01X948018Y191525D02*
X948100Y191405D01*
G01X947403Y193535D02*
X947526Y193374D01*
G01X937977Y185554D02*
X937583Y185947D01*
G01X937977Y181617D02*
X937583Y182010D01*
G01X937977Y177680D02*
X937583Y178073D01*
G01X937977Y173743D02*
X937583Y174136D01*
G01X948141Y191806D02*
X948182Y191967D01*
G01X948018D02*
X947977Y191806D01*
G01X940956Y173676D02*
X940928Y173544D01*
G01X940956Y177613D02*
X940928Y177481D01*
G01X939958Y172924D02*
X939985Y173056D01*
G01X940956Y181550D02*
X940928Y181418D01*
G01X939958Y176861D02*
X939985Y176993D01*
G01X940956Y185487D02*
X940928Y185355D01*
G01X939958Y180798D02*
X939985Y180930D01*
G01X940956Y189424D02*
X940928Y189292D01*
G01X939958Y184735D02*
X939985Y184867D01*
G01X939958Y188672D02*
X939985Y188804D01*
G01X948388Y193535D02*
X948429Y193736D01*
G01X947361D02*
X947403Y193535D01*
G01X940928Y188804D02*
X940956Y188672D01*
G01X940928Y184867D02*
X940956Y184735D01*
G01X939985Y189292D02*
X939958Y189424D01*
G01X940928Y180930D02*
X940956Y180798D01*
G01X939985Y185355D02*
X939958Y185487D01*
G01X940928Y176993D02*
X940956Y176861D01*
G01X939985Y181418D02*
X939958Y181550D01*
G01X940928Y173056D02*
X940956Y172924D01*
G01X939985Y177481D02*
X939958Y177613D01*
G01X939985Y173544D02*
X939958Y173676D01*
G01X948182Y191646D02*
X948141Y191806D01*
G01X947608Y193575D02*
X947567Y193695D01*
G01X947977Y191646D02*
X948018Y191525D01*
G01X949788Y173693D02*
Y172906D01*
G01Y177630D02*
Y176843D01*
G01Y181567D02*
Y180780D01*
G01Y185504D02*
Y184717D01*
G01Y189441D02*
Y188654D01*
G01X949290Y192168D02*
Y192369D01*
G01Y192691D02*
Y192892D01*
G01Y191244D02*
Y191445D01*
G01Y190440D02*
Y190681D01*
G01X949197Y173693D02*
Y172906D01*
G01Y177630D02*
Y176843D01*
G01Y181567D02*
Y180780D01*
G01Y185504D02*
Y184717D01*
G01Y189441D02*
Y188654D01*
G01X948429Y193736D02*
Y194459D01*
G01X948182D02*
Y193695D01*
G01X947977Y191806D02*
Y191646D01*
G01Y192369D02*
Y192168D01*
G01Y192892D02*
Y192691D01*
G01X947762Y188654D02*
Y189441D01*
G01Y184717D02*
Y185504D01*
G01Y180780D02*
Y181567D01*
G01Y176843D02*
Y177630D01*
G01Y172906D02*
Y173693D01*
G01X947567Y193695D02*
Y194459D01*
G01Y192691D02*
Y192892D01*
G01X947361Y190681D02*
Y190440D01*
G01Y192892D02*
Y192691D01*
G01Y194700D02*
Y193736D01*
G01X947032Y195741D02*
Y171922D01*
G01X946561Y188654D02*
Y189441D01*
G01Y184717D02*
Y185504D01*
G01Y180780D02*
Y181567D01*
G01Y176843D02*
Y177630D01*
G01Y172906D02*
Y173693D01*
G01X946048Y173743D02*
Y172857D01*
G01Y177680D02*
Y176794D01*
G01Y181617D02*
Y180731D01*
G01Y185554D02*
Y184668D01*
G01Y189491D02*
Y188605D01*
G01Y194599D02*
Y193024D01*
G01X945677Y188654D02*
Y189441D01*
G01Y184717D02*
Y185504D01*
G01Y180780D02*
Y181567D01*
G01Y176843D02*
Y177630D01*
G01Y172906D02*
Y173693D01*
G01X945605Y188654D02*
Y189441D01*
G01Y184717D02*
Y185504D01*
G01Y180780D02*
Y181567D01*
G01Y176843D02*
Y177630D01*
G01Y172906D02*
Y173693D01*
G01X945457Y176794D02*
Y173743D01*
G01Y180731D02*
Y177680D01*
G01Y184668D02*
Y181617D01*
G01Y188605D02*
Y185554D01*
G01Y191410D02*
Y189491D01*
G01X945426Y188654D02*
Y189441D01*
G01Y184717D02*
Y185504D01*
G01Y180780D02*
Y181567D01*
G01Y176843D02*
Y177630D01*
G01Y172906D02*
Y173693D01*
G01X945260Y194599D02*
Y193024D01*
G01X945063Y173497D02*
Y173103D01*
G01Y177434D02*
Y177040D01*
G01Y181371D02*
Y180977D01*
G01Y185308D02*
Y184914D01*
G01Y189245D02*
Y188851D01*
G01X944945Y193733D02*
Y194599D01*
G01X944591D02*
Y193733D01*
G01X944276Y194599D02*
Y193024D01*
G01X944057Y188654D02*
Y189441D01*
G01Y184717D02*
Y185504D01*
G01Y180780D02*
Y181567D01*
G01Y176843D02*
Y177630D01*
G01Y172906D02*
Y173693D01*
G01X943882Y188851D02*
Y189245D01*
G01Y184914D02*
Y185308D01*
G01Y180977D02*
Y181371D01*
G01Y177040D02*
Y177434D01*
G01Y173103D02*
Y173497D01*
G01X943685Y173693D02*
Y172906D01*
G01Y177630D02*
Y176843D01*
G01Y181567D02*
Y180780D01*
G01Y185504D02*
Y184717D01*
G01Y189441D02*
Y188654D01*
G01X943528Y173743D02*
Y172857D01*
G01Y177680D02*
Y176794D01*
G01Y181617D02*
Y180731D01*
G01Y185554D02*
Y184668D01*
G01Y189491D02*
Y188605D01*
G01X943488Y189491D02*
Y191410D01*
G01Y188654D02*
Y189441D01*
G01Y185554D02*
Y188605D01*
G01Y184717D02*
Y185504D01*
G01Y181617D02*
Y184668D01*
G01Y180780D02*
Y181567D01*
G01Y177680D02*
Y180731D01*
G01Y176843D02*
Y177630D01*
G01Y173743D02*
Y176794D01*
G01Y172906D02*
Y173693D01*
G01X943340D02*
Y172906D01*
G01Y177630D02*
Y176843D01*
G01Y181567D02*
Y180780D01*
G01Y185504D02*
Y184717D01*
G01Y189441D02*
Y188654D01*
G01X943292Y194599D02*
Y193024D01*
G01X943268Y173693D02*
Y172906D01*
G01Y177630D02*
Y176843D01*
G01Y181567D02*
Y180780D01*
G01Y185504D02*
Y184717D01*
G01Y189441D02*
Y188654D01*
G01X943134Y173743D02*
Y172857D01*
G01Y177680D02*
Y176794D01*
G01Y181617D02*
Y180731D01*
G01Y185554D02*
Y184668D01*
G01Y189491D02*
Y188605D01*
G01X943095Y194599D02*
Y193024D01*
G01X942977D02*
Y194914D01*
G01X942701Y194332D02*
Y194000D01*
G01X941906Y193772D02*
Y194560D01*
G01X941796Y188605D02*
Y189491D01*
G01Y180731D02*
Y181617D01*
G01Y172857D02*
Y173743D01*
G01Y177680D02*
Y176794D01*
G01Y185554D02*
Y184668D01*
G01X941559Y193772D02*
Y194560D01*
G01X941546D02*
Y193772D01*
G01X941441Y173693D02*
Y172906D01*
G01Y177630D02*
Y176843D01*
G01Y181567D02*
Y180780D01*
G01Y185504D02*
Y184717D01*
G01Y189441D02*
Y188654D01*
G01X941402Y173743D02*
Y172857D01*
G01Y177680D02*
Y176794D01*
G01Y181617D02*
Y180731D01*
G01Y185554D02*
Y184668D01*
G01Y189491D02*
Y188605D01*
G01X941376Y194560D02*
Y193772D01*
G01X941346Y188654D02*
Y189441D01*
G01Y184717D02*
Y185504D01*
G01Y180780D02*
Y181567D01*
G01Y176843D02*
Y177630D01*
G01Y172906D02*
Y173693D01*
G01X941323Y193772D02*
Y192197D01*
G01X941274Y188654D02*
Y189441D01*
G01Y184717D02*
Y185504D01*
G01Y180780D02*
Y181567D01*
G01Y176843D02*
Y177630D01*
G01Y172906D02*
Y173693D01*
G01X941244D02*
Y172906D01*
G01Y177630D02*
Y176843D01*
G01Y181567D02*
Y180780D01*
G01Y185504D02*
Y184717D01*
G01Y189441D02*
Y188654D01*
G01X941126Y192000D02*
Y193575D01*
G01Y176794D02*
Y173743D01*
G01Y180731D02*
Y177680D01*
G01Y184668D02*
Y181617D01*
G01Y188605D02*
Y185554D01*
G01Y191410D02*
Y189491D01*
G01X940928Y173544D02*
Y173056D01*
G01Y177481D02*
Y176993D01*
G01Y181418D02*
Y180930D01*
G01Y185355D02*
Y184867D01*
G01Y189292D02*
Y188804D01*
G01X940733Y173497D02*
Y173103D01*
G01Y177434D02*
Y177040D01*
G01Y181371D02*
Y180977D01*
G01Y185308D02*
Y184914D01*
G01Y189245D02*
Y188851D01*
G01X940536Y193772D02*
Y194560D01*
G01X940355D02*
Y193772D01*
G01X940339Y193733D02*
Y194599D01*
G01X939985Y188804D02*
Y189292D01*
G01Y184867D02*
Y185355D01*
G01Y180930D02*
Y181418D01*
G01Y176993D02*
Y177481D01*
G01Y173056D02*
Y173544D01*
G01X939748Y194560D02*
Y193772D01*
G01X939670Y173743D02*
Y172857D01*
G01Y177680D02*
Y176794D01*
G01Y181617D02*
Y180731D01*
G01Y185554D02*
Y184668D01*
G01Y189491D02*
Y188605D01*
G01X939551Y188851D02*
Y189245D01*
G01Y184914D02*
Y185308D01*
G01Y180977D02*
Y181371D01*
G01Y177040D02*
Y177434D01*
G01Y173103D02*
Y173497D01*
G01X939473Y188654D02*
Y189441D01*
G01Y184717D02*
Y185504D01*
G01Y180780D02*
Y181567D01*
G01Y176843D02*
Y177630D01*
G01Y172906D02*
Y173693D01*
G01X939276Y173743D02*
Y172857D01*
G01Y177680D02*
Y176794D01*
G01Y181617D02*
Y180731D01*
G01Y185554D02*
Y184668D01*
G01Y189491D02*
Y188605D01*
G01X939158Y189491D02*
Y191410D01*
G01Y185554D02*
Y188605D01*
G01Y181617D02*
Y184668D01*
G01Y177680D02*
Y180731D01*
G01Y173743D02*
Y176794D01*
G01Y194599D02*
Y193024D01*
G01X939010Y173693D02*
Y172906D01*
G01Y177630D02*
Y176843D01*
G01Y181567D02*
Y180780D01*
G01Y185504D02*
Y184717D01*
G01Y189441D02*
Y188654D01*
G01X938938Y173693D02*
Y172906D01*
G01Y177630D02*
Y176843D01*
G01Y181567D02*
Y180780D01*
G01Y185504D02*
Y184717D01*
G01Y189441D02*
Y188654D01*
G01X938764Y194332D02*
Y194000D01*
G01X938488Y188654D02*
Y189441D01*
G01Y184717D02*
Y185504D01*
G01Y180780D02*
Y181567D01*
G01Y176843D02*
Y177630D01*
G01Y172906D02*
Y173693D01*
G01X938370Y193575D02*
Y192000D01*
G01X938174Y192197D02*
Y194560D01*
G01X938128D02*
Y193772D01*
G01X938029D02*
Y194560D01*
G01X937977Y188605D02*
Y189491D01*
G01Y184668D02*
Y185554D01*
G01Y180731D02*
Y181617D01*
G01Y176794D02*
Y177680D01*
G01Y172857D02*
Y173743D01*
G01X937583Y174136D02*
Y172463D01*
G01Y178073D02*
Y176400D01*
G01Y182010D02*
Y180337D01*
G01Y185947D02*
Y184274D01*
G01Y189884D02*
Y188211D01*
G01X937574Y193772D02*
Y194560D01*
G01X937394D02*
Y193772D01*
G01X936717Y194599D02*
Y193733D01*
G01X936599Y194560D02*
Y193772D01*
G01X936402Y194599D02*
Y193733D01*
G01X935339Y193024D02*
Y194599D01*
G01X935103Y192788D02*
Y194756D01*
G01X934827Y193772D02*
Y194560D01*
G01X934729D02*
Y193772D01*
G01X934630Y194363D02*
Y193969D01*
G01X934433Y194560D02*
Y193772D01*
G01X947032Y195741D02*
X935024D01*
G01X942977Y194914D02*
X947032D01*
G01X935024Y194756D02*
X935103D01*
G01X949290Y194700D02*
X947361D01*
G01X935339Y194599D02*
X943095D01*
G01X947032D02*
X943292D01*
G01X942307Y194560D02*
X934433D01*
G01X948429Y194459D02*
X949290D01*
G01X947567D02*
X948182D01*
G01X943292Y194599D02*
X942977Y194914D01*
G01X936717Y194599D02*
X936402Y194914D01*
G01X935339Y194599D02*
X935024Y194914D01*
G01X949290Y194459D02*
Y194700D01*
G01X936402Y195741D02*
Y194914D01*
G01X941607Y226859D02*
X1157565D01*
G01X938458D02*
X941607D01*
G01X950990Y231190D02*
X950269Y233355D01*
G01X952434Y229746D02*
X950990Y231190D01*
G01X954600Y229025D02*
X952434Y229746D01*
G01X956765D02*
X954600Y229025D01*
G01Y237686D02*
X956765Y236964D01*
G01X952434D02*
X954600Y237686D01*
G01X950990Y235521D02*
X952434Y236964D01*
G01X950269Y233355D02*
X950990Y235521D01*
G01Y226859D02*
X958208Y239851D01*
G01X950224Y499282D02*
G03X952192Y497313I1969J0D01*
G01D02*
X967940D01*
G01X950224Y516999D02*
Y499282D01*
G01X952192Y518967D02*
G03X950224Y516999I0J-1968D01*
G01X967940Y518967D02*
X952192D01*
G01X950224Y543770D02*
G03X952192Y541802I1968J0D01*
G01D02*
X967940D01*
G01X950224Y561487D02*
Y543770D01*
G01X952192Y563455D02*
G03X950224Y561487I0J-1968D01*
G01X967940Y563455D02*
X952192D01*
G01X937099Y687867D02*
X935656Y686423D01*
G01X937821Y690032D02*
X937099Y687867D01*
G01Y692197D02*
X937821Y690032D01*
G01X935656Y693641D02*
X937099Y692197D01*
G01X951914Y686423D02*
X952401Y685702D01*
G01X951914D02*
Y686423D01*
G01X952401Y685702D02*
X951914D01*
G01X943144Y686423D02*
X942657Y687145D01*
G01X944119Y685702D02*
X943144Y686423D01*
G01X945093Y685702D02*
X944119D01*
G01X946068Y686423D02*
X945093Y685702D01*
G01X946555Y687145D02*
X946068Y686423D01*
G01X947042Y688589D02*
X946555Y687145D01*
G01Y690032D02*
X947042Y688589D01*
G01X946068Y690754D02*
X946555Y690032D01*
G01X945093Y691476D02*
X946068Y690754D01*
G01X944119Y691476D02*
X945093D01*
G01X943144Y690754D02*
X944119Y691476D01*
G01X943631Y694363D02*
X943144Y690754D01*
G01X946555Y694363D02*
X943631D01*
G01X950472Y970112D02*
Y952789D01*
G01X959678Y35732D02*
X1066502D01*
G01X974186Y43671D02*
X973698Y42949D01*
G01X974186Y45115D02*
Y43671D01*
G01X973698Y45836D02*
X974186Y45115D01*
G01X972724Y46558D02*
X973698Y45836D01*
G01X971750Y46558D02*
X972724D01*
G01X970775Y45836D02*
X971750Y46558D01*
G01X970288Y45115D02*
X970775Y45836D01*
G01X970288Y37897D02*
X974186D01*
G01X970775Y40062D02*
X970288Y37897D01*
G01X971750Y41506D02*
X970775Y40062D01*
G01X973698Y42949D02*
X971750Y41506D01*
G01X978083Y37897D02*
X981981Y46558D01*
G01X978083D02*
X981981Y37897D01*
G01X975378Y156371D02*
G03X973410Y154402I1J-1969D01*
G01Y152434D02*
G03X975378Y150465I1968J-1D01*
G01X1081677Y156371D02*
X975378D01*
G01Y150465D02*
X1081677D01*
G01X973410Y154402D02*
Y152434D01*
G01X958208Y231190D02*
X956765Y229746D01*
G01X958930Y233355D02*
X958208Y231190D01*
G01Y235521D02*
X958930Y233355D01*
G01X956765Y236964D02*
X958208Y235521D01*
G01X966689Y236964D02*
X967177Y236242D01*
G01X965715Y237686D02*
X966689Y236964D01*
G01X964740D02*
X965715Y237686D01*
G01X964253Y236242D02*
X964740Y236964D01*
G01X963766Y234799D02*
X964253Y236242D01*
G01X963766Y231912D02*
Y234799D01*
G01X964253Y230468D02*
X963766Y231912D01*
G01X964740Y229746D02*
X964253Y230468D01*
G01X965715Y229025D02*
X964740Y229746D01*
G01X966689D02*
X965715Y229025D01*
G01X967177Y230468D02*
X966689Y229746D01*
G01X967664Y231912D02*
X967177Y230468D01*
G01Y233355D02*
X967664Y231912D01*
G01X965715Y234077D02*
X967177Y233355D01*
G01X964253D02*
X965715Y234077D01*
G01X963766Y231912D02*
X964253Y233355D01*
G01X973023Y229746D02*
X973510Y229025D01*
G01X973023D02*
Y229746D01*
G01X973510Y229025D02*
X973023D01*
G01X978511Y507895D02*
X978413Y507914D01*
G01X978583Y507844D02*
X978511Y507895D01*
G01X978609Y507774D02*
X978583Y507844D01*
G01X976982D02*
X976956Y507774D01*
G01X977054Y507895D02*
X976982Y507844D01*
G01X977153Y507914D02*
X977054Y507895D01*
G01X978609Y508343D02*
G03X978413Y508540I-197J0D01*
G01X977153D02*
G03X976956Y508343I0J-197D01*
G01X960696Y505581D02*
G03X961877Y504400I1181J0D01*
G01Y511880D02*
G03X960696Y510699I0J-1181D01*
G01X965381Y506959D02*
X961151Y504649D01*
G01X967074Y509321D02*
X969042Y510625D01*
G01X971287Y500660D02*
X967940Y497313D01*
G01X973964Y507156D02*
X972783Y505975D01*
G01X961877Y511880D02*
X970420D01*
G01X965381Y509321D02*
X967074D01*
G01X978413Y508540D02*
X977153D01*
G01X978413Y507914D02*
X977153D01*
G01X1010420Y507156D02*
X973964D01*
G01X967074Y506959D02*
X965381D01*
G01X1009239Y505975D02*
X972783D01*
G01X961877Y504400D02*
X970420D01*
G01X969042Y501250D02*
X1111523D01*
G01X1109279Y500660D02*
X971287D01*
G01X961151Y511632D02*
X965381Y509321D01*
G01X978609Y507156D02*
Y508343D01*
G01X978413Y507156D02*
Y508540D01*
G01X977153Y507156D02*
Y508540D01*
G01X976956Y508343D02*
Y507156D01*
G01X973964D02*
Y512668D01*
G01X972783Y505975D02*
Y513849D01*
G01X970420Y504400D02*
Y501250D01*
G01Y515030D02*
Y511880D01*
G01X969042Y501250D02*
Y515030D01*
G01Y505656D02*
X967074Y506959D01*
G01D02*
Y509321D01*
G01X965381Y506959D02*
Y509321D01*
G01X960696Y505581D02*
Y510699D01*
G01X970224Y536408D02*
G03X972192Y534439I1969J0D01*
G01D02*
X1078491D01*
G01X971287Y515621D02*
X1007626D01*
G01X969042Y515030D02*
X1007468D01*
G01X972783Y513849D02*
X1107783D01*
G01X973964Y512668D02*
X1106601D01*
G01X967940Y518967D02*
X971287Y515621D01*
G01X973964Y512668D02*
X972783Y513849D01*
G01X978511Y552383D02*
X978413Y552402D01*
G01X978583Y552332D02*
X978511Y552383D01*
G01X978609Y552262D02*
X978583Y552332D01*
G01X976982D02*
X976956Y552262D01*
G01X977054Y552383D02*
X976982Y552332D01*
G01X977153Y552402D02*
X977054Y552383D01*
G01X978609Y552831D02*
G03X978413Y553028I-197J0D01*
G01X977153D02*
G03X976956Y552831I0J-197D01*
G01X960696Y550069D02*
G03X961877Y548888I1181J0D01*
G01Y556369D02*
G03X960696Y555187I0J-1181D01*
G01X972192Y540345D02*
G03X970224Y538376I0J-1968D01*
G01X965381Y551447D02*
X961151Y549137D01*
G01X967074Y553810D02*
X969042Y555113D01*
G01X973964Y557156D02*
X1106601D01*
G01X961877Y556369D02*
X970420D01*
G01X965381Y553810D02*
X967074D01*
G01X978413Y553028D02*
X977153D01*
G01X978413Y552402D02*
X977153D01*
G01X1010420Y551644D02*
X973964D01*
G01X967074Y551447D02*
X965381D01*
G01X1009239Y550463D02*
X972783D01*
G01X961877Y548888D02*
X970420D01*
G01X969042Y545739D02*
X1111523D01*
G01X1109279Y545148D02*
X971287D01*
G01X1078491Y540345D02*
X972192D01*
G01X971287Y545148D02*
X967940Y541802D01*
G01X973964Y551644D02*
X972783Y550463D01*
G01X961151Y556120D02*
X965381Y553810D01*
G01X969042Y550144D02*
X967074Y551447D01*
G01X973964Y557156D02*
X972783Y558337D01*
G01X978609Y551644D02*
Y552831D01*
G01X978413Y551644D02*
Y553028D01*
G01X977153Y551644D02*
Y553028D01*
G01X976956Y552831D02*
Y551644D01*
G01X973964D02*
Y557156D01*
G01X972783Y550463D02*
Y558337D01*
G01X970420Y548888D02*
Y545739D01*
G01Y559518D02*
Y556369D01*
G01X970224Y538376D02*
Y536408D01*
G01X969042Y545739D02*
Y559518D01*
G01X967074Y551447D02*
Y553810D01*
G01X965381Y551447D02*
Y553810D01*
G01X960696Y550069D02*
Y555187D01*
G01X971287Y560109D02*
X1007626D01*
G01X969042Y559518D02*
X1007468D01*
G01X972783Y558337D02*
X1107783D01*
G01X967940Y563455D02*
X971287Y560109D01*
G01X968966Y686423D02*
X967992Y685702D01*
G01X969453Y687145D02*
X968966Y686423D01*
G01X969940Y688589D02*
X969453Y687145D01*
G01X969940Y691476D02*
Y688589D01*
G01X969453Y692919D02*
X969940Y691476D01*
G01X968966Y693641D02*
X969453Y692919D01*
G01X966530D02*
X967017Y693641D01*
G01X966043Y691476D02*
X966530Y692919D01*
G01X966043Y688589D02*
Y691476D01*
G01X966530Y687145D02*
X966043Y688589D01*
G01X967017Y686423D02*
X966530Y687145D01*
G01X967992Y685702D02*
X967017Y686423D01*
G01X958735D02*
X958248Y687145D01*
G01X959709Y685702D02*
X958735Y686423D01*
G01X960684Y685702D02*
X959709D01*
G01X961658Y686423D02*
X960684Y685702D01*
G01X962145Y687145D02*
X961658Y686423D01*
G01X962633Y688589D02*
X962145Y687145D01*
G01Y690032D02*
X962633Y688589D01*
G01X961658Y690754D02*
X962145Y690032D01*
G01X960684Y691476D02*
X961658Y690754D01*
G01X959709Y691476D02*
X960684D01*
G01X958735Y690754D02*
X959709Y691476D01*
G01X959222Y694363D02*
X958735Y690754D01*
G01X967992Y694363D02*
X968966Y693641D01*
G01X967017D02*
X967992Y694363D01*
G01X962145D02*
X959222D01*
G01X984651Y35731D02*
X991869Y48723D01*
G01X997427Y40062D02*
X1001812D01*
G01X1000837Y46558D02*
X997427Y40062D01*
G01X1000837Y37897D02*
Y46558D01*
G01X984651Y40062D02*
X983929Y42228D01*
G01X986095Y38619D02*
X984651Y40062D01*
G01X988261Y37897D02*
X986095Y38619D01*
G01X990426D02*
X988261Y37897D01*
G01X991869Y40062D02*
X990426Y38619D01*
G01X992591Y42228D02*
X991869Y40062D01*
G01Y44393D02*
X992591Y42228D01*
G01X990426Y45836D02*
X991869Y44393D01*
G01X988261Y46558D02*
X990426Y45836D01*
G01X986095D02*
X988261Y46558D01*
G01X984651Y44393D02*
X986095Y45836D01*
G01X983929Y42228D02*
X984651Y44393D01*
G01X982280Y229746D02*
X981305Y229025D01*
G01X982767Y230468D02*
X982280Y229746D01*
G01X983254Y231912D02*
X982767Y230468D01*
G01X983254Y234799D02*
Y231912D01*
G01X982767Y236242D02*
X983254Y234799D01*
G01X982280Y236964D02*
X982767Y236242D01*
G01X981305Y237686D02*
X982280Y236964D01*
G01X980331D02*
X981305Y237686D01*
G01X979844Y236242D02*
X980331Y236964D01*
G01X979357Y234799D02*
X979844Y236242D01*
G01X979357Y231912D02*
Y234799D01*
G01X979844Y230468D02*
X979357Y231912D01*
G01X980331Y229746D02*
X979844Y230468D01*
G01X981305Y229025D02*
X980331Y229746D01*
G01X990075D02*
X989101Y229025D01*
G01X990563Y230468D02*
X990075Y229746D01*
G01X991050Y231912D02*
X990563Y230468D01*
G01X991050Y234799D02*
Y231912D01*
G01X990563Y236242D02*
X991050Y234799D01*
G01X990075Y236964D02*
X990563Y236242D01*
G01X989101Y237686D02*
X990075Y236964D01*
G01X988126D02*
X989101Y237686D01*
G01X987639Y236242D02*
X988126Y236964D01*
G01X987152Y234799D02*
X987639Y236242D01*
G01X987152Y231912D02*
Y234799D01*
G01X987639Y230468D02*
X987152Y231912D01*
G01X988126Y229746D02*
X987639Y230468D01*
G01X989101Y229025D02*
X988126Y229746D01*
G01X1095671Y411075D02*
X988847D01*
G01X999457Y415405D02*
X1003842D01*
G01X1002868Y421901D02*
X999457Y415405D01*
G01X983511Y507895D02*
X983413Y507914D01*
G01X983583Y507844D02*
X983511Y507895D01*
G01X983609Y507774D02*
X983583Y507844D01*
G01X988511Y507895D02*
X988413Y507914D01*
G01X988583Y507844D02*
X988511Y507895D01*
G01X988609Y507774D02*
X988583Y507844D01*
G01X993511Y507895D02*
X993413Y507914D01*
G01X993583Y507844D02*
X993511Y507895D01*
G01X993609Y507774D02*
X993583Y507844D01*
G01X998511Y507895D02*
X998413Y507914D01*
G01X998583Y507844D02*
X998511Y507895D01*
G01X998609Y507774D02*
X998583Y507844D01*
G01X1001982D02*
X1001956Y507774D01*
G01X1002054Y507895D02*
X1001982Y507844D01*
G01X996982D02*
X996956Y507774D01*
G01X997054Y507895D02*
X996982Y507844D01*
G01X997153Y507914D02*
X997054Y507895D01*
G01X991982Y507844D02*
X991956Y507774D01*
G01X992054Y507895D02*
X991982Y507844D01*
G01X992153Y507914D02*
X992054Y507895D01*
G01X986982Y507844D02*
X986956Y507774D01*
G01X987054Y507895D02*
X986982Y507844D01*
G01X987153Y507914D02*
X987054Y507895D01*
G01X981982Y507844D02*
X981956Y507774D01*
G01X982054Y507895D02*
X981982Y507844D01*
G01X982153Y507914D02*
X982054Y507895D01*
G01X983609Y508343D02*
G03X983413Y508540I-197J0D01*
G01X982153D02*
G03X981956Y508343I0J-197D01*
G01X988609D02*
G03X988413Y508540I-197J0D01*
G01X987153D02*
G03X986956Y508343I0J-197D01*
G01X993609D02*
G03X993413Y508540I-197J0D01*
G01X992153D02*
G03X991956Y508343I0J-197D01*
G01X998609D02*
G03X998413Y508540I-197J0D01*
G01X997153D02*
G03X996956Y508343I0J-197D01*
G01X983413Y508540D02*
X982153D01*
G01X988413D02*
X987153D01*
G01X993413D02*
X992153D01*
G01X998413D02*
X997153D01*
G01X983413Y507914D02*
X982153D01*
G01X988413D02*
X987153D01*
G01X993413D02*
X992153D01*
G01X998413D02*
X997153D01*
G01X998609Y507156D02*
Y508343D01*
G01X998413Y507156D02*
Y508540D01*
G01X997153Y507156D02*
Y508540D01*
G01X996956Y508343D02*
Y507156D01*
G01X993609D02*
Y508343D01*
G01X993413Y507156D02*
Y508540D01*
G01X992153Y507156D02*
Y508540D01*
G01X991956Y508343D02*
Y507156D01*
G01X988609D02*
Y508343D01*
G01X988413Y507156D02*
Y508540D01*
G01X987153Y507156D02*
Y508540D01*
G01X986956Y508343D02*
Y507156D01*
G01X983609D02*
Y508343D01*
G01X983413Y507156D02*
Y508540D01*
G01X982153Y507156D02*
Y508540D01*
G01X981956Y508343D02*
Y507156D01*
G01X983511Y552383D02*
X983413Y552402D01*
G01X983583Y552332D02*
X983511Y552383D01*
G01X983609Y552262D02*
X983583Y552332D01*
G01X988511Y552383D02*
X988413Y552402D01*
G01X988583Y552332D02*
X988511Y552383D01*
G01X988609Y552262D02*
X988583Y552332D01*
G01X993511Y552383D02*
X993413Y552402D01*
G01X993583Y552332D02*
X993511Y552383D01*
G01X993609Y552262D02*
X993583Y552332D01*
G01X998511Y552383D02*
X998413Y552402D01*
G01X998583Y552332D02*
X998511Y552383D01*
G01X998609Y552262D02*
X998583Y552332D01*
G01X1001982D02*
X1001956Y552262D01*
G01X1002054Y552383D02*
X1001982Y552332D01*
G01X996982D02*
X996956Y552262D01*
G01X997054Y552383D02*
X996982Y552332D01*
G01X997153Y552402D02*
X997054Y552383D01*
G01X991982Y552332D02*
X991956Y552262D01*
G01X992054Y552383D02*
X991982Y552332D01*
G01X992153Y552402D02*
X992054Y552383D01*
G01X986982Y552332D02*
X986956Y552262D01*
G01X987054Y552383D02*
X986982Y552332D01*
G01X987153Y552402D02*
X987054Y552383D01*
G01X981982Y552332D02*
X981956Y552262D01*
G01X982054Y552383D02*
X981982Y552332D01*
G01X982153Y552402D02*
X982054Y552383D01*
G01X983609Y552831D02*
G03X983413Y553028I-197J0D01*
G01X982153D02*
G03X981956Y552831I0J-197D01*
G01X988609D02*
G03X988413Y553028I-197J0D01*
G01X987153D02*
G03X986956Y552831I0J-197D01*
G01X993609D02*
G03X993413Y553028I-197J0D01*
G01X992153D02*
G03X991956Y552831I0J-197D01*
G01X998609D02*
G03X998413Y553028I-197J0D01*
G01X997153D02*
G03X996956Y552831I0J-197D01*
G01X983413Y553028D02*
X982153D01*
G01X988413D02*
X987153D01*
G01X993413D02*
X992153D01*
G01X998413D02*
X997153D01*
G01X983413Y552402D02*
X982153D01*
G01X988413D02*
X987153D01*
G01X993413D02*
X992153D01*
G01X998413D02*
X997153D01*
G01X998609Y551644D02*
Y552831D01*
G01X998413Y551644D02*
Y553028D01*
G01X997153Y551644D02*
Y553028D01*
G01X996956Y552831D02*
Y551644D01*
G01X993609D02*
Y552831D01*
G01X993413Y551644D02*
Y553028D01*
G01X992153Y551644D02*
Y553028D01*
G01X991956Y552831D02*
Y551644D01*
G01X988609D02*
Y552831D01*
G01X988413Y551644D02*
Y553028D01*
G01X987153Y551644D02*
Y553028D01*
G01X986956Y552831D02*
Y551644D01*
G01X983609D02*
Y552831D01*
G01X983413Y551644D02*
Y553028D01*
G01X982153Y551644D02*
Y553028D01*
G01X981956Y552831D02*
Y551644D01*
G01X984070Y690032D02*
X981633D01*
G01X985044Y690754D02*
X984070Y690032D01*
G01X985531Y691476D02*
X985044Y690754D01*
G01X985531Y692919D02*
Y691476D01*
G01X985044Y693641D02*
X985531Y692919D01*
G01X981633Y685702D02*
Y694363D01*
G01X991377D02*
X993814Y685702D01*
G01X988942D02*
X991377Y694363D01*
G01X997224Y685702D02*
Y694363D01*
G01X999173Y685702D02*
X997224D01*
G01X1000147Y686423D02*
X999173Y685702D01*
G01X1001122Y687867D02*
X1000147Y686423D01*
G01X1001609Y690032D02*
X1001122Y687867D01*
G01Y692197D02*
X1001609Y690032D01*
G01X1000147Y693641D02*
X1001122Y692197D01*
G01X989916Y688589D02*
X992839D01*
G01X984070Y694363D02*
X985044Y693641D01*
G01X981633Y694363D02*
X984070D01*
G01X999173D02*
X1000147Y693641D01*
G01X997224Y694363D02*
X999173D01*
G01X1023736Y38619D02*
X1022762Y37897D01*
G01X1024223Y39340D02*
X1023736Y38619D01*
G01X1024711Y40784D02*
X1024223Y39340D01*
G01Y45115D02*
X1024711Y43671D01*
G01X1023736Y45836D02*
X1024223Y45115D01*
G01X1022762Y46558D02*
X1023736Y45836D01*
G01X1021787D02*
X1022762Y46558D01*
G01X1021300Y45115D02*
X1021787Y45836D01*
G01X1020813Y43671D02*
X1021300Y45115D01*
G01X1020813Y40784D02*
Y43671D01*
G01X1021300Y39340D02*
X1020813Y40784D01*
G01X1021787Y38619D02*
X1021300Y39340D01*
G01X1022762Y37897D02*
X1021787Y38619D01*
G01X1006684D02*
X1007171Y37897D01*
G01X1006684D02*
Y38619D01*
G01X1007171Y37897D02*
X1006684D01*
G01X1013018D02*
X1016915D01*
G01X1013505Y40062D02*
X1013018Y37897D01*
G01X1014479Y41506D02*
X1013505Y40062D01*
G01X1015453Y42228D02*
X1014479Y41506D01*
G01X1016428Y42949D02*
X1015453Y42228D01*
G01X1016915Y43671D02*
X1016428Y42949D01*
G01X1016915Y45115D02*
Y43671D01*
G01X1016428Y45836D02*
X1016915Y45115D01*
G01X1015453Y46558D02*
X1016428Y45836D01*
G01X1014479Y46558D02*
X1015453D01*
G01X1013505Y45836D02*
X1014479Y46558D01*
G01X1013018Y45115D02*
X1013505Y45836D01*
G01X1012974Y233355D02*
X1010538D01*
G01X1013948Y234077D02*
X1012974Y233355D01*
G01X1014435Y234799D02*
X1013948Y234077D01*
G01X1014435Y236242D02*
Y234799D01*
G01X1013948Y236964D02*
X1014435Y236242D01*
G01X1012974Y237686D02*
X1013948Y236964D01*
G01X1010538Y237686D02*
X1012974D01*
G01X1010538Y229025D02*
Y237686D01*
G01X1020282D02*
X1022718Y229025D01*
G01X1017846D02*
X1020282Y237686D01*
G01X1018820Y231912D02*
X1021744D01*
G01X1013821Y415405D02*
X1013099Y417571D01*
G01X1015264Y413962D02*
X1013821Y415405D01*
G01X1017429Y413240D02*
X1015264Y413962D01*
G01X1019595D02*
X1017429Y413240D01*
G01X1021038Y415405D02*
X1019595Y413962D01*
G01X1021760Y417571D02*
X1021038Y415405D01*
G01Y419736D02*
X1021760Y417571D01*
G01X1019595Y421179D02*
X1021038Y419736D01*
G01X1017429Y421901D02*
X1019595Y421179D01*
G01X1015264D02*
X1017429Y421901D01*
G01X1013821Y419736D02*
X1015264Y421179D01*
G01X1013099Y417571D02*
X1013821Y419736D01*
G01X1002868Y413240D02*
Y421901D01*
G01X1007252D02*
X1011150Y413240D01*
G01X1013821Y411075D02*
X1021038Y424067D01*
G01X1007252Y413240D02*
X1011150Y421901D01*
G01X1003511Y507895D02*
X1003413Y507914D01*
G01X1003583Y507844D02*
X1003511Y507895D01*
G01X1003609Y507774D02*
X1003583Y507844D01*
G01X1008511Y507895D02*
X1008413Y507914D01*
G01X1008583Y507844D02*
X1008511Y507895D01*
G01X1008609Y507774D02*
X1008583Y507844D01*
G01X1010302Y512103D02*
X1010230Y512153D01*
G01X1013452Y512103D02*
X1013380Y512153D01*
G01X1016601Y512103D02*
X1016529Y512153D01*
G01X1019751Y512103D02*
X1019679Y512153D01*
G01X1022901Y512103D02*
X1022829Y512153D01*
G01X1011437D02*
X1011365Y512103D01*
G01X1014587Y512153D02*
X1014515Y512103D01*
G01X1017737Y512153D02*
X1017664Y512103D01*
G01X1020886Y512153D02*
X1020814Y512103D01*
G01X1024036Y512153D02*
X1023964Y512103D01*
G01X1006982Y507844D02*
X1006956Y507774D01*
G01X1007054Y507895D02*
X1006982Y507844D01*
G01X1007153Y507914D02*
X1007054Y507895D01*
G01X1002153Y507914D02*
X1002054Y507895D01*
G01X1022802Y511625D02*
G03X1022999Y511428I197J0D01*
G01X1023865D02*
G03X1024062Y511625I0J197D01*
G01X1019653D02*
G03X1019850Y511428I197J0D01*
G01X1020716D02*
G03X1020913Y511625I0J197D01*
G01X1016503D02*
G03X1016700Y511428I197J0D01*
G01X1017566D02*
G03X1017763Y511625I0J197D01*
G01X1013353D02*
G03X1013550Y511428I197J0D01*
G01X1014416D02*
G03X1014613Y511625I0J197D01*
G01X1010204D02*
G03X1010401Y511428I197J0D01*
G01X1011267D02*
G03X1011464Y511625I0J197D01*
G01X1003609Y508343D02*
G03X1003413Y508540I-197J0D01*
G01X1002153D02*
G03X1001956Y508343I0J-197D01*
G01X1008609D02*
G03X1008413Y508540I-197J0D01*
G01X1007153D02*
G03X1006956Y508343I0J-197D01*
G01X1010420Y503219D02*
X1009239Y502038D01*
G01X1010420Y507156D02*
X1009239Y505975D01*
G01X1022999Y511428D02*
X1023865D01*
G01X1019850D02*
X1020716D01*
G01X1016700D02*
X1017566D01*
G01X1013550D02*
X1014416D01*
G01X1010401D02*
X1011267D01*
G01X1003413Y508540D02*
X1002153D01*
G01X1008413D02*
X1007153D01*
G01X1003413Y507914D02*
X1002153D01*
G01X1008413D02*
X1007153D01*
G01X1030145Y503219D02*
X1010420D01*
G01X1031326Y502038D02*
X1009239D01*
G01X1024062Y511625D02*
Y512668D01*
G01X1023865Y511428D02*
Y512471D01*
G01X1022999D02*
Y511428D01*
G01X1022802Y512668D02*
Y511625D01*
G01X1020913D02*
Y512668D01*
G01X1020716Y511428D02*
Y512471D01*
G01X1019850D02*
Y511428D01*
G01X1019653Y512668D02*
Y511625D01*
G01X1017763D02*
Y512668D01*
G01X1017566Y511428D02*
Y512471D01*
G01X1016700D02*
Y511428D01*
G01X1016503Y512668D02*
Y511625D01*
G01X1014613D02*
Y512668D01*
G01X1014416Y511428D02*
Y512471D01*
G01X1013550D02*
Y511428D01*
G01X1013353Y512668D02*
Y511625D01*
G01X1011464D02*
Y512668D01*
G01X1011267Y511428D02*
Y512471D01*
G01X1010420Y503219D02*
Y507156D01*
G01X1010401Y512471D02*
Y511428D01*
G01X1010204Y512668D02*
Y511625D01*
G01X1009239Y502038D02*
Y505975D01*
G01X1008609Y507156D02*
Y508343D01*
G01X1008413Y507156D02*
Y508540D01*
G01X1007153Y507156D02*
Y508540D01*
G01X1006956Y508343D02*
Y507156D01*
G01X1003609D02*
Y508343D01*
G01X1003413Y507156D02*
Y508540D01*
G01X1002153Y507156D02*
Y508540D01*
G01X1001956Y508343D02*
Y507156D01*
G01X1010230Y512153D02*
X1010204Y512222D01*
G01X1010401Y512084D02*
X1010302Y512103D01*
G01X1013380Y512153D02*
X1013353Y512222D01*
G01X1013550Y512084D02*
X1013452Y512103D01*
G01X1016529Y512153D02*
X1016503Y512222D01*
G01X1016700Y512084D02*
X1016601Y512103D01*
G01X1019679Y512153D02*
X1019653Y512222D01*
G01X1019850Y512084D02*
X1019751Y512103D01*
G01X1022829Y512153D02*
X1022802Y512222D01*
G01X1022999Y512084D02*
X1022901Y512103D01*
G01X1011365D02*
X1011267Y512084D01*
G01X1011464Y512222D02*
X1011437Y512153D01*
G01X1014515Y512103D02*
X1014416Y512084D01*
G01X1014613Y512222D02*
X1014587Y512153D01*
G01X1017664Y512103D02*
X1017566Y512084D01*
G01X1017763Y512222D02*
X1017737Y512153D01*
G01X1020814Y512103D02*
X1020716Y512084D01*
G01X1020913Y512222D02*
X1020886Y512153D01*
G01X1023964Y512103D02*
X1023865Y512084D01*
G01X1024062Y512222D02*
X1024036Y512153D01*
G01X1032042Y518967D02*
X1008522D01*
G01X1032412Y517589D02*
X1008153D01*
G01X1023865Y512471D02*
X1024062D01*
G01X1022802D02*
X1022999D01*
G01X1020716D02*
X1020913D01*
G01X1019653D02*
X1019850D01*
G01X1017566D02*
X1017763D01*
G01X1016503D02*
X1016700D01*
G01X1014416D02*
X1014613D01*
G01X1013353D02*
X1013550D01*
G01X1011267D02*
X1011464D01*
G01X1010204D02*
X1010401D01*
G01X1022999Y512084D02*
X1023865D01*
G01X1019850D02*
X1020716D01*
G01X1016700D02*
X1017566D01*
G01X1013550D02*
X1014416D01*
G01X1010401D02*
X1011267D01*
G01X1007468Y515030D02*
X1008522Y518967D01*
G01X1003511Y552383D02*
X1003413Y552402D01*
G01X1003583Y552332D02*
X1003511Y552383D01*
G01X1003609Y552262D02*
X1003583Y552332D01*
G01X1008511Y552383D02*
X1008413Y552402D01*
G01X1008583Y552332D02*
X1008511Y552383D01*
G01X1008609Y552262D02*
X1008583Y552332D01*
G01X1011365Y556591D02*
X1011267Y556573D01*
G01X1011437Y556641D02*
X1011365Y556591D01*
G01X1011464Y556710D02*
X1011437Y556641D01*
G01X1014515Y556591D02*
X1014416Y556573D01*
G01X1014587Y556641D02*
X1014515Y556591D01*
G01X1014613Y556710D02*
X1014587Y556641D01*
G01X1017664Y556591D02*
X1017566Y556573D01*
G01X1017737Y556641D02*
X1017664Y556591D01*
G01X1017763Y556710D02*
X1017737Y556641D01*
G01X1020814Y556591D02*
X1020716Y556573D01*
G01X1020886Y556641D02*
X1020814Y556591D01*
G01X1020913Y556710D02*
X1020886Y556641D01*
G01X1023964Y556591D02*
X1023865Y556573D01*
G01X1024036Y556641D02*
X1023964Y556591D01*
G01X1024062Y556710D02*
X1024036Y556641D01*
G01X1010230D02*
X1010204Y556710D01*
G01X1010302Y556591D02*
X1010230Y556641D01*
G01X1010401Y556573D02*
X1010302Y556591D01*
G01X1013380Y556641D02*
X1013353Y556710D01*
G01X1013452Y556591D02*
X1013380Y556641D01*
G01X1013550Y556573D02*
X1013452Y556591D01*
G01X1016529Y556641D02*
X1016503Y556710D01*
G01X1016601Y556591D02*
X1016529Y556641D01*
G01X1016700Y556573D02*
X1016601Y556591D01*
G01X1019679Y556641D02*
X1019653Y556710D01*
G01X1019751Y556591D02*
X1019679Y556641D01*
G01X1019850Y556573D02*
X1019751Y556591D01*
G01X1022829Y556641D02*
X1022802Y556710D01*
G01X1022901Y556591D02*
X1022829Y556641D01*
G01X1022999Y556573D02*
X1022901Y556591D01*
G01X1006982Y552332D02*
X1006956Y552262D01*
G01X1007054Y552383D02*
X1006982Y552332D01*
G01X1007153Y552402D02*
X1007054Y552383D01*
G01X1002153Y552402D02*
X1002054Y552383D01*
G01X1022802Y556113D02*
G03X1022999Y555916I197J0D01*
G01X1023865D02*
G03X1024062Y556113I0J197D01*
G01X1019653D02*
G03X1019850Y555916I197J0D01*
G01X1020716D02*
G03X1020913Y556113I0J197D01*
G01X1016503D02*
G03X1016700Y555916I197J0D01*
G01X1017566D02*
G03X1017763Y556113I0J197D01*
G01X1013353D02*
G03X1013550Y555916I197J0D01*
G01X1014416D02*
G03X1014613Y556113I0J197D01*
G01X1010204D02*
G03X1010401Y555916I197J0D01*
G01X1011267D02*
G03X1011464Y556113I0J197D01*
G01X1003609Y552831D02*
G03X1003413Y553028I-197J0D01*
G01X1002153D02*
G03X1001956Y552831I0J-197D01*
G01X1008609D02*
G03X1008413Y553028I-197J0D01*
G01X1007153D02*
G03X1006956Y552831I0J-197D01*
G01X1023865Y556960D02*
X1024062D01*
G01X1022802D02*
X1022999D01*
G01X1020716D02*
X1020913D01*
G01X1019653D02*
X1019850D01*
G01X1017566D02*
X1017763D01*
G01X1016503D02*
X1016700D01*
G01X1014416D02*
X1014613D01*
G01X1013353D02*
X1013550D01*
G01X1011267D02*
X1011464D01*
G01X1010204D02*
X1010401D01*
G01X1022999Y556573D02*
X1023865D01*
G01X1019850D02*
X1020716D01*
G01X1016700D02*
X1017566D01*
G01X1013550D02*
X1014416D01*
G01X1010401D02*
X1011267D01*
G01X1022999Y555916D02*
X1023865D01*
G01X1019850D02*
X1020716D01*
G01X1016700D02*
X1017566D01*
G01X1013550D02*
X1014416D01*
G01X1010401D02*
X1011267D01*
G01X1003413Y553028D02*
X1002153D01*
G01X1008413D02*
X1007153D01*
G01X1003413Y552402D02*
X1002153D01*
G01X1008413D02*
X1007153D01*
G01X1030145Y547707D02*
X1010420D01*
G01X1031326Y546526D02*
X1009239D01*
G01X1010420Y547707D02*
X1009239Y546526D01*
G01X1010420Y551644D02*
X1009239Y550463D01*
G01X1024062Y556113D02*
Y557156D01*
G01X1023865Y555916D02*
Y556960D01*
G01X1022999D02*
Y555916D01*
G01X1022802Y557156D02*
Y556113D01*
G01X1020913D02*
Y557156D01*
G01X1020716Y555916D02*
Y556960D01*
G01X1019850D02*
Y555916D01*
G01X1019653Y557156D02*
Y556113D01*
G01X1017763D02*
Y557156D01*
G01X1017566Y555916D02*
Y556960D01*
G01X1016700D02*
Y555916D01*
G01X1016503Y557156D02*
Y556113D01*
G01X1014613D02*
Y557156D01*
G01X1014416Y555916D02*
Y556960D01*
G01X1013550D02*
Y555916D01*
G01X1013353Y557156D02*
Y556113D01*
G01X1011464D02*
Y557156D01*
G01X1011267Y555916D02*
Y556960D01*
G01X1010420Y547707D02*
Y551644D01*
G01X1010401Y556960D02*
Y555916D01*
G01X1010204Y557156D02*
Y556113D01*
G01X1009239Y546526D02*
Y550463D01*
G01X1008609Y551644D02*
Y552831D01*
G01X1008413Y551644D02*
Y553028D01*
G01X1007153Y551644D02*
Y553028D01*
G01X1006956Y552831D02*
Y551644D01*
G01X1003609D02*
Y552831D01*
G01X1003413Y551644D02*
Y553028D01*
G01X1002153Y551644D02*
Y553028D01*
G01X1001956Y552831D02*
Y551644D01*
G01X1018700Y575242D02*
X1015542Y573630D01*
G01X1013964D02*
X1018249Y575933D01*
G01X1021858Y578928D02*
X1023211D01*
G01X1010806D02*
X1012159D01*
G01X1003137D02*
X1004490D01*
G01Y574551D02*
X1010806D01*
G01Y573169D02*
X1004490D01*
G01Y568101D02*
X1003137D01*
G01X1012159D02*
X1010806D01*
G01X1023211D02*
X1021858D01*
G01X1032042Y563455D02*
X1008522D01*
G01X1032412Y562077D02*
X1008153D01*
G01X1021858Y577085D02*
X1020505Y575473D01*
G01Y577315D02*
X1021858Y578928D01*
G01X1018249Y571326D02*
X1013964Y573630D01*
G01X1015542D02*
X1018700Y572017D01*
G01D02*
X1018249Y571326D01*
G01Y575933D02*
X1018700Y575242D01*
G01X1007468Y559518D02*
X1008522Y563455D01*
G01X1023211Y578928D02*
Y568101D01*
G01X1021858D02*
Y577085D01*
G01X1020505Y575473D02*
Y577315D01*
G01X1012159Y578928D02*
Y568101D01*
G01X1010806Y574551D02*
Y578928D01*
G01Y568101D02*
Y573169D01*
G01X1004490D02*
Y568101D01*
G01Y578928D02*
Y574551D01*
G01X1003137Y568101D02*
Y578928D01*
G01X1017200Y687867D02*
X1016225Y686423D01*
G01X1017687Y690032D02*
X1017200Y687867D01*
G01Y692197D02*
X1017687Y690032D01*
G01X1016712Y692919D02*
X1017200Y692197D01*
G01X1016225Y693641D02*
X1016712Y692919D01*
G01X1012327Y692197D02*
X1013302Y693641D01*
G01X1024507Y685702D02*
Y694363D01*
G01X1020610D02*
X1024507Y685702D01*
G01X1020610D02*
Y694363D01*
G01X1011840Y690032D02*
X1012327Y692197D01*
G01Y687867D02*
X1011840Y690032D01*
G01X1012814Y687145D02*
X1012327Y687867D01*
G01X1013302Y686423D02*
X1012814Y687145D01*
G01X1014276Y685702D02*
X1013302Y686423D01*
G01X1015251Y685702D02*
X1014276D01*
G01X1016225Y686423D02*
X1015251Y685702D01*
G01Y694363D02*
X1016225Y693641D01*
G01X1014276Y694363D02*
X1015251D01*
G01X1013302Y693641D02*
X1014276Y694363D01*
G01X1024711Y43671D02*
Y40784D01*
G01X1038839Y42228D02*
X1036403D01*
G01X1039814Y42949D02*
X1038839Y42228D01*
G01X1040301Y43671D02*
X1039814Y42949D01*
G01X1040301Y45115D02*
Y43671D01*
G01X1039814Y45836D02*
X1040301Y45115D01*
G01X1038839Y46558D02*
X1039814Y45836D01*
G01X1036403Y46558D02*
X1038839D01*
G01X1036403Y37897D02*
Y46558D01*
G01X1046148D02*
Y37897D01*
G01X1043711Y46558D02*
X1048583D01*
G01X1045221Y190122D02*
X1044305Y189810D01*
G01X1040339Y190122D02*
X1039424Y189810D01*
G01X1045221Y188564D02*
X1045831Y188875D01*
G01X1040339Y188564D02*
X1040949Y188875D01*
G01X1041559Y190122D02*
X1040339D01*
G01X1046441D02*
X1045221D01*
G01X1045831Y188875D02*
X1046441D01*
G01X1040949D02*
X1041864D01*
G01X1043085Y180150D02*
X1044611D01*
G01X1038203D02*
X1039729D01*
G01X1044916Y188252D02*
X1045221Y188564D01*
G01X1044305Y189810D02*
X1043390Y188875D01*
G01X1040034Y188252D02*
X1040339Y188564D01*
G01X1039424Y189810D02*
X1038813Y189187D01*
G01X1047357Y189810D02*
X1046441Y190122D01*
G01Y188875D02*
X1047357Y188564D01*
G01X1042475Y189810D02*
X1041559Y190122D01*
G01X1044611Y187629D02*
X1044916Y188252D01*
G01X1039729Y187629D02*
X1040034Y188252D01*
G01X1041864Y188875D02*
X1042475Y188564D01*
G01X1038813Y189187D02*
X1038203Y187629D01*
G01X1042780Y188252D02*
X1043085Y187629D01*
G01X1047967Y189187D02*
X1047357Y189810D01*
G01Y188564D02*
X1047967Y187941D01*
G01X1043390Y188875D02*
X1042475Y189810D01*
G01Y188564D02*
X1042780Y188252D01*
G01X1044611Y180150D02*
Y187629D01*
G01X1043085D02*
Y180150D01*
G01X1039729D02*
Y187629D01*
G01X1038203D02*
Y180150D01*
G01X1030026Y231190D02*
X1029051Y229746D01*
G01X1030513Y233355D02*
X1030026Y231190D01*
G01Y235521D02*
X1030513Y233355D01*
G01X1029051Y236964D02*
X1030026Y235521D01*
G01X1040744Y233355D02*
X1041232Y235521D01*
G01Y231190D02*
X1040744Y233355D01*
G01X1042206Y229746D02*
X1041232Y231190D01*
G01X1043181Y229025D02*
X1042206Y229746D01*
G01X1044155Y229025D02*
X1043181D01*
G01X1045129Y229746D02*
X1044155Y229025D01*
G01X1046104Y231190D02*
X1045129Y229746D01*
G01X1044155Y237686D02*
X1045129Y236964D01*
G01X1043181Y237686D02*
X1044155D01*
G01X1042206Y236964D02*
X1043181Y237686D01*
G01X1041232Y235521D02*
X1042206Y236964D01*
G01X1046591Y233355D02*
X1046104Y231190D01*
G01Y235521D02*
X1046591Y233355D01*
G01X1045129Y236964D02*
X1046104Y235521D01*
G01X1026128Y229025D02*
Y237686D01*
G01X1028077Y229025D02*
X1026128D01*
G01X1029051Y229746D02*
X1028077Y229025D01*
G01Y237686D02*
X1029051Y236964D01*
G01X1026128Y237686D02*
X1028077D01*
G01X1030007Y417571D02*
X1030981Y416127D01*
G01X1029032Y418292D02*
X1030007Y417571D01*
G01Y419014D02*
X1029032Y418292D01*
G01X1030494Y419736D02*
X1030007Y419014D01*
G01X1030494Y420458D02*
Y419736D01*
G01X1030007Y421179D02*
X1030494Y420458D01*
G01X1029032Y421901D02*
X1030007Y421179D01*
G01X1027083D02*
X1028058Y421901D01*
G01X1027083Y413962D02*
X1026596Y414683D01*
G01X1028058Y413240D02*
X1027083Y413962D01*
G01X1029032Y413240D02*
X1028058D01*
G01X1030007Y413962D02*
X1029032Y413240D01*
G01X1045597Y417571D02*
X1046572Y416127D01*
G01X1044623Y418292D02*
X1045597Y417571D01*
G01Y419014D02*
X1044623Y418292D01*
G01X1046085Y419736D02*
X1045597Y419014D01*
G01X1046085Y420458D02*
Y419736D01*
G01X1045597Y421179D02*
X1046085Y420458D01*
G01X1044623Y421901D02*
X1045597Y421179D01*
G01X1042674D02*
X1043648Y421901D01*
G01X1042674Y413962D02*
X1042187Y414683D01*
G01X1043648Y413240D02*
X1042674Y413962D01*
G01X1044623Y413240D02*
X1043648D01*
G01X1045597Y413962D02*
X1044623Y413240D01*
G01X1046572Y415405D02*
X1045597Y413962D01*
G01X1030981Y415405D02*
X1030007Y413962D01*
G01X1030981Y416127D02*
Y415405D01*
G01X1035853Y413962D02*
X1036340Y413240D01*
G01X1035853D02*
Y413962D01*
G01X1036340Y413240D02*
X1035853D01*
G01X1043648Y418292D02*
X1044623D01*
G01X1028058D02*
X1029032D01*
G01X1046572Y416127D02*
Y415405D01*
G01X1028058Y421901D02*
X1029032D01*
G01X1043648D02*
X1044623D01*
G01X1033511Y507895D02*
X1033413Y507914D01*
G01X1033583Y507844D02*
X1033511Y507895D01*
G01X1033609Y507774D02*
X1033583Y507844D01*
G01X1038511Y507895D02*
X1038413Y507914D01*
G01X1038583Y507844D02*
X1038511Y507895D01*
G01X1038609Y507774D02*
X1038583Y507844D01*
G01X1043511Y507895D02*
X1043413Y507914D01*
G01X1043583Y507844D02*
X1043511Y507895D01*
G01X1043609Y507774D02*
X1043583Y507844D01*
G01X1026050Y512103D02*
X1025978Y512153D01*
G01X1029200Y512103D02*
X1029128Y512153D01*
G01X1027185D02*
X1027113Y512103D01*
G01X1030335Y512153D02*
X1030263Y512103D01*
G01X1046982Y507844D02*
X1046956Y507774D01*
G01X1047054Y507895D02*
X1046982Y507844D01*
G01X1047153Y507914D02*
X1047054Y507895D01*
G01X1041982Y507844D02*
X1041956Y507774D01*
G01X1042054Y507895D02*
X1041982Y507844D01*
G01X1042153Y507914D02*
X1042054Y507895D01*
G01X1036982Y507844D02*
X1036956Y507774D01*
G01X1037054Y507895D02*
X1036982Y507844D01*
G01X1037153Y507914D02*
X1037054Y507895D01*
G01X1031982Y507844D02*
X1031956Y507774D01*
G01X1032054Y507895D02*
X1031982Y507844D01*
G01X1032153Y507914D02*
X1032054Y507895D01*
G01X1029101Y511625D02*
G03X1029298Y511428I197J0D01*
G01X1030164D02*
G03X1030361Y511625I0J197D01*
G01X1027015Y511428D02*
G03X1027212Y511625I0J197D01*
G01X1047153Y508540D02*
G03X1046956Y508343I0J-197D01*
G01X1033609D02*
G03X1033413Y508540I-197J0D01*
G01X1032153D02*
G03X1031956Y508343I0J-197D01*
G01X1038609D02*
G03X1038413Y508540I-197J0D01*
G01X1037153D02*
G03X1036956Y508343I0J-197D01*
G01X1043609D02*
G03X1043413Y508540I-197J0D01*
G01X1042153D02*
G03X1041956Y508343I0J-197D01*
G01X1025952Y511625D02*
G03X1026149Y511428I197J0D01*
G01X1029298D02*
X1030164D01*
G01X1026149D02*
X1027015D01*
G01X1033413Y508540D02*
X1032153D01*
G01X1038413D02*
X1037153D01*
G01X1043413D02*
X1042153D01*
G01X1048413D02*
X1047153D01*
G01X1033413Y507914D02*
X1032153D01*
G01X1038413D02*
X1037153D01*
G01X1043413D02*
X1042153D01*
G01X1048413D02*
X1047153D01*
G01X1106601Y507156D02*
X1030145D01*
G01X1107783Y505975D02*
X1031326D01*
G01X1047153Y507156D02*
Y508540D01*
G01X1046956Y508343D02*
Y507156D01*
G01X1043609D02*
Y508343D01*
G01X1043413Y507156D02*
Y508540D01*
G01X1042153Y507156D02*
Y508540D01*
G01X1041956Y508343D02*
Y507156D01*
G01X1038609D02*
Y508343D01*
G01X1038413Y507156D02*
Y508540D01*
G01X1037153Y507156D02*
Y508540D01*
G01X1036956Y508343D02*
Y507156D01*
G01X1033609D02*
Y508343D01*
G01X1033413Y507156D02*
Y508540D01*
G01X1032153Y507156D02*
Y508540D01*
G01X1031956Y508343D02*
Y507156D01*
G01X1031326Y505975D02*
Y502038D01*
G01X1030361Y511625D02*
Y512668D01*
G01X1030164Y511428D02*
Y512471D01*
G01X1030145Y507156D02*
Y503219D01*
G01X1029298Y512471D02*
Y511428D01*
G01X1029101Y512668D02*
Y511625D01*
G01X1027212D02*
Y512668D01*
G01X1027015Y511428D02*
Y512471D01*
G01X1026149D02*
Y511428D01*
G01X1025952Y512668D02*
Y511625D01*
G01X1030145Y507156D02*
X1031326Y505975D01*
G01X1030145Y503219D02*
X1031326Y502038D01*
G01X1025978Y512153D02*
X1025952Y512222D01*
G01X1026149Y512084D02*
X1026050Y512103D01*
G01X1029128Y512153D02*
X1029101Y512222D01*
G01X1029298Y512084D02*
X1029200Y512103D01*
G01X1027113D02*
X1027015Y512084D01*
G01X1027212Y512222D02*
X1027185Y512153D01*
G01X1030263Y512103D02*
X1030164Y512084D01*
G01X1030361Y512222D02*
X1030335Y512153D01*
G01X1032939Y515621D02*
X1109279D01*
G01X1111523Y515030D02*
X1033098D01*
G01X1030164Y512471D02*
X1030361D01*
G01X1029101D02*
X1029298D01*
G01X1027015D02*
X1027212D01*
G01X1025952D02*
X1026149D01*
G01X1029298Y512084D02*
X1030164D01*
G01X1026149D02*
X1027015D01*
G01X1033098Y515030D02*
X1032042Y518967D01*
G01X1033511Y552383D02*
X1033413Y552402D01*
G01X1033583Y552332D02*
X1033511Y552383D01*
G01X1033609Y552262D02*
X1033583Y552332D01*
G01X1038511Y552383D02*
X1038413Y552402D01*
G01X1038583Y552332D02*
X1038511Y552383D01*
G01X1038609Y552262D02*
X1038583Y552332D01*
G01X1043511Y552383D02*
X1043413Y552402D01*
G01X1043583Y552332D02*
X1043511Y552383D01*
G01X1043609Y552262D02*
X1043583Y552332D01*
G01X1027113Y556591D02*
X1027015Y556573D01*
G01X1027185Y556641D02*
X1027113Y556591D01*
G01X1027212Y556710D02*
X1027185Y556641D01*
G01X1030263Y556591D02*
X1030164Y556573D01*
G01X1030335Y556641D02*
X1030263Y556591D01*
G01X1030361Y556710D02*
X1030335Y556641D01*
G01X1025978D02*
X1025952Y556710D01*
G01X1026050Y556591D02*
X1025978Y556641D01*
G01X1026149Y556573D02*
X1026050Y556591D01*
G01X1029128Y556641D02*
X1029101Y556710D01*
G01X1029200Y556591D02*
X1029128Y556641D01*
G01X1029298Y556573D02*
X1029200Y556591D01*
G01X1046982Y552332D02*
X1046956Y552262D01*
G01X1047054Y552383D02*
X1046982Y552332D01*
G01X1047153Y552402D02*
X1047054Y552383D01*
G01X1041982Y552332D02*
X1041956Y552262D01*
G01X1042054Y552383D02*
X1041982Y552332D01*
G01X1042153Y552402D02*
X1042054Y552383D01*
G01X1036982Y552332D02*
X1036956Y552262D01*
G01X1037054Y552383D02*
X1036982Y552332D01*
G01X1037153Y552402D02*
X1037054Y552383D01*
G01X1031982Y552332D02*
X1031956Y552262D01*
G01X1032054Y552383D02*
X1031982Y552332D01*
G01X1032153Y552402D02*
X1032054Y552383D01*
G01X1029101Y556113D02*
G03X1029298Y555916I197J0D01*
G01X1030164D02*
G03X1030361Y556113I0J197D01*
G01X1027015Y555916D02*
G03X1027212Y556113I0J197D01*
G01X1047153Y553028D02*
G03X1046956Y552831I0J-197D01*
G01X1033609D02*
G03X1033413Y553028I-197J0D01*
G01X1032153D02*
G03X1031956Y552831I0J-197D01*
G01X1038609D02*
G03X1038413Y553028I-197J0D01*
G01X1037153D02*
G03X1036956Y552831I0J-197D01*
G01X1043609D02*
G03X1043413Y553028I-197J0D01*
G01X1042153D02*
G03X1041956Y552831I0J-197D01*
G01X1025952Y556113D02*
G03X1026149Y555916I197J0D01*
G01X1030164Y556960D02*
X1030361D01*
G01X1029101D02*
X1029298D01*
G01X1027015D02*
X1027212D01*
G01X1025952D02*
X1026149D01*
G01X1029298Y556573D02*
X1030164D01*
G01X1026149D02*
X1027015D01*
G01X1029298Y555916D02*
X1030164D01*
G01X1026149D02*
X1027015D01*
G01X1033413Y553028D02*
X1032153D01*
G01X1038413D02*
X1037153D01*
G01X1043413D02*
X1042153D01*
G01X1048413D02*
X1047153D01*
G01X1033413Y552402D02*
X1032153D01*
G01X1038413D02*
X1037153D01*
G01X1043413D02*
X1042153D01*
G01X1048413D02*
X1047153D01*
G01X1106601Y551644D02*
X1030145D01*
G01X1107783Y550463D02*
X1031326D01*
G01X1047153Y551644D02*
Y553028D01*
G01X1046956Y552831D02*
Y551644D01*
G01X1043609D02*
Y552831D01*
G01X1043413Y551644D02*
Y553028D01*
G01X1042153Y551644D02*
Y553028D01*
G01X1041956Y552831D02*
Y551644D01*
G01X1038609D02*
Y552831D01*
G01X1038413Y551644D02*
Y553028D01*
G01X1037153Y551644D02*
Y553028D01*
G01X1036956Y552831D02*
Y551644D01*
G01X1033609D02*
Y552831D01*
G01X1033413Y551644D02*
Y553028D01*
G01X1032153Y551644D02*
Y553028D01*
G01X1031956Y552831D02*
Y551644D01*
G01X1031326Y550463D02*
Y546526D01*
G01X1030361Y556113D02*
Y557156D01*
G01X1030164Y555916D02*
Y556960D01*
G01X1030145Y551644D02*
Y547707D01*
G01Y551644D02*
X1031326Y550463D01*
G01X1030145Y547707D02*
X1031326Y546526D01*
G01X1029298Y556960D02*
Y555916D01*
G01X1029101Y557156D02*
Y556113D01*
G01X1027212D02*
Y557156D01*
G01X1027015Y555916D02*
Y556960D01*
G01X1026149D02*
Y555916D01*
G01X1025952Y557156D02*
Y556113D01*
G01X1031557Y578928D02*
X1030429Y578697D01*
G01X1031557Y577776D02*
X1030655Y577546D01*
G01X1032459Y574090D02*
X1033361Y574321D01*
G01X1031557Y573169D02*
X1030655Y572939D01*
G01X1032459Y569253D02*
X1033361Y569483D01*
G01X1043061Y575242D02*
X1043737Y575473D01*
G01X1040128Y574551D02*
X1039451Y574321D01*
G01Y575242D02*
X1040128Y575473D01*
G01X1043512Y574551D02*
X1043061Y574321D01*
G01X1033361Y569483D02*
X1034264Y569944D01*
G01X1032685Y568101D02*
X1033813Y568332D01*
G01X1034264Y573630D02*
X1034715Y573860D01*
G01X1030655Y572939D02*
X1029753Y572478D01*
G01Y573630D02*
X1029301Y573399D01*
G01X1033813Y568332D02*
X1034940Y569023D01*
G01X1030429Y578697D02*
X1029301Y578006D01*
G01X1032459Y578928D02*
X1031557D01*
G01X1032459Y577776D02*
X1031557D01*
G01X1043737Y575473D02*
X1044639D01*
G01X1040128D02*
X1041031D01*
G01X1037873D02*
X1039000D01*
G01X1040579Y574551D02*
X1040128D01*
G01X1044188D02*
X1043512D01*
G01X1031557Y574090D02*
X1032459D01*
G01Y573169D02*
X1031557D01*
G01Y569253D02*
X1032459D01*
G01X1025016D02*
X1026144D01*
G01X1031331Y568101D02*
X1032685D01*
G01X1026144D02*
X1025016D01*
G01X1039000D02*
X1037873D01*
G01X1042609D02*
X1041481D01*
G01X1046218D02*
X1045090D01*
G01X1033361Y574321D02*
X1034264Y575012D01*
G01X1029301Y573399D02*
X1028399Y572708D01*
G01X1030655Y577546D02*
X1029753Y576854D01*
G01X1043061Y574321D02*
X1042835Y574090D01*
G01X1033361Y577546D02*
X1032459Y577776D01*
G01X1033587Y578697D02*
X1032459Y578928D01*
G01X1032939Y560109D02*
X1109279D01*
G01X1111523Y559518D02*
X1033098D01*
G01X1042384Y574551D02*
X1043061Y575242D01*
G01X1034940Y569023D02*
X1035617Y569713D01*
G01X1039451Y574321D02*
X1039000Y573860D01*
G01Y574781D02*
X1039451Y575242D01*
G01X1034715Y573860D02*
X1035392Y574551D01*
G01X1029301Y578006D02*
X1028625Y577315D01*
G01X1044639Y574321D02*
X1044188Y574551D01*
G01X1044639Y575473D02*
X1045316Y575242D01*
G01X1041031Y575473D02*
X1041707Y575242D01*
G01X1030655Y574321D02*
X1031557Y574090D01*
G01X1033361Y572939D02*
X1032459Y573169D01*
G01X1030655Y569483D02*
X1031557Y569253D01*
G01X1030204Y568332D02*
X1031331Y568101D01*
G01X1034264Y569944D02*
X1034940Y570865D01*
G01X1029753Y572478D02*
X1029076Y571556D01*
G01X1034264Y575012D02*
X1034715Y575703D01*
G01X1029753Y576854D02*
X1029301Y576163D01*
G01X1042835Y574090D02*
X1042609Y573630D01*
G01X1034264Y576854D02*
X1033361Y577546D01*
G01X1034715Y578006D02*
X1033587Y578697D01*
G01X1029076Y569023D02*
X1030204Y568332D01*
G01X1041031Y574321D02*
X1040579Y574551D01*
G01X1034715Y573399D02*
X1034264Y573630D01*
G01Y572478D02*
X1033361Y572939D01*
G01X1029301Y573860D02*
X1029753Y573630D01*
G01Y569944D02*
X1030655Y569483D01*
G01X1035392Y574551D02*
X1035843Y575473D01*
G01X1035617Y569713D02*
X1036068Y570865D01*
G01X1028399Y572708D02*
X1027948Y571556D01*
G01X1028625Y577315D02*
X1028174Y576163D01*
G01X1045767Y574781D02*
X1046218Y573630D01*
G01X1045090D02*
X1044865Y574090D01*
G01X1041481Y573630D02*
X1041256Y574090D01*
G01X1034715Y576163D02*
X1034264Y576854D01*
G01X1034940Y571556D02*
X1034264Y572478D01*
G01X1045316Y575242D02*
X1045767Y574781D01*
G01X1044865Y574090D02*
X1044639Y574321D01*
G01X1041707Y575242D02*
X1042384Y574551D01*
G01X1041256Y574090D02*
X1041031Y574321D01*
G01X1035392Y577315D02*
X1034715Y578006D01*
G01X1028625Y574551D02*
X1029301Y573860D01*
G01X1028399Y569713D02*
X1029076Y569023D01*
G01X1035617Y572708D02*
X1034715Y573399D01*
G01X1029753Y575012D02*
X1030655Y574321D01*
G01X1046218Y573630D02*
Y568101D01*
G01X1045090D02*
Y573630D01*
G01X1042609D02*
Y568101D01*
G01X1041481D02*
Y573630D01*
G01X1039000Y573860D02*
Y568101D01*
G01Y575473D02*
Y574781D01*
G01X1037873Y568101D02*
Y575473D01*
G01X1036068Y570865D02*
Y571556D01*
G01X1035843Y575473D02*
Y576163D01*
G01X1034940Y570865D02*
Y571556D01*
G01X1034715Y575703D02*
Y576163D01*
G01X1033098Y559518D02*
X1032042Y563455D01*
G01X1035843Y576163D02*
X1035392Y577315D01*
G01X1036068Y571556D02*
X1035617Y572708D01*
G01X1027948Y570865D02*
X1028399Y569713D01*
G01X1028174Y575473D02*
X1028625Y574551D01*
G01X1029301Y575703D02*
X1029753Y575012D01*
G01X1029076Y570865D02*
X1029753Y569944D01*
G01X1029301Y576163D02*
Y575703D01*
G01X1029076Y571556D02*
Y570865D01*
G01X1028174Y576163D02*
Y575473D01*
G01X1027948Y571556D02*
Y570865D01*
G01X1026144Y569253D02*
Y568101D01*
G01X1025016D02*
Y569253D01*
G01X1036419Y594676D02*
X1040803D01*
G01X1039829Y601172D02*
X1036419Y594676D01*
G01X1039829Y592510D02*
Y601172D01*
G01X1028624Y592510D02*
X1032521D01*
G01X1029111Y594676D02*
X1028624Y592510D01*
G01X1030085Y596119D02*
X1029111Y594676D01*
G01X1031059Y596841D02*
X1030085Y596119D01*
G01X1032034Y597563D02*
X1031059Y596841D01*
G01X1032521Y598285D02*
X1032034Y597563D01*
G01X1032521Y599728D02*
Y598285D01*
G01X1032034Y600450D02*
X1032521Y599728D01*
G01X1031059Y601172D02*
X1032034Y600450D01*
G01X1030085Y601172D02*
X1031059D01*
G01X1029111Y600450D02*
X1030085Y601172D01*
G01X1028624Y599728D02*
X1029111Y600450D01*
G01X1045676Y593232D02*
X1046163Y592510D01*
G01X1045676D02*
Y593232D01*
G01X1046163Y592510D02*
X1045676D01*
G01X1039611Y693641D02*
X1040098Y692919D01*
G01X1035713Y692197D02*
X1036688Y693641D01*
G01X1037662Y685702D02*
X1036688Y686423D01*
G01X1038637Y685702D02*
X1037662D01*
G01X1039611Y686423D02*
X1038637Y685702D01*
G01X1040098Y687145D02*
X1039611Y686423D01*
G01X1048381Y687867D02*
X1047406Y686423D01*
G01X1043509Y692197D02*
X1044483Y693641D01*
G01X1043021Y690032D02*
X1043509Y692197D01*
G01Y687867D02*
X1043021Y690032D01*
G01X1043996Y687145D02*
X1043509Y687867D01*
G01X1044483Y686423D02*
X1043996Y687145D01*
G01X1045457Y685702D02*
X1044483Y686423D01*
G01X1046432Y685702D02*
X1045457D01*
G01X1047406Y686423D02*
X1046432Y685702D01*
G01X1035226Y690032D02*
X1035713Y692197D01*
G01Y687867D02*
X1035226Y690032D01*
G01X1036688Y686423D02*
X1035713Y687867D01*
G01X1038637Y694363D02*
X1039611Y693641D01*
G01X1037662Y694363D02*
X1038637D01*
G01X1036688Y693641D02*
X1037662Y694363D01*
G01X1047406Y693641D02*
X1047893Y692919D01*
G01X1046432Y694363D02*
X1047406Y693641D01*
G01X1045457Y694363D02*
X1046432D01*
G01X1044483Y693641D02*
X1045457Y694363D01*
G01X1055892Y46558D02*
Y37897D01*
G01X1051994Y46558D02*
Y37897D01*
G01Y42228D02*
X1055892D01*
G01X1058951Y190122D02*
X1058036Y189810D01*
G01X1054069Y190122D02*
X1053154Y189810D01*
G01X1058951Y188564D02*
X1059561Y188875D01*
G01X1068410Y194484D02*
X1067189Y193861D01*
G01X1054069Y188564D02*
X1054679Y188875D01*
G01X1070240Y194796D02*
X1068410Y194484D01*
G01X1069020Y192926D02*
X1070546Y193238D01*
G01X1068105Y192303D02*
X1069020Y192926D01*
G01X1049492Y190122D02*
X1047967D01*
G01X1055290D02*
X1054069D01*
G01X1060172D02*
X1058951D01*
G01X1063223D02*
X1061697D01*
G01X1059561Y188875D02*
X1060172D01*
G01X1054679D02*
X1055595D01*
G01X1074207Y181708D02*
X1065664D01*
G01Y180150D02*
X1076648D01*
G01X1061697D02*
X1063223D01*
G01X1056815D02*
X1058341D01*
G01X1051933D02*
X1053459D01*
G01X1047967D02*
X1049492D01*
G01X1067189Y193861D02*
X1065969Y192615D01*
G01X1058646Y188252D02*
X1058951Y188564D01*
G01X1058036Y189810D02*
X1057120Y188875D01*
G01X1053764Y188252D02*
X1054069Y188564D01*
G01X1053154Y189810D02*
X1052544Y189187D01*
G01X1067494Y191368D02*
X1068105Y192303D01*
G01X1055595Y188875D02*
X1056205Y188564D01*
G01X1061087Y189810D02*
X1060172Y190122D01*
G01Y188875D02*
X1061087Y188564D01*
G01X1056205Y189810D02*
X1055290Y190122D01*
G01X1058341Y187629D02*
X1058646Y188252D01*
G01X1053459Y187629D02*
X1053764Y188252D01*
G01X1052544Y189187D02*
X1051933Y187629D01*
G01X1065969Y192615D02*
X1065664Y191368D01*
G01Y190745D02*
X1065969Y189499D01*
G01X1068105D02*
X1067494Y190745D01*
G01X1065969Y189499D02*
X1066579Y188564D01*
G01X1061697Y189187D02*
X1061087Y189810D01*
G01Y188564D02*
X1061697Y187941D01*
G01X1057120Y188875D02*
X1056205Y189810D01*
G01Y188564D02*
X1056510Y188252D01*
G01X1076648Y181708D02*
X1068105Y189499D01*
G01X1066579Y188564D02*
X1074207Y181708D01*
G01X1067494Y190745D02*
Y191368D01*
G01X1065664Y181708D02*
Y180150D01*
G01Y191368D02*
Y190745D01*
G01X1063223Y180150D02*
Y190122D01*
G01X1061697Y187941D02*
Y180150D01*
G01Y190122D02*
Y189187D01*
G01X1058341Y180150D02*
Y187629D01*
G01X1056815D02*
Y180150D01*
G01X1056510Y188252D02*
X1056815Y187629D01*
G01X1053459Y180150D02*
Y187629D01*
G01X1051933D02*
Y180150D01*
G01X1049492D02*
Y190122D01*
G01X1047967Y187941D02*
Y180150D01*
G01Y190122D02*
Y189187D01*
G01X1053412Y229025D02*
Y237686D01*
G01X1049514D02*
X1053412Y229025D01*
G01X1049514D02*
Y237686D01*
G01X1065592Y229746D02*
X1064618Y231190D01*
G01X1066566Y229025D02*
X1065592Y229746D01*
G01X1067541Y229025D02*
X1066566D01*
G01X1068515Y229746D02*
X1067541Y229025D01*
G01X1069002Y230468D02*
X1068515Y229746D01*
G01X1069002Y231912D02*
Y230468D01*
G01X1068515Y232633D02*
X1069002Y231912D01*
G01X1065105Y235521D02*
X1065592Y234799D01*
G01X1065105Y236242D02*
Y235521D01*
G01X1065592Y236964D02*
X1065105Y236242D01*
G01X1066566Y237686D02*
X1065592Y236964D01*
G01X1067541Y237686D02*
X1066566D01*
G01X1068515Y236964D02*
X1067541Y237686D01*
G01X1069002Y236242D02*
X1068515Y236964D01*
G01X1065592Y234799D02*
X1068515Y232633D01*
G01X1068009Y417571D02*
X1065573D01*
G01X1068983Y418292D02*
X1068009Y417571D01*
G01X1069470Y419014D02*
X1068983Y418292D01*
G01X1069470Y420458D02*
Y419014D01*
G01X1068983Y421179D02*
X1069470Y420458D01*
G01X1068009Y421901D02*
X1068983Y421179D01*
G01X1065573Y413240D02*
Y421901D01*
G01X1052905Y413962D02*
X1051931Y413240D01*
G01X1053392Y414683D02*
X1052905Y413962D01*
G01X1053880Y416127D02*
X1053392Y414683D01*
G01X1053880Y419014D02*
Y416127D01*
G01X1053392Y420458D02*
X1053880Y419014D01*
G01X1052905Y421179D02*
X1053392Y420458D01*
G01X1051931Y421901D02*
X1052905Y421179D01*
G01X1050957D02*
X1051931Y421901D01*
G01X1050469Y420458D02*
X1050957Y421179D01*
G01X1049982Y419014D02*
X1050469Y420458D01*
G01X1049982Y416127D02*
Y419014D01*
G01X1050469Y414683D02*
X1049982Y416127D01*
G01X1050957Y413962D02*
X1050469Y414683D01*
G01X1051931Y413240D02*
X1050957Y413962D01*
G01X1065573Y421901D02*
X1068009D01*
G01X1048511Y507895D02*
X1048413Y507914D01*
G01X1048583Y507844D02*
X1048511Y507895D01*
G01X1048609Y507774D02*
X1048583Y507844D01*
G01X1053511Y507895D02*
X1053413Y507914D01*
G01X1053583Y507844D02*
X1053511Y507895D01*
G01X1053609Y507774D02*
X1053583Y507844D01*
G01X1058511Y507895D02*
X1058413Y507914D01*
G01X1058583Y507844D02*
X1058511Y507895D01*
G01X1058609Y507774D02*
X1058583Y507844D01*
G01X1063511Y507895D02*
X1063413Y507914D01*
G01X1063583Y507844D02*
X1063511Y507895D01*
G01X1063609Y507774D02*
X1063583Y507844D01*
G01X1068511Y507895D02*
X1068413Y507914D01*
G01X1068583Y507844D02*
X1068511Y507895D01*
G01X1068609Y507774D02*
X1068583Y507844D01*
G01X1066982D02*
X1066956Y507774D01*
G01X1067054Y507895D02*
X1066982Y507844D01*
G01X1067153Y507914D02*
X1067054Y507895D01*
G01X1061982Y507844D02*
X1061956Y507774D01*
G01X1062054Y507895D02*
X1061982Y507844D01*
G01X1062153Y507914D02*
X1062054Y507895D01*
G01X1056982Y507844D02*
X1056956Y507774D01*
G01X1057054Y507895D02*
X1056982Y507844D01*
G01X1057153Y507914D02*
X1057054Y507895D01*
G01X1051982Y507844D02*
X1051956Y507774D01*
G01X1052054Y507895D02*
X1051982Y507844D01*
G01X1052153Y507914D02*
X1052054Y507895D01*
G01X1048609Y508343D02*
G03X1048413Y508540I-197J0D01*
G01X1053609Y508343D02*
G03X1053413Y508540I-197J0D01*
G01X1052153D02*
G03X1051956Y508343I0J-197D01*
G01X1058609D02*
G03X1058413Y508540I-197J0D01*
G01X1057153D02*
G03X1056956Y508343I0J-197D01*
G01X1063609D02*
G03X1063413Y508540I-197J0D01*
G01X1062153D02*
G03X1061956Y508343I0J-197D01*
G01X1068609D02*
G03X1068413Y508540I-197J0D01*
G01X1067153D02*
G03X1066956Y508343I0J-197D01*
G01X1053413Y508540D02*
X1052153D01*
G01X1058413D02*
X1057153D01*
G01X1063413D02*
X1062153D01*
G01X1068413D02*
X1067153D01*
G01X1053413Y507914D02*
X1052153D01*
G01X1058413D02*
X1057153D01*
G01X1063413D02*
X1062153D01*
G01X1068413D02*
X1067153D01*
G01X1068609Y507156D02*
Y508343D01*
G01X1068413Y507156D02*
Y508540D01*
G01X1067153Y507156D02*
Y508540D01*
G01X1066956Y508343D02*
Y507156D01*
G01X1063609D02*
Y508343D01*
G01X1063413Y507156D02*
Y508540D01*
G01X1062153Y507156D02*
Y508540D01*
G01X1061956Y508343D02*
Y507156D01*
G01X1058609D02*
Y508343D01*
G01X1058413Y507156D02*
Y508540D01*
G01X1057153Y507156D02*
Y508540D01*
G01X1056956Y508343D02*
Y507156D01*
G01X1053609D02*
Y508343D01*
G01X1053413Y507156D02*
Y508540D01*
G01X1052153Y507156D02*
Y508540D01*
G01X1051956Y508343D02*
Y507156D01*
G01X1048609D02*
Y508343D01*
G01X1048413Y507156D02*
Y508540D01*
G01X1048511Y552383D02*
X1048413Y552402D01*
G01X1048583Y552332D02*
X1048511Y552383D01*
G01X1048609Y552262D02*
X1048583Y552332D01*
G01X1053511Y552383D02*
X1053413Y552402D01*
G01X1053583Y552332D02*
X1053511Y552383D01*
G01X1053609Y552262D02*
X1053583Y552332D01*
G01X1058511Y552383D02*
X1058413Y552402D01*
G01X1058583Y552332D02*
X1058511Y552383D01*
G01X1058609Y552262D02*
X1058583Y552332D01*
G01X1063511Y552383D02*
X1063413Y552402D01*
G01X1063583Y552332D02*
X1063511Y552383D01*
G01X1063609Y552262D02*
X1063583Y552332D01*
G01X1068511Y552383D02*
X1068413Y552402D01*
G01X1068583Y552332D02*
X1068511Y552383D01*
G01X1068609Y552262D02*
X1068583Y552332D01*
G01X1066982D02*
X1066956Y552262D01*
G01X1067054Y552383D02*
X1066982Y552332D01*
G01X1067153Y552402D02*
X1067054Y552383D01*
G01X1061982Y552332D02*
X1061956Y552262D01*
G01X1062054Y552383D02*
X1061982Y552332D01*
G01X1062153Y552402D02*
X1062054Y552383D01*
G01X1056982Y552332D02*
X1056956Y552262D01*
G01X1057054Y552383D02*
X1056982Y552332D01*
G01X1057153Y552402D02*
X1057054Y552383D01*
G01X1051982Y552332D02*
X1051956Y552262D01*
G01X1052054Y552383D02*
X1051982Y552332D01*
G01X1052153Y552402D02*
X1052054Y552383D01*
G01X1048609Y552831D02*
G03X1048413Y553028I-197J0D01*
G01X1053609Y552831D02*
G03X1053413Y553028I-197J0D01*
G01X1052153D02*
G03X1051956Y552831I0J-197D01*
G01X1058609D02*
G03X1058413Y553028I-197J0D01*
G01X1057153D02*
G03X1056956Y552831I0J-197D01*
G01X1063609D02*
G03X1063413Y553028I-197J0D01*
G01X1062153D02*
G03X1061956Y552831I0J-197D01*
G01X1068609D02*
G03X1068413Y553028I-197J0D01*
G01X1067153D02*
G03X1066956Y552831I0J-197D01*
G01X1053413Y553028D02*
X1052153D01*
G01X1058413D02*
X1057153D01*
G01X1063413D02*
X1062153D01*
G01X1068413D02*
X1067153D01*
G01X1053413Y552402D02*
X1052153D01*
G01X1058413D02*
X1057153D01*
G01X1063413D02*
X1062153D01*
G01X1068413D02*
X1067153D01*
G01X1068609Y551644D02*
Y552831D01*
G01X1068413Y551644D02*
Y553028D01*
G01X1067153Y551644D02*
Y553028D01*
G01X1066956Y552831D02*
Y551644D01*
G01X1063609D02*
Y552831D01*
G01X1063413Y551644D02*
Y553028D01*
G01X1062153Y551644D02*
Y553028D01*
G01X1061956Y552831D02*
Y551644D01*
G01X1058609D02*
Y552831D01*
G01X1058413Y551644D02*
Y553028D01*
G01X1057153Y551644D02*
Y553028D01*
G01X1056956Y552831D02*
Y551644D01*
G01X1053609D02*
Y552831D01*
G01X1053413Y551644D02*
Y553028D01*
G01X1052153Y551644D02*
Y553028D01*
G01X1051956Y552831D02*
Y551644D01*
G01X1048609D02*
Y552831D01*
G01X1048413Y551644D02*
Y553028D01*
G01X1053211Y575242D02*
X1053887Y575473D01*
G01X1050278Y574551D02*
X1049601Y574321D01*
G01Y575242D02*
X1050278Y575473D01*
G01X1053662Y574551D02*
X1053211Y574321D01*
G01X1053887Y575473D02*
X1054790D01*
G01X1050278D02*
X1051181D01*
G01X1048023D02*
X1049151D01*
G01X1050729Y574551D02*
X1050278D01*
G01X1054338D02*
X1053662D01*
G01X1049151Y568101D02*
X1048023D01*
G01X1052759D02*
X1051632D01*
G01X1056368D02*
X1055240D01*
G01X1053211Y574321D02*
X1052985Y574090D01*
G01X1052534Y574551D02*
X1053211Y575242D01*
G01X1049601Y574321D02*
X1049151Y573860D01*
G01Y574781D02*
X1049601Y575242D01*
G01X1054790Y574321D02*
X1054338Y574551D01*
G01X1051181Y574321D02*
X1050729Y574551D01*
G01X1054790Y575473D02*
X1055466Y575242D01*
G01X1051181Y575473D02*
X1051857Y575242D01*
G01X1052985Y574090D02*
X1052759Y573630D01*
G01X1055466Y575242D02*
X1055917Y574781D01*
G01X1055015Y574090D02*
X1054790Y574321D01*
G01X1051857Y575242D02*
X1052534Y574551D01*
G01X1051406Y574090D02*
X1051181Y574321D01*
G01X1056368Y573630D02*
Y568101D01*
G01X1055240D02*
Y573630D01*
G01X1052759D02*
Y568101D01*
G01X1051632D02*
Y573630D01*
G01X1055917Y574781D02*
X1056368Y573630D01*
G01X1055240D02*
X1055015Y574090D01*
G01X1051632Y573630D02*
X1051406Y574090D01*
G01X1049151Y573860D02*
Y568101D01*
G01Y575473D02*
Y574781D01*
G01X1048023Y568101D02*
Y575473D01*
G01X1054445Y596119D02*
X1054933Y598285D01*
G01X1053958Y592510D02*
X1054445Y596119D01*
G01X1055907Y601172D02*
X1052009D01*
G01X1054933Y598285D02*
X1055907Y601172D01*
G01X1062728Y593232D02*
X1061753Y592510D01*
G01X1063215Y593954D02*
X1062728Y593232D01*
G01X1063702Y595398D02*
X1063215Y593954D01*
G01X1063702Y598285D02*
Y595398D01*
G01X1063215Y599728D02*
X1063702Y598285D01*
G01X1062728Y600450D02*
X1063215Y599728D01*
G01X1061753Y601172D02*
X1062728Y600450D01*
G01X1060779D02*
X1061753Y601172D01*
G01X1060292Y599728D02*
X1060779Y600450D01*
G01X1059805Y598285D02*
X1060292Y599728D01*
G01X1059805Y595398D02*
Y598285D01*
G01X1060292Y593954D02*
X1059805Y595398D01*
G01X1060779Y593232D02*
X1060292Y593954D01*
G01X1061753Y592510D02*
X1060779Y593232D01*
G01X1048868Y690032D02*
X1048381Y687867D01*
G01Y692197D02*
X1048868Y690032D01*
G01X1047893Y692919D02*
X1048381Y692197D01*
G01X1056176Y694363D02*
Y685702D01*
G01X1053740Y687145D02*
X1056176Y694363D01*
G01X1051304D02*
X1053740Y687145D01*
G01X1051304Y685702D02*
Y694363D01*
G01X1062022Y690032D02*
X1059586D01*
G01X1062997Y690754D02*
X1062022Y690032D01*
G01X1063484Y691476D02*
X1062997Y690754D01*
G01X1063484Y692919D02*
Y691476D01*
G01X1062997Y693641D02*
X1063484Y692919D01*
G01X1059586Y685702D02*
Y694363D01*
G01X1066894Y692197D02*
X1067869Y693641D01*
G01X1066407Y690032D02*
X1066894Y692197D01*
G01Y687867D02*
X1066407Y690032D01*
G01X1067381Y687145D02*
X1066894Y687867D01*
G01X1067869Y686423D02*
X1067381Y687145D01*
G01X1068843Y685702D02*
X1067869Y686423D01*
G01X1069818Y685702D02*
X1068843D01*
G01X1070792Y686423D02*
X1069818Y685702D01*
G01X1062022Y694363D02*
X1062997Y693641D01*
G01X1059586Y694363D02*
X1062022D01*
G01X1069818D02*
X1070792Y693641D01*
G01X1068843Y694363D02*
X1069818D01*
G01X1067869Y693641D02*
X1068843Y694363D01*
G01X1083646Y154402D02*
G03X1081677Y156371I-1969J0D01*
G01Y150465D02*
G03X1083646Y152434I0J1969D01*
G01D02*
Y154402D01*
G01X1083361Y187629D02*
X1079089Y185448D01*
G01X1079699Y184513D02*
X1085496Y187629D01*
G01X1073597Y194484D02*
X1071461Y194796D01*
G01X1070546Y193238D02*
X1071766D01*
G01X1074817Y191368D02*
X1076343D01*
G01X1098311Y188875D02*
X1089768D01*
G01Y187006D02*
X1098311D01*
G01X1087937Y180150D02*
X1089768D01*
G01X1079699Y190745D02*
X1079089Y189810D01*
G01X1071766Y193238D02*
X1073292Y192926D01*
G01D02*
X1074207Y192303D01*
G01X1085496Y187629D02*
X1079699Y190745D01*
G01X1074817Y193861D02*
X1073597Y194484D01*
G01X1079089Y189810D02*
X1083361Y187629D01*
G01X1089768Y188875D02*
Y194796D01*
G01Y180150D02*
Y187006D01*
G01X1087937Y194796D02*
Y180150D01*
G01X1076648D02*
Y181708D01*
G01X1076343Y191368D02*
X1076038Y192615D01*
G01X1079089Y185448D02*
X1079699Y184513D01*
G01X1074207Y192303D02*
X1074817Y191368D01*
G01X1076038Y192615D02*
X1074817Y193861D01*
G01X1089551Y206371D02*
G03X1087583Y204402I1J-1969D01*
G01X1085615Y200465D02*
G03X1087583Y202434I-1J1969D01*
G01X1085614Y200465D02*
G03X1087583Y202434I0J1969D01*
G01X1089551Y206371D02*
G03X1087583Y204402I1J-1969D01*
G01X1089551Y206371D02*
X1162386D01*
G01X1089551D02*
X1162386D01*
G01X1071461Y194796D02*
X1070240D01*
G01X1089768D02*
X1087937D01*
G01X1087583Y202434D02*
Y204402D01*
G01Y202434D02*
Y204402D01*
G01X1072413Y235521D02*
X1073387Y236964D01*
G01X1071926Y233355D02*
X1072413Y235521D01*
G01Y231190D02*
X1071926Y233355D01*
G01X1080695Y229025D02*
X1084593D01*
G01X1080695Y237686D02*
Y229025D01*
G01X1077285Y231190D02*
X1076311Y229746D01*
G01X1077772Y233355D02*
X1077285Y231190D01*
G01Y235521D02*
X1077772Y233355D01*
G01X1076311Y236964D02*
X1077285Y235521D01*
G01X1075336Y237686D02*
X1076311Y236964D01*
G01X1074362Y237686D02*
X1075336D01*
G01X1073387Y236964D02*
X1074362Y237686D01*
G01X1092388Y231190D02*
X1091414Y229746D01*
G01X1092876Y233355D02*
X1092388Y231190D01*
G01Y235521D02*
X1092876Y233355D01*
G01X1091414Y236964D02*
X1092388Y235521D01*
G01X1073387Y229746D02*
X1072413Y231190D01*
G01X1074362Y229025D02*
X1073387Y229746D01*
G01X1075336Y229025D02*
X1074362D01*
G01X1076311Y229746D02*
X1075336Y229025D01*
G01X1088490D02*
Y237686D01*
G01X1090439Y229025D02*
X1088490D01*
G01X1091414Y229746D02*
X1090439Y229025D01*
G01Y237686D02*
X1091414Y236964D01*
G01X1088490Y237686D02*
X1090439D01*
G01X1081163Y417571D02*
X1085061D01*
G01Y421901D02*
Y413240D01*
G01X1081163Y421901D02*
Y413240D01*
G01X1075316Y421901D02*
Y413240D01*
G01X1072881Y421901D02*
X1077753D01*
G01X1073511Y507895D02*
X1073413Y507914D01*
G01X1073583Y507844D02*
X1073511Y507895D01*
G01X1073609Y507774D02*
X1073583Y507844D01*
G01X1078511Y507895D02*
X1078413Y507914D01*
G01X1078583Y507844D02*
X1078511Y507895D01*
G01X1078609Y507774D02*
X1078583Y507844D01*
G01X1083511Y507895D02*
X1083413Y507914D01*
G01X1083583Y507844D02*
X1083511Y507895D01*
G01X1083609Y507774D02*
X1083583Y507844D01*
G01X1088511Y507895D02*
X1088413Y507914D01*
G01X1088583Y507844D02*
X1088511Y507895D01*
G01X1088609Y507774D02*
X1088583Y507844D01*
G01X1091982D02*
X1091956Y507774D01*
G01X1092054Y507895D02*
X1091982Y507844D01*
G01X1092153Y507914D02*
X1092054Y507895D01*
G01X1086982Y507844D02*
X1086956Y507774D01*
G01X1087054Y507895D02*
X1086982Y507844D01*
G01X1087153Y507914D02*
X1087054Y507895D01*
G01X1081982Y507844D02*
X1081956Y507774D01*
G01X1082054Y507895D02*
X1081982Y507844D01*
G01X1082153Y507914D02*
X1082054Y507895D01*
G01X1076982Y507844D02*
X1076956Y507774D01*
G01X1077054Y507895D02*
X1076982Y507844D01*
G01X1077153Y507914D02*
X1077054Y507895D01*
G01X1071982Y507844D02*
X1071956Y507774D01*
G01X1072054Y507895D02*
X1071982Y507844D01*
G01X1072153Y507914D02*
X1072054Y507895D01*
G01X1088609Y508343D02*
G03X1088413Y508540I-197J0D01*
G01X1087153D02*
G03X1086956Y508343I0J-197D01*
G01X1078609D02*
G03X1078413Y508540I-197J0D01*
G01X1083609Y508343D02*
G03X1083413Y508540I-197J0D01*
G01X1082153D02*
G03X1081956Y508343I0J-197D01*
G01X1092153Y508540D02*
G03X1091956Y508343I0J-197D01*
G01X1073609D02*
G03X1073413Y508540I-197J0D01*
G01X1072153D02*
G03X1071956Y508343I0J-197D01*
G01X1077153Y508540D02*
G03X1076956Y508343I0J-197D01*
G01X1092153Y507156D02*
Y508540D01*
G01X1091956Y508343D02*
Y507156D01*
G01X1088609D02*
Y508343D01*
G01X1088413Y507156D02*
Y508540D01*
G01X1087153Y507156D02*
Y508540D01*
G01X1086956Y508343D02*
Y507156D01*
G01X1083609D02*
Y508343D01*
G01X1083413Y507156D02*
Y508540D01*
G01X1082153Y507156D02*
Y508540D01*
G01X1081956Y508343D02*
Y507156D01*
G01X1078609D02*
Y508343D01*
G01X1078413Y507156D02*
Y508540D01*
G01X1077153Y507156D02*
Y508540D01*
G01X1076956Y508343D02*
Y507156D01*
G01X1073609D02*
Y508343D01*
G01X1073413Y507156D02*
Y508540D01*
G01X1072153Y507156D02*
Y508540D01*
G01X1071956Y508343D02*
Y507156D01*
G01X1073413Y508540D02*
X1072153D01*
G01X1078413D02*
X1077153D01*
G01X1083413D02*
X1082153D01*
G01X1088413D02*
X1087153D01*
G01X1093413D02*
X1092153D01*
G01X1073413Y507914D02*
X1072153D01*
G01X1078413D02*
X1077153D01*
G01X1083413D02*
X1082153D01*
G01X1088413D02*
X1087153D01*
G01X1093413D02*
X1092153D01*
G01X1078491Y534439D02*
G03X1080460Y536408I0J1969D01*
G01X1073511Y552383D02*
X1073413Y552402D01*
G01X1073583Y552332D02*
X1073511Y552383D01*
G01X1073609Y552262D02*
X1073583Y552332D01*
G01X1078511Y552383D02*
X1078413Y552402D01*
G01X1078583Y552332D02*
X1078511Y552383D01*
G01X1078609Y552262D02*
X1078583Y552332D01*
G01X1083511Y552383D02*
X1083413Y552402D01*
G01X1083583Y552332D02*
X1083511Y552383D01*
G01X1083609Y552262D02*
X1083583Y552332D01*
G01X1088511Y552383D02*
X1088413Y552402D01*
G01X1088583Y552332D02*
X1088511Y552383D01*
G01X1088609Y552262D02*
X1088583Y552332D01*
G01X1091982D02*
X1091956Y552262D01*
G01X1092054Y552383D02*
X1091982Y552332D01*
G01X1092153Y552402D02*
X1092054Y552383D01*
G01X1086982Y552332D02*
X1086956Y552262D01*
G01X1087054Y552383D02*
X1086982Y552332D01*
G01X1087153Y552402D02*
X1087054Y552383D01*
G01X1081982Y552332D02*
X1081956Y552262D01*
G01X1082054Y552383D02*
X1081982Y552332D01*
G01X1082153Y552402D02*
X1082054Y552383D01*
G01X1076982Y552332D02*
X1076956Y552262D01*
G01X1077054Y552383D02*
X1076982Y552332D01*
G01X1077153Y552402D02*
X1077054Y552383D01*
G01X1071982Y552332D02*
X1071956Y552262D01*
G01X1072054Y552383D02*
X1071982Y552332D01*
G01X1072153Y552402D02*
X1072054Y552383D01*
G01X1088609Y552831D02*
G03X1088413Y553028I-197J0D01*
G01X1087153D02*
G03X1086956Y552831I0J-197D01*
G01X1073609D02*
G03X1073413Y553028I-197J0D01*
G01X1072153D02*
G03X1071956Y552831I0J-197D01*
G01X1078609D02*
G03X1078413Y553028I-197J0D01*
G01X1077153D02*
G03X1076956Y552831I0J-197D01*
G01X1083609D02*
G03X1083413Y553028I-197J0D01*
G01X1082153D02*
G03X1081956Y552831I0J-197D01*
G01X1092153Y553028D02*
G03X1091956Y552831I0J-197D01*
G01X1080460Y538376D02*
G03X1078491Y540345I-1969J0D01*
G01X1073413Y553028D02*
X1072153D01*
G01X1078413D02*
X1077153D01*
G01X1083413D02*
X1082153D01*
G01X1088413D02*
X1087153D01*
G01X1093413D02*
X1092153D01*
G01X1073413Y552402D02*
X1072153D01*
G01X1078413D02*
X1077153D01*
G01X1083413D02*
X1082153D01*
G01X1088413D02*
X1087153D01*
G01X1093413D02*
X1092153D01*
G01Y551644D02*
Y553028D01*
G01X1091956Y552831D02*
Y551644D01*
G01X1088609D02*
Y552831D01*
G01X1088413Y551644D02*
Y553028D01*
G01X1087153Y551644D02*
Y553028D01*
G01X1086956Y552831D02*
Y551644D01*
G01X1083609D02*
Y552831D01*
G01X1083413Y551644D02*
Y553028D01*
G01X1082153Y551644D02*
Y553028D01*
G01X1081956Y552831D02*
Y551644D01*
G01X1080460Y536408D02*
Y538376D01*
G01X1078609Y551644D02*
Y552831D01*
G01X1078413Y551644D02*
Y553028D01*
G01X1077153Y551644D02*
Y553028D01*
G01X1076956Y552831D02*
Y551644D01*
G01X1073609D02*
Y552831D01*
G01X1073413Y551644D02*
Y553028D01*
G01X1072153Y551644D02*
Y553028D01*
G01X1071956Y552831D02*
Y551644D01*
G01X1082428Y590345D02*
X1069982D01*
G01X1084397Y592313D02*
Y600999D01*
G01X1082428Y584439D02*
G03X1084397Y586408I0J1969D01*
G01X1086365Y590345D02*
G03X1084397Y588376I0J-1968D01*
G01X1086365Y590345D02*
G03X1084397Y588376I0J-1968D01*
G01X1082428Y584439D02*
G03X1084397Y586408I0J1969D01*
G01X1086365Y590345D02*
X1159200D01*
G01X1086365D02*
X1159200D01*
G01X1084397Y586408D02*
Y588376D01*
G01Y586408D02*
Y588376D01*
G01X1081509Y624331D02*
X1082231Y624818D01*
G01Y624331D02*
X1081509D01*
G01X1082231Y624818D02*
Y624331D01*
G01X1081509Y616049D02*
X1080788Y615561D01*
G01X1082231Y617023D02*
X1081509Y616049D01*
G01Y617997D02*
X1082231Y617023D01*
G01X1080788Y618484D02*
X1081509Y617997D01*
G01X1079344Y618972D02*
X1080788Y618484D01*
G01X1076457Y618972D02*
X1079344D01*
G01X1075013Y618484D02*
X1076457Y618972D01*
G01X1074292Y617997D02*
X1075013Y618484D01*
G01X1073570Y617023D02*
X1074292Y617997D01*
G01Y616049D02*
X1073570Y617023D01*
G01X1075013Y615561D02*
X1074292Y616049D01*
G01X1076457Y615074D02*
X1075013Y615561D01*
G01X1077901D02*
X1076457Y615074D01*
G01X1078622Y617023D02*
X1077901Y615561D01*
G01Y618484D02*
X1078622Y617023D01*
G01X1076457Y618972D02*
X1077901Y618484D01*
G01X1080066Y607279D02*
Y611663D01*
G01X1073570Y610689D02*
X1080066Y607279D01*
G01X1082231Y610689D02*
X1073570D01*
G01X1081509Y631152D02*
X1080788Y630665D01*
G01X1082231Y632126D02*
X1081509Y631152D01*
G01X1082231Y633100D02*
Y632126D01*
G01X1081509Y634075D02*
X1082231Y633100D01*
G01X1080788Y634562D02*
X1081509Y634075D01*
G01X1079344Y635049D02*
X1080788Y634562D01*
G01X1077901D02*
X1079344Y635049D01*
G01X1077179Y634075D02*
X1077901Y634562D01*
G01X1076457Y633100D02*
X1077179Y634075D01*
G01X1076457Y632126D02*
Y633100D01*
G01X1077179Y631152D02*
X1076457Y632126D01*
G01X1073570Y631639D02*
X1077179Y631152D01*
G01X1073570Y634562D02*
Y631639D01*
G01X1081509Y641383D02*
X1082231Y640409D01*
G01X1080788Y641870D02*
X1081509Y641383D01*
G01X1079344Y642358D02*
X1080788Y641870D01*
G01X1076457Y642358D02*
X1079344D01*
G01X1075013Y641870D02*
X1076457Y642358D01*
G01X1074292Y641383D02*
X1075013Y641870D01*
G01X1073570Y640409D02*
X1074292Y641383D01*
G01Y639434D02*
X1073570Y640409D01*
G01X1075013Y638947D02*
X1074292Y639434D01*
G01X1076457Y638460D02*
X1075013Y638947D01*
G01X1079344Y638460D02*
X1076457D01*
G01X1080788Y638947D02*
X1079344Y638460D01*
G01X1081509Y639434D02*
X1080788Y638947D01*
G01X1082231Y640409D02*
X1081509Y639434D01*
G01X1071766Y687867D02*
X1070792Y686423D01*
G01X1072253Y690032D02*
X1071766Y687867D01*
G01Y692197D02*
X1072253Y690032D01*
G01X1071279Y692919D02*
X1071766Y692197D01*
G01X1070792Y693641D02*
X1071279Y692919D01*
G01X1079074Y685702D02*
Y694363D01*
G01X1075177D02*
X1079074Y685702D01*
G01X1075177D02*
Y694363D01*
G01X1090767D02*
X1094665Y685702D01*
G01X1090767D02*
Y694363D01*
G01X1082972Y685702D02*
Y694363D01*
G01X1086870Y685702D02*
X1082972D01*
G01Y690032D02*
X1085408D01*
G01X1082972Y694363D02*
X1086870D01*
G01X1098311Y180150D02*
X1100142D01*
G01D02*
Y194796D01*
G01X1098311Y187006D02*
Y180150D01*
G01Y194796D02*
Y188875D01*
G01X1100142Y194796D02*
X1098311D01*
G01X1106517Y233355D02*
X1104081D01*
G01X1107492Y234077D02*
X1106517Y233355D01*
G01X1107979Y234799D02*
X1107492Y234077D01*
G01X1107979Y236242D02*
Y234799D01*
G01X1107492Y236964D02*
X1107979Y236242D01*
G01X1106517Y237686D02*
X1107492Y236964D01*
G01X1104081Y237686D02*
X1106517D01*
G01X1104081Y229025D02*
Y237686D01*
G01X1096286D02*
X1100183D01*
G01X1096286Y229025D02*
Y237686D01*
G01X1100183Y229025D02*
X1096286D01*
G01Y233355D02*
X1098722D01*
G01X1106517D02*
X1107979Y229025D01*
G01X1099898Y359258D02*
X1097950Y357814D01*
G01X1100385Y359980D02*
X1099898Y359258D01*
G01X1100385Y361423D02*
Y359980D01*
G01X1099898Y362145D02*
X1100385Y361423D01*
G01X1098924Y362867D02*
X1099898Y362145D01*
G01X1097950Y362867D02*
X1098924D01*
G01X1096975Y362145D02*
X1097950Y362867D01*
G01X1096488Y361423D02*
X1096975Y362145D01*
G01X1096488Y354205D02*
X1100385D01*
G01X1096975Y356371D02*
X1096488Y354205D01*
G01X1097950Y357814D02*
X1096975Y356371D01*
G01X1115001Y362145D02*
X1115489Y361423D01*
G01X1114027Y362867D02*
X1115001Y362145D01*
G01X1113053D02*
X1114027Y362867D01*
G01X1112566Y361423D02*
X1113053Y362145D01*
G01X1112079Y359980D02*
X1112566Y361423D01*
G01X1112079Y357093D02*
Y359980D01*
G01X1112566Y355649D02*
X1112079Y357093D01*
G01X1113053Y354927D02*
X1112566Y355649D01*
G01X1114027Y354205D02*
X1113053Y354927D01*
G01X1115001D02*
X1114027Y354205D01*
G01X1115489Y355649D02*
X1115001Y354927D01*
G01X1114027Y359258D02*
X1115489Y358536D01*
G01X1112566D02*
X1114027Y359258D01*
G01X1112079Y357093D02*
X1112566Y358536D01*
G01X1104283Y362867D02*
X1108181Y354205D01*
G01X1104283D02*
X1108181Y362867D01*
G01X1110196Y411075D02*
X1095671D01*
G01X1190502Y355726D02*
X1110196Y411075D01*
G01X1114887Y464305D02*
X1115861Y465027D01*
G01X1114399Y463583D02*
X1114887Y464305D01*
G01X1113912Y462862D02*
X1114399Y463583D01*
G01X1113425Y460696D02*
X1113912Y462862D01*
G01Y458531D02*
X1113425Y460696D01*
G01X1114399Y457809D02*
X1113912Y458531D01*
G01X1114887Y457087D02*
X1114399Y457809D01*
G01X1115861Y456365D02*
X1114887Y457087D01*
G01X1093511Y507895D02*
X1093413Y507914D01*
G01X1093583Y507844D02*
X1093511Y507895D01*
G01X1093609Y507774D02*
X1093583Y507844D01*
G01X1098511Y507895D02*
X1098413Y507914D01*
G01X1098583Y507844D02*
X1098511Y507895D01*
G01X1098609Y507774D02*
X1098583Y507844D01*
G01X1103511Y507895D02*
X1103413Y507914D01*
G01X1103583Y507844D02*
X1103511Y507895D01*
G01X1103609Y507774D02*
X1103583Y507844D01*
G01X1101982D02*
X1101956Y507774D01*
G01X1102054Y507895D02*
X1101982Y507844D01*
G01X1102153Y507914D02*
X1102054Y507895D01*
G01X1096982Y507844D02*
X1096956Y507774D01*
G01X1097054Y507895D02*
X1096982Y507844D01*
G01X1097153Y507914D02*
X1097054Y507895D01*
G01X1093609Y508343D02*
G03X1093413Y508540I-197J0D01*
G01X1103609Y508343D02*
G03X1103413Y508540I-197J0D01*
G01X1102153D02*
G03X1101956Y508343I0J-197D01*
G01X1098609D02*
G03X1098413Y508540I-197J0D01*
G01X1097153D02*
G03X1096956Y508343I0J-197D01*
G01X1115184Y509321D02*
X1119413Y511632D01*
G01X1113491Y506959D02*
X1111523Y505656D01*
G01X1115184Y509321D02*
Y506959D01*
G01X1113491Y509321D02*
Y506959D01*
G01X1111523Y501250D02*
Y515030D01*
G01X1110145Y511880D02*
Y515030D01*
G01Y501250D02*
Y504400D01*
G01X1107783Y513849D02*
Y505975D01*
G01X1106601Y512668D02*
Y507156D01*
G01X1103609D02*
Y508343D01*
G01X1103413Y507156D02*
Y508540D01*
G01X1102153Y507156D02*
Y508540D01*
G01X1101956Y508343D02*
Y507156D01*
G01X1098609D02*
Y508343D01*
G01X1098413Y507156D02*
Y508540D01*
G01X1097153Y507156D02*
Y508540D01*
G01X1096956Y508343D02*
Y507156D01*
G01X1093609D02*
Y508343D01*
G01X1093413Y507156D02*
Y508540D01*
G01X1110145Y511880D02*
X1118688D01*
G01X1113491Y509321D02*
X1115184D01*
G01X1098413Y508540D02*
X1097153D01*
G01X1103413D02*
X1102153D01*
G01X1098413Y507914D02*
X1097153D01*
G01X1103413D02*
X1102153D01*
G01X1115184Y506959D02*
X1113491D01*
G01X1110145Y504400D02*
X1118688D01*
G01X1106601Y507156D02*
X1107783Y505975D01*
G01X1112625Y497313D02*
X1109279Y500660D01*
G01X1111523Y510625D02*
X1113491Y509321D01*
G01X1119413Y504649D02*
X1115184Y506959D01*
G01X1112625Y497313D02*
X1128373D01*
G01X1107783Y513849D02*
X1106601Y512668D01*
G01X1109279Y515621D02*
X1112625Y518967D01*
G01X1128373D02*
X1112625D01*
G01X1093511Y552383D02*
X1093413Y552402D01*
G01X1093583Y552332D02*
X1093511Y552383D01*
G01X1093609Y552262D02*
X1093583Y552332D01*
G01X1098511Y552383D02*
X1098413Y552402D01*
G01X1098583Y552332D02*
X1098511Y552383D01*
G01X1098609Y552262D02*
X1098583Y552332D01*
G01X1103511Y552383D02*
X1103413Y552402D01*
G01X1103583Y552332D02*
X1103511Y552383D01*
G01X1103609Y552262D02*
X1103583Y552332D01*
G01X1101982D02*
X1101956Y552262D01*
G01X1102054Y552383D02*
X1101982Y552332D01*
G01X1102153Y552402D02*
X1102054Y552383D01*
G01X1096982Y552332D02*
X1096956Y552262D01*
G01X1097054Y552383D02*
X1096982Y552332D01*
G01X1097153Y552402D02*
X1097054Y552383D01*
G01X1093609Y552831D02*
G03X1093413Y553028I-197J0D01*
G01X1103609Y552831D02*
G03X1103413Y553028I-197J0D01*
G01X1102153D02*
G03X1101956Y552831I0J-197D01*
G01X1098609D02*
G03X1098413Y553028I-197J0D01*
G01X1097153D02*
G03X1096956Y552831I0J-197D01*
G01X1115184Y553810D02*
X1119413Y556120D01*
G01X1113491Y551447D02*
X1111523Y550144D01*
G01X1107783Y558337D02*
X1106601Y557156D01*
G01X1115184Y553810D02*
Y551447D01*
G01X1113491Y553810D02*
Y551447D01*
G01X1110145Y556369D02*
X1118688D01*
G01X1113491Y553810D02*
X1115184D01*
G01X1098413Y553028D02*
X1097153D01*
G01X1103413D02*
X1102153D01*
G01X1098413Y552402D02*
X1097153D01*
G01X1103413D02*
X1102153D01*
G01X1115184Y551447D02*
X1113491D01*
G01X1110145Y548888D02*
X1118688D01*
G01X1112625Y541802D02*
X1128373D01*
G01X1111523Y545739D02*
Y559518D01*
G01X1110145Y556369D02*
Y559518D01*
G01Y545739D02*
Y548888D01*
G01X1107783Y558337D02*
Y550463D01*
G01X1106601Y557156D02*
Y551644D01*
G01X1103609D02*
Y552831D01*
G01X1103413Y551644D02*
Y553028D01*
G01X1102153Y551644D02*
Y553028D01*
G01X1101956Y552831D02*
Y551644D01*
G01X1098609D02*
Y552831D01*
G01X1098413Y551644D02*
Y553028D01*
G01X1097153Y551644D02*
Y553028D01*
G01X1096956Y552831D02*
Y551644D01*
G01X1093609D02*
Y552831D01*
G01X1093413Y551644D02*
Y553028D01*
G01X1106601Y551644D02*
X1107783Y550463D01*
G01X1112625Y541802D02*
X1109279Y545148D01*
G01X1111523Y555113D02*
X1113491Y553810D01*
G01X1119413Y549137D02*
X1115184Y551447D01*
G01X1109279Y560109D02*
X1112625Y563455D01*
G01X1128373D02*
X1112625D01*
G01X1094665Y685702D02*
Y694363D01*
G01X1114153Y692197D02*
X1114640Y691476D01*
G01X1114153Y692919D02*
Y692197D01*
G01X1114640Y693641D02*
X1114153Y692919D01*
G01X1114640Y686423D02*
X1113666Y687867D01*
G01X1115615Y685702D02*
X1114640Y686423D01*
G01Y691476D02*
X1116589Y690032D01*
G01X1100511Y694363D02*
Y685702D01*
G01X1115615Y694363D02*
X1114640Y693641D01*
G01X1098076Y694363D02*
X1102948D01*
G01X1103136Y759899D02*
X1103624Y759177D01*
G01X1102162Y760621D02*
X1103136Y759899D01*
G01X1101187D02*
X1102162Y760621D01*
G01X1100700Y759177D02*
X1101187Y759899D01*
G01X1100213Y757734D02*
X1100700Y759177D01*
G01X1100213Y754847D02*
Y757734D01*
G01X1100700Y753403D02*
X1100213Y754847D01*
G01X1101187Y752681D02*
X1100700Y753403D01*
G01X1102162Y751959D02*
X1101187Y752681D01*
G01X1103136D02*
X1102162Y751959D01*
G01X1103624Y753403D02*
X1103136Y752681D01*
G01X1104111Y754847D02*
X1103624Y753403D01*
G01Y756290D02*
X1104111Y754847D01*
G01X1102162Y757012D02*
X1103624Y756290D01*
G01X1100700D02*
X1102162Y757012D01*
G01X1100213Y754847D02*
X1100700Y756290D01*
G01X1108496Y752681D02*
X1108008Y753403D01*
G01X1109470Y751959D02*
X1108496Y752681D01*
G01X1110444Y751959D02*
X1109470D01*
G01X1111419Y752681D02*
X1110444Y751959D01*
G01X1111906Y753403D02*
X1111419Y752681D01*
G01X1112393Y754847D02*
X1111906Y753403D01*
G01Y756290D02*
X1112393Y754847D01*
G01X1111419Y757012D02*
X1111906Y756290D01*
G01X1110444Y757734D02*
X1111419Y757012D01*
G01X1109470Y757734D02*
X1110444D01*
G01X1108496Y757012D02*
X1109470Y757734D01*
G01X1108983Y760621D02*
X1108496Y757012D01*
G01X1111906Y760621D02*
X1108983D01*
G01X1123700Y-390518D02*
Y-407840D01*
G01X1120159Y229746D02*
X1119185Y231190D01*
G01X1121133Y229025D02*
X1120159Y229746D01*
G01X1122108Y229025D02*
X1121133D01*
G01X1123082Y229746D02*
X1122108Y229025D01*
G01X1123569Y230468D02*
X1123082Y229746D01*
G01X1123569Y231912D02*
Y230468D01*
G01X1123082Y232633D02*
X1123569Y231912D01*
G01X1119672Y235521D02*
X1120159Y234799D01*
G01X1119672Y236242D02*
Y235521D01*
G01X1120159Y236964D02*
X1119672Y236242D01*
G01X1121133Y237686D02*
X1120159Y236964D01*
G01X1122108Y237686D02*
X1121133D01*
G01X1123082Y236964D02*
X1122108Y237686D01*
G01X1123569Y236242D02*
X1123082Y236964D01*
G01X1135262Y229025D02*
Y237686D01*
G01X1137211Y229025D02*
X1135262D01*
G01X1138185Y229746D02*
X1137211Y229025D01*
G01Y237686D02*
X1138185Y236964D01*
G01X1135262Y237686D02*
X1137211D01*
G01X1120159Y234799D02*
X1123082Y232633D01*
G01X1129416Y237686D02*
Y229025D01*
G01X1115976Y357093D02*
X1115489Y355649D01*
G01Y358536D02*
X1115976Y357093D01*
G01X1139362Y362867D02*
X1135464D01*
G01X1137900Y357814D02*
X1138388Y359980D01*
G01X1137413Y354205D02*
X1137900Y357814D01*
G01X1129131Y354927D02*
X1129618Y354205D01*
G01X1129131D02*
Y354927D01*
G01X1129618Y354205D02*
X1129131D01*
G01X1121822Y362867D02*
Y354205D01*
G01X1134374Y465027D02*
Y456365D01*
G01X1131938Y457809D02*
X1134374Y465027D01*
G01X1129503D02*
X1131938Y457809D01*
G01X1129503Y456365D02*
Y465027D01*
G01X1140221Y460696D02*
X1137785D01*
G01Y465027D02*
X1140221D01*
G01X1137785Y456365D02*
Y465027D01*
G01X1117809Y464305D02*
X1118297Y463583D01*
G01X1116835Y465027D02*
X1117809Y464305D01*
G01X1115861Y465027D02*
X1116835D01*
G01Y456365D02*
X1115861D01*
G01X1117809Y457087D02*
X1116835Y456365D01*
G01X1118297Y457809D02*
X1117809Y457087D01*
G01X1126579Y458531D02*
X1126092Y457809D01*
G01X1127066Y460696D02*
X1126579Y458531D01*
G01Y462862D02*
X1127066Y460696D01*
G01X1126092Y463583D02*
X1126579Y462862D01*
G01X1125605Y464305D02*
X1126092Y463583D01*
G01X1124630Y465027D02*
X1125605Y464305D01*
G01X1123656Y465027D02*
X1124630D01*
G01X1122682Y464305D02*
X1123656Y465027D01*
G01X1122194Y463583D02*
X1122682Y464305D01*
G01X1121707Y462862D02*
X1122194Y463583D01*
G01X1121220Y460696D02*
X1121707Y462862D01*
G01Y458531D02*
X1121220Y460696D01*
G01X1122194Y457809D02*
X1121707Y458531D01*
G01X1122682Y457087D02*
X1122194Y457809D01*
G01X1123656Y456365D02*
X1122682Y457087D01*
G01X1124630Y456365D02*
X1123656D01*
G01X1125605Y457087D02*
X1124630Y456365D01*
G01X1126092Y457809D02*
X1125605Y457087D01*
G01X1120191Y474216D02*
X1119704Y474938D01*
G01X1120679Y473495D02*
X1120191Y474216D01*
G01X1121653Y472773D02*
X1120679Y473495D01*
G01X1122627Y472773D02*
X1121653D01*
G01X1123602Y473495D02*
X1122627Y472773D01*
G01X1124089Y474216D02*
X1123602Y473495D01*
G01X1124089Y475660D02*
Y474216D01*
G01X1123602Y476382D02*
X1124089Y475660D01*
G01X1120679Y478547D02*
X1123602Y476382D01*
G01X1120191Y479269D02*
X1120679Y478547D01*
G01X1120191Y479991D02*
Y479269D01*
G01X1120679Y480712D02*
X1120191Y479991D01*
G01X1121653Y481434D02*
X1120679Y480712D01*
G01X1122627Y481434D02*
X1121653D01*
G01X1123602Y480712D02*
X1122627Y481434D01*
G01X1124089Y479991D02*
X1123602Y480712D01*
G01X1137731Y481434D02*
X1140167Y472773D01*
G01X1135295D02*
X1137731Y481434D01*
G01X1131397Y480712D02*
X1131884Y479991D01*
G01X1130423Y481434D02*
X1131397Y480712D01*
G01X1129448Y481434D02*
X1130423D01*
G01X1128474Y480712D02*
X1129448Y481434D01*
G01X1127987Y479991D02*
X1128474Y480712D01*
G01X1127500Y479269D02*
X1127987Y479991D01*
G01X1127012Y477103D02*
X1127500Y479269D01*
G01Y474938D02*
X1127012Y477103D01*
G01X1127987Y474216D02*
X1127500Y474938D01*
G01X1128474Y473495D02*
X1127987Y474216D01*
G01X1129448Y472773D02*
X1128474Y473495D01*
G01X1130423Y472773D02*
X1129448D01*
G01X1131397Y473495D02*
X1130423Y472773D01*
G01X1131884Y474216D02*
X1131397Y473495D01*
G01X1136269Y475660D02*
X1139192D01*
G01X1118688Y504400D02*
G03X1119869Y505581I0J1181D01*
G01Y510699D02*
G03X1118688Y511880I-1181J0D01*
G01X1128373Y497313D02*
G03X1130342Y499282I0J1969D01*
G01D02*
Y516999D01*
G01X1119869Y510699D02*
Y505581D01*
G01X1130342Y516999D02*
G03X1128373Y518967I-1969J-1D01*
G01X1118688Y548888D02*
G03X1119869Y550069I0J1181D01*
G01Y555187D02*
G03X1118688Y556369I-1181J1D01*
G01X1128373Y541802D02*
G03X1130342Y543770I0J1969D01*
G01D02*
Y561487D01*
G01X1119869Y555187D02*
Y550069D01*
G01X1130342Y561487D02*
G03X1128373Y563455I-1969J-1D01*
G01X1129744Y685702D02*
Y694363D01*
G01X1131692Y685702D02*
X1129744D01*
G01X1132667Y686423D02*
X1131692Y685702D01*
G01X1133641Y687867D02*
X1132667Y686423D01*
G01X1134129Y690032D02*
X1133641Y687867D01*
G01Y692197D02*
X1134129Y690032D01*
G01X1118051Y692919D02*
X1117563Y693641D01*
G01X1116589Y685702D02*
X1115615D01*
G01X1117563Y686423D02*
X1116589Y685702D01*
G01X1118051Y687145D02*
X1117563Y686423D01*
G01X1118051Y688589D02*
Y687145D01*
G01X1117563Y689310D02*
X1118051Y688589D01*
G01X1116589Y690032D02*
X1117563Y689310D01*
G01X1137539Y685702D02*
Y694363D01*
G01X1141437Y685702D02*
X1137539D01*
G01X1132667Y693641D02*
X1133641Y692197D01*
G01X1137539Y690032D02*
X1139975D01*
G01X1123897Y694363D02*
Y685702D01*
G01X1116589Y694363D02*
X1115615D01*
G01X1117563Y693641D02*
X1116589Y694363D01*
G01X1137539D02*
X1141437D01*
G01X1131692D02*
X1132667Y693641D01*
G01X1129744Y694363D02*
X1131692D01*
G01X1123599Y751959D02*
X1127496D01*
G01X1124086Y754125D02*
X1123599Y751959D01*
G01X1125061Y755568D02*
X1124086Y754125D01*
G01X1127009Y757012D02*
X1125061Y755568D01*
G01X1127496Y757734D02*
X1127009Y757012D01*
G01X1127496Y759177D02*
Y757734D01*
G01X1127009Y759899D02*
X1127496Y759177D01*
G01X1126035Y760621D02*
X1127009Y759899D01*
G01X1125061Y760621D02*
X1126035D01*
G01X1124086Y759899D02*
X1125061Y760621D01*
G01X1123599Y759177D02*
X1124086Y759899D01*
G01X1134317Y752681D02*
X1133343Y751959D01*
G01X1134805Y753403D02*
X1134317Y752681D01*
G01X1135292Y754847D02*
X1134805Y753403D01*
G01X1135292Y757734D02*
Y754847D01*
G01X1134805Y759177D02*
X1135292Y757734D01*
G01X1134317Y759899D02*
X1134805Y759177D01*
G01X1133343Y760621D02*
X1134317Y759899D01*
G01X1132368D02*
X1133343Y760621D01*
G01X1131881Y759177D02*
X1132368Y759899D01*
G01X1131394Y757734D02*
X1131881Y759177D01*
G01X1131394Y754847D02*
Y757734D01*
G01X1131881Y753403D02*
X1131394Y754847D01*
G01X1132368Y752681D02*
X1131881Y753403D01*
G01X1133343Y751959D02*
X1132368Y752681D01*
G01X1117265D02*
X1117752Y751959D01*
G01X1117265D02*
Y752681D01*
G01X1117752Y751959D02*
X1117265D01*
G01X1123700Y970112D02*
Y952789D01*
G01X1156998Y40765D02*
X1156511Y41487D01*
G01X1157485Y40043D02*
X1156998Y40765D01*
G01X1158460Y39321D02*
X1157485Y40043D01*
G01X1159434Y39321D02*
X1158460D01*
G01X1160409Y40043D02*
X1159434Y39321D01*
G01X1160896Y40765D02*
X1160409Y40043D01*
G01Y42930D02*
X1160896Y42208D01*
G01X1156998Y45817D02*
X1157485Y45096D01*
G01X1156998Y46539D02*
Y45817D01*
G01X1157485Y47261D02*
X1156998Y46539D01*
G01X1158460Y47983D02*
X1157485Y47261D01*
G01X1159434Y47983D02*
X1158460D01*
G01X1160409Y47261D02*
X1159434Y47983D01*
G01X1160896Y46539D02*
X1160409Y47261D01*
G01X1157485Y45096D02*
X1160409Y42930D01*
G01X1139160Y231190D02*
X1138185Y229746D01*
G01X1139647Y233355D02*
X1139160Y231190D01*
G01Y235521D02*
X1139647Y233355D01*
G01X1138185Y236964D02*
X1139160Y235521D01*
G01X1143057Y237686D02*
X1146955D01*
G01X1143057Y229025D02*
Y237686D01*
G01X1146955Y229025D02*
X1143057D01*
G01Y233355D02*
X1145494D01*
G01X1191914Y352040D02*
X1153437D01*
G01X1138875Y361423D02*
X1139362Y362867D01*
G01X1138388Y359980D02*
X1138875Y361423D01*
G01X1146183Y354927D02*
X1145209Y354205D01*
G01X1146670Y355649D02*
X1146183Y354927D01*
G01X1147157Y357093D02*
X1146670Y355649D01*
G01X1147157Y359980D02*
Y357093D01*
G01X1146670Y361423D02*
X1147157Y359980D01*
G01X1146183Y362145D02*
X1146670Y361423D01*
G01X1145209Y362867D02*
X1146183Y362145D01*
G01X1144234D02*
X1145209Y362867D01*
G01X1143747Y361423D02*
X1144234Y362145D01*
G01X1143260Y359980D02*
X1143747Y361423D01*
G01X1143260Y357093D02*
Y359980D01*
G01X1143747Y355649D02*
X1143260Y357093D01*
G01X1144234Y354927D02*
X1143747Y355649D01*
G01X1145209Y354205D02*
X1144234Y354927D01*
G01X1141195Y461418D02*
X1140221Y460696D01*
G01X1141683Y462139D02*
X1141195Y461418D01*
G01X1141683Y463583D02*
Y462139D01*
G01X1141195Y464305D02*
X1141683Y463583D01*
G01X1140221Y465027D02*
X1141195Y464305D01*
G01X1157273Y456365D02*
Y465027D01*
G01X1153376D02*
X1157273Y456365D01*
G01X1153376D02*
Y465027D01*
G01X1149965Y458531D02*
X1149478Y457809D01*
G01X1150452Y460696D02*
X1149965Y458531D01*
G01Y462862D02*
X1150452Y460696D01*
G01X1149478Y463583D02*
X1149965Y462862D01*
G01X1148991Y464305D02*
X1149478Y463583D01*
G01X1148016Y465027D02*
X1148991Y464305D01*
G01X1147042Y465027D02*
X1148016D01*
G01X1146068Y464305D02*
X1147042Y465027D01*
G01X1145580Y463583D02*
X1146068Y464305D01*
G01X1145093Y462862D02*
X1145580Y463583D01*
G01X1144606Y460696D02*
X1145093Y462862D01*
G01Y458531D02*
X1144606Y460696D01*
G01X1145580Y457809D02*
X1145093Y458531D01*
G01X1146068Y457087D02*
X1145580Y457809D01*
G01X1147042Y456365D02*
X1146068Y457087D01*
G01X1148016Y456365D02*
X1147042D01*
G01X1148991Y457087D02*
X1148016Y456365D01*
G01X1149478Y457809D02*
X1148991Y457087D01*
G01X1151372Y481434D02*
X1155270D01*
G01X1151372Y472773D02*
Y481434D01*
G01X1155270Y472773D02*
X1151372D01*
G01X1143577D02*
X1147475D01*
G01X1143577Y481434D02*
Y472773D01*
G01X1151372Y477103D02*
X1153809D01*
G01X1159200Y590345D02*
G03X1163137Y594282I0J3937D01*
G01X1159200Y590345D02*
G03X1163137Y594282I0J3937D01*
G01Y749794D02*
X1141571D01*
G01X1153032Y779257D02*
X1153753Y779745D01*
G01X1152310Y778283D02*
X1153032Y779257D01*
G01Y777308D02*
X1152310Y778283D01*
G01X1153753Y776821D02*
X1153032Y777308D01*
G01X1155197Y776334D02*
X1153753Y776821D01*
G01X1158084Y776334D02*
X1155197D01*
G01X1159528Y776821D02*
X1158084Y776334D01*
G01X1160250Y777308D02*
X1159528Y776821D01*
G01X1160972Y778283D02*
X1160250Y777308D01*
G01Y779257D02*
X1160972Y778283D01*
G01X1159528Y779745D02*
X1160250Y779257D01*
G01X1158084Y780232D02*
X1159528Y779745D01*
G01X1156641D02*
X1158084Y780232D01*
G01X1155919Y778283D02*
X1156641Y779745D01*
G01Y776821D02*
X1155919Y778283D01*
G01X1158084Y776334D02*
X1156641Y776821D01*
G01X1155197Y784129D02*
X1153753Y784617D01*
G01X1156641D02*
X1155197Y784129D01*
G01X1160250Y800207D02*
X1159528Y799720D01*
G01X1160972Y801182D02*
X1160250Y800207D01*
G01Y803130D02*
X1160972Y802156D01*
G01X1159528Y803618D02*
X1160250Y803130D01*
G01X1158084Y804105D02*
X1159528Y803618D01*
G01X1156641D02*
X1158084Y804105D01*
G01X1155919Y803130D02*
X1156641Y803618D01*
G01X1155197Y802156D02*
X1155919Y803130D01*
G01X1155197Y801182D02*
Y802156D01*
G01X1155919Y800207D02*
X1155197Y801182D01*
G01X1152310Y800694D02*
X1155919Y800207D01*
G01X1152310Y803618D02*
Y800694D01*
G01X1160250Y793386D02*
X1160972Y793873D01*
G01Y793386D02*
X1160250D01*
G01Y785104D02*
X1159528Y784617D01*
G01X1160972Y786078D02*
X1160250Y785104D01*
G01Y787052D02*
X1160972Y786078D01*
G01X1159528Y787540D02*
X1160250Y787052D01*
G01X1158084Y788027D02*
X1159528Y787540D01*
G01X1155197Y788027D02*
X1158084D01*
G01X1153753Y787540D02*
X1155197Y788027D01*
G01X1153032Y787052D02*
X1153753Y787540D01*
G01X1152310Y786078D02*
X1153032Y787052D01*
G01Y785104D02*
X1152310Y786078D01*
G01X1153753Y784617D02*
X1153032Y785104D01*
G01X1157363Y786078D02*
X1156641Y784617D01*
G01Y787540D02*
X1157363Y786078D01*
G01X1155197Y788027D02*
X1156641Y787540D01*
G01X1160250Y810439D02*
X1160972Y809464D01*
G01X1159528Y810926D02*
X1160250Y810439D01*
G01X1158084Y811413D02*
X1159528Y810926D01*
G01X1155197Y811413D02*
X1158084D01*
G01X1153753Y810926D02*
X1155197Y811413D01*
G01X1153032Y810439D02*
X1153753Y810926D01*
G01X1152310Y809464D02*
X1153032Y810439D01*
G01Y808489D02*
X1152310Y809464D01*
G01X1153753Y808002D02*
X1153032Y808489D01*
G01X1155197Y807515D02*
X1153753Y808002D01*
G01X1158084Y807515D02*
X1155197D01*
G01X1159528Y808002D02*
X1158084Y807515D01*
G01X1160250Y808489D02*
X1159528Y808002D01*
G01X1160972Y809464D02*
X1160250Y808489D01*
G01X1161916Y28231D02*
X1161429Y28953D01*
G01X1162403Y27509D02*
X1161916Y28231D01*
G01X1163378Y26787D02*
X1162403Y27509D01*
G01X1164352Y26787D02*
X1163378D01*
G01X1165327Y27509D02*
X1164352Y26787D01*
G01X1165814Y28231D02*
X1165327Y27509D01*
G01X1165814Y29675D02*
Y28231D01*
G01X1165327Y30396D02*
X1165814Y29675D01*
G01X1164352Y31118D02*
X1165327Y30396D01*
G01X1163378Y31840D02*
X1164352Y31118D01*
G01X1162403Y32562D02*
X1163378Y31840D01*
G01X1161916Y33284D02*
X1162403Y32562D01*
G01X1161916Y34005D02*
Y33284D01*
G01X1162403Y34727D02*
X1161916Y34005D01*
G01X1163378Y35449D02*
X1162403Y34727D01*
G01X1164352Y35449D02*
X1163378D01*
G01X1165327Y34727D02*
X1164352Y35449D01*
G01X1165814Y34005D02*
X1165327Y34727D01*
G01X1174583Y31118D02*
X1174096Y28953D01*
G01Y33284D02*
X1174583Y31118D01*
G01X1173609Y34005D02*
X1174096Y33284D01*
G01X1173122Y34727D02*
X1173609Y34005D01*
G01X1172148Y35449D02*
X1173122Y34727D01*
G01X1171173Y35449D02*
X1172148D01*
G01X1170199Y34727D02*
X1171173Y35449D01*
G01X1169711Y34005D02*
X1170199Y34727D01*
G01X1169224Y33284D02*
X1169711Y34005D01*
G01X1168737Y31118D02*
X1169224Y33284D01*
G01Y28953D02*
X1168737Y31118D01*
G01X1170199Y27509D02*
X1169224Y28953D01*
G01X1177507Y26787D02*
X1181404D01*
G01X1177507Y35449D02*
Y26787D01*
G01X1171173D02*
X1170199Y27509D01*
G01X1172148Y26787D02*
X1171173D01*
G01X1173122Y27509D02*
X1172148Y26787D01*
G01X1174096Y28953D02*
X1173122Y27509D01*
G01X1160896Y42208D02*
Y40765D01*
G01X1180384Y39321D02*
X1184282D01*
G01X1180384Y47983D02*
Y39321D01*
G01X1174538Y47983D02*
X1176974Y39321D01*
G01X1172101D02*
X1174538Y47983D01*
G01X1168204Y47261D02*
X1168691Y46539D01*
G01X1167229Y47983D02*
X1168204Y47261D01*
G01X1166255Y47983D02*
X1167229D01*
G01X1165281Y47261D02*
X1166255Y47983D01*
G01X1164306Y45817D02*
X1165281Y47261D01*
G01X1163819Y43652D02*
X1164306Y45817D01*
G01Y41487D02*
X1163819Y43652D01*
G01X1164794Y40765D02*
X1164306Y41487D01*
G01X1165281Y40043D02*
X1164794Y40765D01*
G01X1166255Y39321D02*
X1165281Y40043D01*
G01X1167229Y39321D02*
X1166255D01*
G01X1168204Y40043D02*
X1167229Y39321D01*
G01X1168691Y40765D02*
X1168204Y40043D01*
G01X1173076Y42208D02*
X1175999D01*
G01X1182071Y219993D02*
Y172119D01*
G01X1193095Y176843D02*
X1182071D01*
G01Y172119D02*
X1236874D01*
G01X1162386Y206371D02*
G03X1166323Y210308I0J3937D01*
G01X1162386Y206371D02*
G03X1166323Y210308I0J3937D01*
G01Y361882D02*
Y210308D01*
G01Y361882D02*
Y210308D01*
G01X1193095Y215268D02*
X1182071D01*
G01X1236874Y219993D02*
X1182071D01*
G01X1170260Y365819D02*
G03X1166323Y361882I0J-3937D01*
G01X1170260Y365819D02*
G03X1166323Y361882I0J-3937D01*
G01X1453725Y365819D02*
X1170260D01*
G01X1453725D02*
X1170260D01*
G01X1172864Y456365D02*
Y465027D01*
G01X1168966D02*
X1172864Y456365D01*
G01X1168966D02*
Y465027D01*
G01X1161171D02*
X1165068D01*
G01X1161171Y456365D02*
Y465027D01*
G01X1165068Y456365D02*
X1161171D01*
G01X1176274Y465027D02*
X1181146D01*
G01X1161171Y460696D02*
X1163607D01*
G01X1178710Y465027D02*
Y456365D01*
G01X1176707Y481434D02*
Y472773D01*
G01X1203491Y506880D02*
G03I-10827J0D01*
G01X1163137Y745857D02*
Y594282D01*
G01Y745857D02*
Y594282D01*
G01X1203491Y736014D02*
G03I-10827J0D01*
G01X1163137Y749794D02*
Y770054D01*
G01X1167074Y749794D02*
G03X1163137Y745857I0J-3937D01*
G01X1167074Y749794D02*
G03X1163137Y745857I0J-3937D01*
G01X1450538Y749794D02*
X1167074D01*
G01X1450538D02*
X1167074D01*
G01X1160972Y802156D02*
Y801182D01*
G01Y793873D02*
Y793386D01*
G01X1193097Y35449D02*
X1196995D01*
G01X1193097Y26787D02*
Y35449D01*
G01X1196995Y26787D02*
X1193097D01*
G01X1188225Y34727D02*
X1189200Y33284D01*
G01X1187251Y35449D02*
X1188225Y34727D01*
G01X1185302Y35449D02*
X1187251D01*
G01X1185302Y26787D02*
Y35449D01*
G01X1187251Y26787D02*
X1185302D01*
G01X1188225Y27509D02*
X1187251Y26787D01*
G01X1188713Y28231D02*
X1188225Y27509D01*
G01X1189200Y28953D02*
X1188713Y28231D01*
G01X1189687Y31118D02*
X1189200Y28953D01*
G01Y33284D02*
X1189687Y31118D01*
G01X1203329D02*
X1200892D01*
G01X1204303Y31840D02*
X1203329Y31118D01*
G01X1204790Y32562D02*
X1204303Y31840D01*
G01X1204790Y34005D02*
Y32562D01*
G01X1204303Y34727D02*
X1204790Y34005D01*
G01X1203329Y35449D02*
X1204303Y34727D01*
G01X1200892Y35449D02*
X1203329D01*
G01X1200892Y26787D02*
Y35449D01*
G01X1203329Y31118D02*
X1204790Y26787D01*
G01X1193097Y31118D02*
X1195533D01*
G01X1188179Y47983D02*
X1192077D01*
G01X1188179Y39321D02*
Y47983D01*
G01X1192077Y39321D02*
X1188179D01*
G01X1187911Y55306D02*
X1185024Y56280D01*
G01X1190076Y54819D02*
X1187911Y55306D01*
G01X1193685Y54332D02*
X1190076Y54819D01*
G01X1185024Y56280D02*
Y52383D01*
G01X1188179Y43652D02*
X1190615D01*
G01X1190076Y62614D02*
X1187911Y63101D01*
G01X1193685Y62127D02*
X1190076Y62614D01*
G01X1185024Y64076D02*
Y60178D01*
G01X1187911Y63101D02*
X1185024Y64076D01*
G01X1192963Y69435D02*
X1193685Y69922D01*
G01Y69435D02*
X1192963D01*
G01X1193685Y69922D02*
Y69435D01*
G01X1192963Y78692D02*
X1193685Y77717D01*
G01X1192242Y79179D02*
X1192963Y78692D01*
G01X1190798Y79666D02*
X1192242Y79179D01*
G01X1187911Y79666D02*
X1190798D01*
G01X1186467Y79179D02*
X1187911Y79666D01*
G01X1185746Y78692D02*
X1186467Y79179D01*
G01X1185024Y77717D02*
X1185746Y78692D01*
G01Y76743D02*
X1185024Y77717D01*
G01X1186467Y76256D02*
X1185746Y76743D01*
G01X1187911Y75769D02*
X1186467Y76256D01*
G01X1190798Y75769D02*
X1187911D01*
G01X1192242Y76256D02*
X1190798Y75769D01*
G01X1192963Y76743D02*
X1192242Y76256D01*
G01X1193685Y77717D02*
X1192963Y76743D01*
G01X1195851Y118969D02*
Y93741D01*
G01X1192963Y86487D02*
X1193685Y85513D01*
G01X1192242Y86974D02*
X1192963Y86487D01*
G01X1190798Y87462D02*
X1192242Y86974D01*
G01X1187911Y87462D02*
X1190798D01*
G01X1186467Y86974D02*
X1187911Y87462D01*
G01X1185746Y86487D02*
X1186467Y86974D01*
G01X1185024Y85513D02*
X1185746Y86487D01*
G01Y84538D02*
X1185024Y85513D01*
G01X1186467Y84051D02*
X1185746Y84538D01*
G01X1187911Y83564D02*
X1186467Y84051D01*
G01X1190798Y83564D02*
X1187911D01*
G01X1192242Y84051D02*
X1190798Y83564D01*
G01X1192963Y84538D02*
X1192242Y84051D01*
G01X1193685Y85513D02*
X1192963Y84538D01*
G01X1199788Y122906D02*
X1278726D01*
G01X1202347D02*
G03I-6496J0D01*
G01X1207662D02*
G03I-11811J0D01*
G01X1192312Y192767D02*
X1192272Y192709D01*
G01X1192337Y192833D02*
X1192312Y192767D01*
G01X1192347Y192906D02*
X1192337Y192833D01*
G01X1192312Y186861D02*
X1192272Y186804D01*
G01X1192337Y186928D02*
X1192312Y186861D01*
G01X1192347Y187000D02*
X1192337Y186928D01*
G01X1192312Y184581D02*
X1192272Y184638D01*
G01X1192337Y184515D02*
X1192312Y184581D01*
G01X1192347Y184441D02*
X1192337Y184515D01*
G01X1192312Y187534D02*
X1192272Y187591D01*
G01X1192337Y187468D02*
X1192312Y187534D01*
G01X1192347Y187394D02*
X1192337Y187468D01*
G01X1192312Y190487D02*
X1192272Y190544D01*
G01X1192337Y190421D02*
X1192312Y190487D01*
G01X1192347Y190347D02*
X1192337Y190421D01*
G01X1192312Y193439D02*
X1192272Y193497D01*
G01X1192337Y193373D02*
X1192312Y193439D01*
G01X1192347Y193300D02*
X1192337Y193373D01*
G01X1203138Y184581D02*
X1203098Y184638D01*
G01X1203164Y184515D02*
X1203138Y184581D01*
G01X1203174Y184441D02*
X1203164Y184515D01*
G01X1203138Y187534D02*
X1203098Y187591D01*
G01X1203164Y187468D02*
X1203138Y187534D01*
G01X1203174Y187394D02*
X1203164Y187468D01*
G01X1203138Y190487D02*
X1203098Y190544D01*
G01X1203164Y190421D02*
X1203138Y190487D01*
G01X1203174Y190347D02*
X1203164Y190421D01*
G01X1203138Y193439D02*
X1203098Y193497D01*
G01X1203164Y193373D02*
X1203138Y193439D01*
G01X1203174Y193300D02*
X1203164Y193373D01*
G01X1204722Y175204D02*
X1204690Y175288D01*
G01X1204742Y175119D02*
X1204722Y175204D01*
G01X1204748Y175032D02*
X1204742Y175119D01*
G01X1192312Y183908D02*
X1192272Y183851D01*
G01X1192337Y183975D02*
X1192312Y183908D01*
G01X1192347Y184048D02*
X1192337Y183975D01*
G01Y189880D02*
X1192347Y189953D01*
G01X1192312Y189814D02*
X1192337Y189880D01*
G01X1192272Y189756D02*
X1192312Y189814D01*
G01X1204742Y174276D02*
X1204748Y174363D01*
G01X1204722Y174191D02*
X1204742Y174276D01*
G01X1204690Y174107D02*
X1204722Y174191D01*
G01X1203164Y192833D02*
X1203174Y192906D01*
G01X1203138Y192767D02*
X1203164Y192833D01*
G01X1203098Y192709D02*
X1203138Y192767D01*
G01X1203164Y189880D02*
X1203174Y189953D01*
G01X1203138Y189814D02*
X1203164Y189880D01*
G01X1203098Y189756D02*
X1203138Y189814D01*
G01X1203164Y186927D02*
X1203174Y187000D01*
G01X1203138Y186861D02*
X1203164Y186927D01*
G01X1203098Y186804D02*
X1203138Y186861D01*
G01X1203164Y183975D02*
X1203174Y184048D01*
G01X1203138Y183908D02*
X1203164Y183975D01*
G01X1203098Y183851D02*
X1203138Y183908D01*
G01X1190044Y173713D02*
G03Y175682I0J984D01*
G01X1186303D02*
G03Y173713I0J-985D01*
G01X1206872Y175268D02*
G03I-1513J0D01*
G01X1192622Y180406D02*
G03X1194197Y178831I1575J0D01*
G01X1186303Y176666D02*
G03Y172729I0J-1969D01*
G01X1190044D02*
G03Y176666I0J1968D01*
G01X1207327Y175268D02*
G03I-1968J0D01*
G01X1192229Y180406D02*
G03X1194197Y178437I1969J0D01*
G01X1207721Y175268D02*
G03I-2362J0D01*
G01X1208114D02*
G03I-2755J0D01*
G01X1187642Y181948D02*
X1185380Y181210D01*
G01X1185045Y181128D02*
X1184040Y180800D01*
G01X1187977Y181620D02*
X1184040Y180308D01*
G01X1187977Y184737D02*
X1187390Y184245D01*
G01X1187307Y184737D02*
X1186720Y184245D01*
G01X1197622Y180603D02*
X1196189Y179170D01*
G01X1192701Y175780D02*
X1192307Y175386D01*
G01X1184433Y177847D02*
X1185024Y178437D01*
G01X1185811Y179225D02*
X1185418Y178831D01*
G01X1205890Y184835D02*
Y183654D01*
G01Y187788D02*
Y186607D01*
G01Y190741D02*
Y189560D01*
G01Y193693D02*
Y192512D01*
G01X1204748Y175032D02*
Y174363D01*
G01X1204709Y192650D02*
Y193556D01*
G01Y189697D02*
Y190603D01*
G01Y186745D02*
Y187650D01*
G01Y183792D02*
Y184697D01*
G01X1204670Y184638D02*
Y183851D01*
G01Y187591D02*
Y186804D01*
G01Y193497D02*
Y192709D01*
G01X1204473Y190544D02*
Y189756D01*
G01X1204276Y184638D02*
Y183851D01*
G01Y187591D02*
Y186804D01*
G01Y190544D02*
Y189756D01*
G01Y193497D02*
Y192709D01*
G01X1204217Y179619D02*
Y177847D01*
G01X1203922Y179815D02*
Y178437D01*
G01X1203779Y183654D02*
Y179170D01*
G01Y186607D02*
Y184835D01*
G01Y189560D02*
Y187788D01*
G01Y192512D02*
Y190741D01*
G01Y195465D02*
Y193693D01*
G01X1203740Y174107D02*
Y175288D01*
G01X1203272Y184934D02*
Y183556D01*
G01Y187886D02*
Y186508D01*
G01Y190839D02*
Y189461D01*
G01Y193792D02*
Y192414D01*
G01X1203174Y189953D02*
Y190347D01*
G01Y184441D02*
Y184048D01*
G01Y187394D02*
Y187000D01*
G01Y193300D02*
Y192906D01*
G01X1203126Y175288D02*
Y174107D01*
G01X1202977Y190544D02*
Y189756D01*
G01X1202780Y184638D02*
Y183851D01*
G01Y187591D02*
Y186804D01*
G01Y193497D02*
Y192709D01*
G01X1202775Y189756D02*
Y190544D01*
G01X1202664Y192709D02*
Y193497D01*
G01Y186804D02*
Y187591D01*
G01Y183851D02*
Y184638D01*
G01X1202583D02*
Y183851D01*
G01Y187591D02*
Y186804D01*
G01Y190544D02*
Y189756D01*
G01Y193497D02*
Y192709D01*
G01X1202347D02*
Y193497D01*
G01Y186804D02*
Y187591D01*
G01Y183851D02*
Y184638D01*
G01Y183654D02*
Y180603D01*
G01Y186607D02*
Y184835D01*
G01Y190544D02*
Y189756D01*
G01Y189560D02*
Y187788D01*
G01Y192512D02*
Y190741D01*
G01Y195465D02*
Y193693D01*
G01X1202313Y184638D02*
Y183851D01*
G01Y187591D02*
Y186804D01*
G01Y190544D02*
Y189756D01*
G01Y193497D02*
Y192709D01*
G01X1202189Y189756D02*
Y190544D01*
G01Y184638D02*
Y183851D01*
G01Y187591D02*
Y186804D01*
G01Y193497D02*
Y192709D01*
G01X1202151D02*
Y193497D01*
G01Y186804D02*
Y187591D01*
G01Y183851D02*
Y184638D01*
G01X1202149Y189756D02*
Y190544D01*
G01X1201973Y192709D02*
Y193497D01*
G01Y189756D02*
Y190544D01*
G01Y186804D02*
Y187591D01*
G01Y183851D02*
Y184638D01*
G01X1201738Y192709D02*
Y193497D01*
G01Y189756D02*
Y190544D01*
G01Y186804D02*
Y187591D01*
G01Y183851D02*
Y184638D01*
G01X1201451D02*
Y183851D01*
G01Y187591D02*
Y186804D01*
G01Y190544D02*
Y189756D01*
G01Y193497D02*
Y192709D01*
G01X1201204D02*
Y193497D01*
G01Y186804D02*
Y187591D01*
G01Y183851D02*
Y184638D01*
G01X1201201Y189756D02*
Y190544D01*
G01X1201013D02*
Y189756D01*
G01X1200927Y184638D02*
Y183851D01*
G01Y187591D02*
Y186804D01*
G01Y193497D02*
Y192709D01*
G01X1200870D02*
Y193497D01*
G01Y189756D02*
Y190544D01*
G01Y186804D02*
Y187591D01*
G01Y183851D02*
Y184638D01*
G01X1200648Y192709D02*
Y193497D01*
G01Y186804D02*
Y187591D01*
G01Y183851D02*
Y184638D01*
G01X1200526Y189756D02*
Y190544D01*
G01X1199630Y189756D02*
Y190544D01*
G01Y184638D02*
Y183851D01*
G01Y187591D02*
Y186804D01*
G01Y193497D02*
Y192709D01*
G01X1199099Y189756D02*
Y190544D01*
G01Y184638D02*
Y183851D01*
G01Y187591D02*
Y186804D01*
G01Y193497D02*
Y192709D01*
G01X1199040Y174008D02*
Y173221D01*
G01Y176174D02*
Y175386D01*
G01X1198768Y190544D02*
Y189756D01*
G01X1198765Y184638D02*
Y183851D01*
G01Y187591D02*
Y186804D01*
G01Y193497D02*
Y192709D01*
G01X1198548Y192414D02*
Y193792D01*
G01Y189461D02*
Y190839D01*
G01Y186508D02*
Y187886D01*
G01Y183556D02*
Y184934D01*
G01X1198518Y192709D02*
Y193497D01*
G01Y189756D02*
Y190544D01*
G01Y186804D02*
Y187591D01*
G01Y183851D02*
Y184638D01*
G01X1198231D02*
Y183851D01*
G01Y187591D02*
Y186804D01*
G01Y190544D02*
Y189756D01*
G01Y193497D02*
Y192709D01*
G01X1197996Y189756D02*
Y190544D01*
G01Y184638D02*
Y183851D01*
G01Y187591D02*
Y186804D01*
G01Y193497D02*
Y192709D01*
G01X1197820Y190544D02*
Y189756D01*
G01X1197818Y184638D02*
Y183851D01*
G01Y187591D02*
Y186804D01*
G01Y193497D02*
Y192709D01*
G01X1197656D02*
Y193497D01*
G01Y189756D02*
Y190544D01*
G01Y186804D02*
Y187591D01*
G01Y183851D02*
Y184638D01*
G01X1197622Y183654D02*
Y180603D01*
G01Y184638D02*
Y183851D01*
G01Y186607D02*
Y184835D01*
G01Y187591D02*
Y186804D01*
G01Y190544D02*
Y189756D01*
G01Y189560D02*
Y187788D01*
G01Y193497D02*
Y192709D01*
G01Y192512D02*
Y190741D01*
G01Y195465D02*
Y193693D01*
G01X1196189D02*
Y195465D01*
G01Y190741D02*
Y192512D01*
G01Y187788D02*
Y189560D01*
G01Y184835D02*
Y186607D01*
G01Y179170D02*
Y183654D01*
G01X1195260Y184697D02*
Y183792D01*
G01Y187650D02*
Y186745D01*
G01Y190603D02*
Y189697D01*
G01Y193556D02*
Y192650D01*
G01X1194197Y178437D02*
Y178831D01*
G01X1194079Y184835D02*
Y183654D01*
G01Y187788D02*
Y186607D01*
G01Y190741D02*
Y189560D01*
G01Y193693D02*
Y192512D01*
G01X1193685Y184638D02*
Y183851D01*
G01Y187591D02*
Y186804D01*
G01Y193497D02*
Y192709D01*
G01X1193646Y190544D02*
Y189756D01*
G01X1193449Y192709D02*
Y193497D01*
G01Y186804D02*
Y187591D01*
G01Y183851D02*
Y184638D01*
G01Y190544D02*
Y189756D01*
G01X1193095Y176843D02*
Y172119D01*
G01X1192701Y175780D02*
Y173615D01*
G01X1192642Y184934D02*
Y183556D01*
G01Y187886D02*
Y186508D01*
G01Y190839D02*
Y189461D01*
G01Y193792D02*
Y192414D01*
G01X1192622Y211705D02*
Y180406D01*
G01X1192603Y174107D02*
Y175288D01*
G01X1192347Y192906D02*
Y193300D01*
G01Y189953D02*
Y190347D01*
G01Y187000D02*
Y187394D01*
G01Y184048D02*
Y184441D01*
G01X1192307Y175386D02*
Y174008D01*
G01X1192288Y174107D02*
Y175288D01*
G01X1192229Y213674D02*
Y178437D01*
G01X1192209Y175288D02*
Y174107D01*
G01X1192150Y190544D02*
Y189756D01*
G01X1192111Y184638D02*
Y183851D01*
G01Y187591D02*
Y186804D01*
G01Y193497D02*
Y192709D01*
G01X1192102Y174107D02*
Y175288D01*
G01X1191995Y192709D02*
Y193497D01*
G01Y186804D02*
Y187591D01*
G01Y183851D02*
Y184638D01*
G01X1191948Y189756D02*
Y190544D01*
G01X1191815Y175288D02*
Y174107D01*
G01X1191756Y184638D02*
Y183851D01*
G01Y187591D02*
Y186804D01*
G01Y190544D02*
Y189756D01*
G01Y193497D02*
Y192709D01*
G01X1191639Y174107D02*
Y175288D01*
G01X1191638Y178437D02*
Y213674D01*
G01X1191461Y174107D02*
Y175288D01*
G01X1191363Y192709D02*
Y193497D01*
G01Y189756D02*
Y190544D01*
G01Y186804D02*
Y187591D01*
G01Y183851D02*
Y184638D01*
G01X1191323Y182827D02*
Y182768D01*
G01Y183359D02*
Y183260D01*
G01Y185229D02*
Y185130D01*
G01Y185780D02*
Y185662D01*
G01Y186312D02*
Y186213D01*
G01Y188733D02*
Y188615D01*
G01Y188182D02*
Y188083D01*
G01Y189264D02*
Y189166D01*
G01Y191686D02*
Y191567D01*
G01Y191134D02*
Y191036D01*
G01Y192217D02*
Y192119D01*
G01Y194087D02*
Y193989D01*
G01X1190831Y175386D02*
Y174008D01*
G01X1190634Y175288D02*
Y174107D01*
G01X1190186Y190544D02*
Y189756D01*
G01X1190142Y175288D02*
Y174107D01*
G01X1190100Y184638D02*
Y183851D01*
G01Y187591D02*
Y186804D01*
G01Y193497D02*
Y192709D01*
G01X1189822D02*
Y193497D01*
G01Y186804D02*
Y187591D01*
G01Y183851D02*
Y184638D01*
G01X1189699Y189756D02*
Y190544D01*
G01X1189256Y189264D02*
Y189166D01*
G01Y191134D02*
Y191036D01*
G01X1189158Y175288D02*
Y174107D01*
G01X1188961D02*
Y175288D01*
G01X1188823Y183359D02*
Y183260D01*
G01Y185229D02*
Y185130D01*
G01Y186312D02*
Y186213D01*
G01Y188182D02*
Y188083D01*
G01Y192217D02*
Y192119D01*
G01Y194087D02*
Y193989D01*
G01X1188803Y192709D02*
Y193497D01*
G01Y189756D02*
Y190544D01*
G01Y186804D02*
Y187591D01*
G01Y183851D02*
Y184638D01*
G01X1188567Y178437D02*
Y181390D01*
G01X1187977Y182276D02*
Y181620D01*
G01Y185229D02*
Y184737D01*
G01X1187918Y192414D02*
Y193792D01*
G01Y189461D02*
Y190839D01*
G01Y186508D02*
Y187886D01*
G01Y183556D02*
Y184934D01*
G01X1187386Y175288D02*
Y174107D01*
G01X1187189Y175288D02*
Y174107D01*
G01X1186992Y199697D02*
Y192414D01*
G01X1186402Y210721D02*
Y181390D01*
G01X1186205Y175288D02*
Y174107D01*
G01Y199697D02*
Y192414D01*
G01X1185811Y179225D02*
Y192119D01*
G01X1185713Y175288D02*
Y174107D01*
G01X1185516Y175386D02*
Y174008D01*
G01X1185418Y175288D02*
Y174107D01*
G01X1185380Y182686D02*
Y181210D01*
G01X1185045Y182768D02*
Y181128D01*
G01X1185024Y176174D02*
Y173221D01*
G01Y213674D02*
Y178437D01*
G01X1184433Y176843D02*
Y172119D01*
G01Y192414D02*
Y177847D01*
G01X1184040Y180800D02*
Y180308D01*
G01Y183589D02*
Y183097D01*
G01Y185229D02*
Y184737D01*
G01X1183843Y172119D02*
Y176843D01*
G01X1203779Y179170D02*
X1202347Y180603D01*
G01X1192307Y174008D02*
X1192701Y173615D01*
G01X1185024Y179225D02*
X1185811Y178437D01*
G01X1187977Y182276D02*
X1184040Y183589D01*
G01X1187642Y181948D02*
X1185380Y182686D01*
G01X1185045Y182768D02*
X1184040Y183097D01*
G01X1191323Y194087D02*
X1188823D01*
G01X1191323Y193989D02*
X1188823D01*
G01X1198548Y193792D02*
X1203272D01*
G01X1187918D02*
X1192642D01*
G01X1197622Y193693D02*
X1194079D01*
G01X1205890D02*
X1202347D01*
G01X1204709Y193556D02*
X1195260D01*
G01X1199630Y193497D02*
X1204670D01*
G01X1197622D02*
X1199090D01*
G01X1193685D02*
X1188803D01*
G01X1193449Y193300D02*
X1192347D01*
G01X1204276D02*
X1203174D01*
G01Y192906D02*
X1204276D01*
G01X1192347D02*
X1193449D01*
G01X1199630Y192709D02*
X1204670D01*
G01X1197622D02*
X1199090D01*
G01X1188803D02*
X1193685D01*
G01X1195260Y192650D02*
X1204709D01*
G01X1197622Y192512D02*
X1194079D01*
G01X1205890D02*
X1202347D01*
G01X1184433Y192414D02*
X1186992D01*
G01X1192642D02*
X1187918D01*
G01X1203272D02*
X1198548D01*
G01X1191323Y192217D02*
X1188823D01*
G01X1185024Y192119D02*
X1186402D01*
G01X1191323D02*
X1188823D01*
G01X1191323Y191686D02*
X1224394D01*
G01Y191567D02*
X1191323D01*
G01Y191134D02*
X1189256D01*
G01Y191036D02*
X1191323D01*
G01X1198548Y190839D02*
X1203272D01*
G01X1187918D02*
X1192642D01*
G01X1197622Y190741D02*
X1194079D01*
G01X1205890D02*
X1202347D01*
G01X1204709Y190603D02*
X1195260D01*
G01X1199630Y190544D02*
X1204473D01*
G01X1197622D02*
X1199089D01*
G01X1188803D02*
X1193646D01*
G01X1203174Y190347D02*
X1204276D01*
G01X1192347D02*
X1193449D01*
G01Y189953D02*
X1192347D01*
G01X1204276D02*
X1203174D01*
G01X1199630Y189756D02*
X1204473D01*
G01X1197622D02*
X1199089D01*
G01X1188803D02*
X1193646D01*
G01X1195260Y189697D02*
X1204709D01*
G01X1197622Y189560D02*
X1194079D01*
G01X1205890D02*
X1202347D01*
G01X1192642Y189461D02*
X1187918D01*
G01X1203272D02*
X1198548D01*
G01X1189256Y189264D02*
X1191323D01*
G01Y189166D02*
X1189256D01*
G01X1191323Y188733D02*
X1224394D01*
G01Y188615D02*
X1191323D01*
G01Y188182D02*
X1188823D01*
G01X1191323Y188083D02*
X1188823D01*
G01X1198548Y187886D02*
X1203272D01*
G01X1187918D02*
X1192642D01*
G01X1197622Y187788D02*
X1194079D01*
G01X1205890D02*
X1202347D01*
G01X1204709Y187650D02*
X1195260D01*
G01X1199630Y187591D02*
X1204670D01*
G01X1197622D02*
X1199090D01*
G01X1193685D02*
X1188803D01*
G01X1193449Y187394D02*
X1192347D01*
G01X1204276D02*
X1203174D01*
G01Y187000D02*
X1204276D01*
G01X1192347D02*
X1193449D01*
G01X1199630Y186804D02*
X1204670D01*
G01X1197622D02*
X1199090D01*
G01X1188803D02*
X1193685D01*
G01X1195260Y186745D02*
X1204709D01*
G01X1197622Y186607D02*
X1194079D01*
G01X1205890D02*
X1202347D01*
G01X1192642Y186508D02*
X1187918D01*
G01X1203272D02*
X1198548D01*
G01X1191323Y186312D02*
X1188823D01*
G01X1191323Y186213D02*
X1188823D01*
G01X1191323Y185780D02*
X1224394D01*
G01Y185662D02*
X1191323D01*
G01X1187977Y185229D02*
X1184040D01*
G01X1191323D02*
X1188823D01*
G01X1191323Y185130D02*
X1188823D01*
G01X1198548Y184934D02*
X1203272D01*
G01X1187918D02*
X1192642D01*
G01X1197622Y184835D02*
X1194079D01*
G01X1205890D02*
X1202347D01*
G01X1187307Y184737D02*
X1184040D01*
G01X1204709Y184697D02*
X1195260D01*
G01X1199630Y184638D02*
X1204670D01*
G01X1197622D02*
X1199090D01*
G01X1193685D02*
X1188803D01*
G01X1193449Y184441D02*
X1192347D01*
G01X1204276D02*
X1203174D01*
G01X1187390Y184245D02*
X1186720D01*
G01X1203174Y184048D02*
X1204276D01*
G01X1192347D02*
X1193449D01*
G01X1199630Y183851D02*
X1204670D01*
G01X1197622D02*
X1199090D01*
G01X1188803D02*
X1193685D01*
G01X1195260Y183792D02*
X1204709D01*
G01X1197622Y183654D02*
X1194079D01*
G01X1205890D02*
X1202347D01*
G01X1192642Y183556D02*
X1187918D01*
G01X1203272D02*
X1198548D01*
G01X1191323Y183359D02*
X1188823D01*
G01X1191323Y183260D02*
X1188823D01*
G01X1191323Y182827D02*
X1224394D01*
G01Y182768D02*
X1191323D01*
G01X1188567Y181390D02*
X1185024D01*
G01X1202347Y180603D02*
X1197622D01*
G01X1192622Y180406D02*
X1192229D01*
G01X1211796Y179815D02*
X1203922D01*
G01X1211500Y179619D02*
X1204217D01*
G01X1185811Y179225D02*
X1192622D01*
G01X1203779Y179170D02*
X1196189D01*
G01X1194197Y178831D02*
X1203922D01*
G01X1185024Y178437D02*
X1229512D01*
G01X1184433Y177847D02*
X1204217D01*
G01X1190044Y176666D02*
X1186303D01*
G01X1185024Y176174D02*
X1199040D01*
G01X1185024Y175780D02*
X1226441D01*
G01X1190044Y175682D02*
X1186303D01*
G01X1192307Y175386D02*
X1185024D01*
G01X1212426D02*
X1199040D01*
G01X1185024Y175288D02*
X1226441D01*
G01X1206717Y175032D02*
X1204748D01*
G01Y174363D02*
X1206717D01*
G01X1185024Y174107D02*
X1226441D01*
G01X1192307Y174008D02*
X1185024D01*
G01X1212426D02*
X1199040D01*
G01X1186303Y173713D02*
X1190044D01*
G01X1226441Y173615D02*
X1185024D01*
G01X1199040Y173221D02*
X1185024D01*
G01X1186303Y172729D02*
X1190044D01*
G01X1192312Y204578D02*
X1192272Y204520D01*
G01X1192337Y204644D02*
X1192312Y204578D01*
G01X1192347Y204717D02*
X1192337Y204644D01*
G01X1192312Y201625D02*
X1192272Y201567D01*
G01X1192337Y201691D02*
X1192312Y201625D01*
G01X1192347Y201764D02*
X1192337Y201691D01*
G01X1192312Y195719D02*
X1192272Y195662D01*
G01X1192337Y195786D02*
X1192312Y195719D01*
G01X1192347Y195859D02*
X1192337Y195786D01*
G01X1192312Y196392D02*
X1192272Y196449D01*
G01X1192337Y196326D02*
X1192312Y196392D01*
G01X1192347Y196252D02*
X1192337Y196326D01*
G01X1192312Y199345D02*
X1192272Y199402D01*
G01X1192337Y199279D02*
X1192312Y199345D01*
G01X1192347Y199205D02*
X1192337Y199279D01*
G01X1192312Y202298D02*
X1192272Y202355D01*
G01X1192337Y202232D02*
X1192312Y202298D01*
G01X1192347Y202158D02*
X1192337Y202232D01*
G01X1192312Y205250D02*
X1192272Y205308D01*
G01X1192337Y205184D02*
X1192312Y205250D01*
G01X1192347Y205111D02*
X1192337Y205184D01*
G01X1192312Y208203D02*
X1192272Y208260D01*
G01X1192337Y208137D02*
X1192312Y208203D01*
G01X1192347Y208063D02*
X1192337Y208137D01*
G01X1203138Y196392D02*
X1203098Y196449D01*
G01X1203164Y196326D02*
X1203138Y196392D01*
G01X1203174Y196252D02*
X1203164Y196326D01*
G01X1203138Y199345D02*
X1203098Y199402D01*
G01X1203164Y199279D02*
X1203138Y199345D01*
G01X1203174Y199205D02*
X1203164Y199279D01*
G01X1203138Y202298D02*
X1203098Y202355D01*
G01X1203164Y202232D02*
X1203138Y202298D01*
G01X1203174Y202158D02*
X1203164Y202232D01*
G01X1204742Y216993D02*
X1204748Y217079D01*
G01X1204722Y216908D02*
X1204742Y216993D01*
G01X1204690Y216823D02*
X1204722Y216908D01*
G01X1192337Y207597D02*
X1192347Y207670D01*
G01X1192312Y207530D02*
X1192337Y207597D01*
G01X1192272Y207473D02*
X1192312Y207530D01*
G01X1192337Y198738D02*
X1192347Y198812D01*
G01X1192312Y198672D02*
X1192337Y198738D01*
G01X1192272Y198615D02*
X1192312Y198672D01*
G01X1203164Y207597D02*
X1203174Y207670D01*
G01X1203138Y207530D02*
X1203164Y207597D01*
G01X1203098Y207473D02*
X1203138Y207530D01*
G01X1203164Y204644D02*
X1203174Y204717D01*
G01X1203138Y204578D02*
X1203164Y204644D01*
G01X1203098Y204520D02*
X1203138Y204578D01*
G01X1203164Y201691D02*
X1203174Y201764D01*
G01X1203138Y201625D02*
X1203164Y201691D01*
G01X1203098Y201567D02*
X1203138Y201625D01*
G01Y205250D02*
X1203098Y205308D01*
G01X1203164Y205184D02*
X1203138Y205250D01*
G01X1203174Y205111D02*
X1203164Y205184D01*
G01X1203138Y208203D02*
X1203098Y208260D01*
G01X1203164Y208137D02*
X1203138Y208203D01*
G01X1203174Y208063D02*
X1203164Y208137D01*
G01Y198738D02*
X1203174Y198812D01*
G01X1203138Y198672D02*
X1203164Y198738D01*
G01X1203098Y198615D02*
X1203138Y198672D01*
G01X1203164Y195786D02*
X1203174Y195859D01*
G01X1203138Y195719D02*
X1203164Y195786D01*
G01X1203098Y195662D02*
X1203138Y195719D01*
G01X1186303Y218398D02*
G03Y216430I0J-984D01*
G01X1190044D02*
G03Y218398I0J984D01*
G01X1206872Y216843D02*
G03I-1513J0D01*
G01X1194197Y213280D02*
G03X1192622Y211705I0J-1575D01*
G01X1190044Y215445D02*
G03Y219382I0J1969D01*
G01X1186303D02*
G03Y215445I0J-1968D01*
G01X1207327Y216843D02*
G03I-1968J0D01*
G01X1194197Y213674D02*
G03X1192229Y211705I0J-1968D01*
G01X1207721Y216843D02*
G03I-2362J0D01*
G01X1208114D02*
G03I-2755J0D01*
G01X1203779Y212941D02*
X1202347Y211508D01*
G01X1185811Y213674D02*
X1185024Y212886D01*
G01X1205890Y196646D02*
Y195465D01*
G01Y199599D02*
Y198418D01*
G01Y202552D02*
Y201371D01*
G01Y205504D02*
Y204323D01*
G01Y208457D02*
Y207276D01*
G01X1204748Y217749D02*
Y217079D01*
G01X1204709Y207414D02*
Y208319D01*
G01Y204461D02*
Y205367D01*
G01Y201508D02*
Y202414D01*
G01Y198556D02*
Y199461D01*
G01Y195603D02*
Y196508D01*
G01X1204670Y196449D02*
Y195662D01*
G01Y202355D02*
Y201567D01*
G01Y205308D02*
Y204520D01*
G01X1204473Y199402D02*
Y198615D01*
G01Y208260D02*
Y207473D01*
G01X1204276Y196449D02*
Y195662D01*
G01Y199402D02*
Y198615D01*
G01Y202355D02*
Y201567D01*
G01Y205308D02*
Y204520D01*
G01Y208260D02*
Y207473D01*
G01X1204217Y214264D02*
Y212493D01*
G01X1203922Y213674D02*
Y212296D01*
G01X1203779Y198418D02*
Y196646D01*
G01Y201371D02*
Y199599D01*
G01Y204323D02*
Y202552D01*
G01Y207276D02*
Y205504D01*
G01Y212941D02*
Y208457D01*
G01X1203740Y216823D02*
Y218004D01*
G01X1203272Y196745D02*
Y195367D01*
G01Y199697D02*
Y198319D01*
G01Y202650D02*
Y201272D01*
G01Y205603D02*
Y204225D01*
G01Y208556D02*
Y207178D01*
G01X1203174Y207670D02*
Y208063D01*
G01Y198812D02*
Y199205D01*
G01Y196252D02*
Y195859D01*
G01Y202158D02*
Y201764D01*
G01Y205111D02*
Y204717D01*
G01X1203126Y218004D02*
Y216823D01*
G01X1202977Y199402D02*
Y198615D01*
G01Y208260D02*
Y207473D01*
G01X1202780Y196449D02*
Y195662D01*
G01Y202355D02*
Y201567D01*
G01Y205308D02*
Y204520D01*
G01X1202775Y207473D02*
Y208260D01*
G01Y198615D02*
Y199402D01*
G01X1202664Y204520D02*
Y205308D01*
G01Y201567D02*
Y202355D01*
G01Y195662D02*
Y196449D01*
G01X1202583D02*
Y195662D01*
G01Y199402D02*
Y198615D01*
G01Y202355D02*
Y201567D01*
G01Y205308D02*
Y204520D01*
G01Y208260D02*
Y207473D01*
G01X1202347Y204520D02*
Y205308D01*
G01Y201567D02*
Y202355D01*
G01Y195662D02*
Y196449D01*
G01Y198418D02*
Y196646D01*
G01Y199402D02*
Y198615D01*
G01Y201371D02*
Y199599D01*
G01Y204323D02*
Y202552D01*
G01Y208260D02*
Y207473D01*
G01Y207276D02*
Y205504D01*
G01Y211508D02*
Y208457D01*
G01X1202313Y196449D02*
Y195662D01*
G01Y199402D02*
Y198615D01*
G01Y202355D02*
Y201567D01*
G01Y205308D02*
Y204520D01*
G01Y208260D02*
Y207473D01*
G01X1202189D02*
Y208260D01*
G01Y198615D02*
Y199402D01*
G01Y196449D02*
Y195662D01*
G01Y202355D02*
Y201567D01*
G01Y205308D02*
Y204520D01*
G01X1202151D02*
Y205308D01*
G01Y201567D02*
Y202355D01*
G01Y195662D02*
Y196449D01*
G01X1202149Y207473D02*
Y208260D01*
G01Y198615D02*
Y199402D01*
G01X1201973Y207473D02*
Y208260D01*
G01Y204520D02*
Y205308D01*
G01Y201567D02*
Y202355D01*
G01Y198615D02*
Y199402D01*
G01Y195662D02*
Y196449D01*
G01X1201738Y207473D02*
Y208260D01*
G01Y204520D02*
Y205308D01*
G01Y201567D02*
Y202355D01*
G01Y198615D02*
Y199402D01*
G01Y195662D02*
Y196449D01*
G01X1201451D02*
Y195662D01*
G01Y199402D02*
Y198615D01*
G01Y202355D02*
Y201567D01*
G01Y205308D02*
Y204520D01*
G01Y208260D02*
Y207473D01*
G01X1201204Y204520D02*
Y205308D01*
G01Y201567D02*
Y202355D01*
G01Y195662D02*
Y196449D01*
G01X1201201Y207473D02*
Y208260D01*
G01Y198615D02*
Y199402D01*
G01X1201013D02*
Y198615D01*
G01Y208260D02*
Y207473D01*
G01X1200927Y196449D02*
Y195662D01*
G01Y202355D02*
Y201567D01*
G01Y205308D02*
Y204520D01*
G01X1200870Y207473D02*
Y208260D01*
G01Y204520D02*
Y205308D01*
G01Y201567D02*
Y202355D01*
G01Y198615D02*
Y199402D01*
G01Y195662D02*
Y196449D01*
G01X1200648Y204520D02*
Y205308D01*
G01Y201567D02*
Y202355D01*
G01Y195662D02*
Y196449D01*
G01X1200526Y207473D02*
Y208260D01*
G01Y198615D02*
Y199402D01*
G01X1199630Y207473D02*
Y208260D01*
G01Y198615D02*
Y199402D01*
G01Y196449D02*
Y195662D01*
G01Y202355D02*
Y201567D01*
G01Y205308D02*
Y204520D01*
G01X1199099Y207473D02*
Y208260D01*
G01Y198615D02*
Y199402D01*
G01Y196449D02*
Y195662D01*
G01Y202355D02*
Y201567D01*
G01Y205308D02*
Y204520D01*
G01X1199040Y216725D02*
Y215937D01*
G01X1198768Y199402D02*
Y198615D01*
G01Y208260D02*
Y207473D01*
G01X1198765Y196449D02*
Y195662D01*
G01Y202355D02*
Y201567D01*
G01Y205308D02*
Y204520D01*
G01X1198548Y207178D02*
Y208556D01*
G01Y204225D02*
Y205603D01*
G01Y201272D02*
Y202650D01*
G01Y198319D02*
Y199697D01*
G01Y195367D02*
Y196745D01*
G01X1198518Y207473D02*
Y208260D01*
G01Y204520D02*
Y205308D01*
G01Y201567D02*
Y202355D01*
G01Y198615D02*
Y199402D01*
G01Y195662D02*
Y196449D01*
G01X1198231D02*
Y195662D01*
G01Y199402D02*
Y198615D01*
G01Y202355D02*
Y201567D01*
G01Y205308D02*
Y204520D01*
G01Y208260D02*
Y207473D01*
G01X1197996D02*
Y208260D01*
G01Y198615D02*
Y199402D01*
G01Y196449D02*
Y195662D01*
G01Y202355D02*
Y201567D01*
G01Y205308D02*
Y204520D01*
G01X1197820Y199402D02*
Y198615D01*
G01Y208260D02*
Y207473D01*
G01X1197818Y196449D02*
Y195662D01*
G01Y202355D02*
Y201567D01*
G01Y205308D02*
Y204520D01*
G01X1197656Y207473D02*
Y208260D01*
G01Y204520D02*
Y205308D01*
G01Y201567D02*
Y202355D01*
G01Y198615D02*
Y199402D01*
G01Y195662D02*
Y196449D01*
G01X1197622D02*
Y195662D01*
G01Y198418D02*
Y196646D01*
G01Y199402D02*
Y198615D01*
G01Y201371D02*
Y199599D01*
G01Y202355D02*
Y201567D01*
G01Y205308D02*
Y204520D01*
G01Y204323D02*
Y202552D01*
G01Y208260D02*
Y207473D01*
G01Y207276D02*
Y205504D01*
G01Y211508D02*
Y208457D01*
G01X1196189D02*
Y212941D01*
G01Y205504D02*
Y207276D01*
G01Y202552D02*
Y204323D01*
G01Y199599D02*
Y201371D01*
G01Y196646D02*
Y198418D01*
G01X1195260Y196508D02*
Y195603D01*
G01Y199461D02*
Y198556D01*
G01Y202414D02*
Y201508D01*
G01Y205367D02*
Y204461D01*
G01Y208319D02*
Y207414D01*
G01X1194197Y213280D02*
Y213674D01*
G01X1194079Y196646D02*
Y195465D01*
G01Y199599D02*
Y198418D01*
G01Y202552D02*
Y201371D01*
G01Y205504D02*
Y204323D01*
G01Y208457D02*
Y207276D01*
G01X1193685Y196449D02*
Y195662D01*
G01Y202355D02*
Y201567D01*
G01Y205308D02*
Y204520D01*
G01X1193646Y199402D02*
Y198615D01*
G01Y208260D02*
Y207473D01*
G01X1193449Y204520D02*
Y205308D01*
G01Y201567D02*
Y202355D01*
G01Y195662D02*
Y196449D01*
G01Y199402D02*
Y198615D01*
G01Y208260D02*
Y207473D01*
G01X1193095Y219993D02*
Y215268D01*
G01X1192701Y218497D02*
Y216331D01*
G01X1192642Y196745D02*
Y195367D01*
G01Y199697D02*
Y198319D01*
G01Y202650D02*
Y201272D01*
G01Y205603D02*
Y204225D01*
G01Y208556D02*
Y207178D01*
G01X1192603Y216823D02*
Y218004D01*
G01X1192347Y207670D02*
Y208063D01*
G01Y204717D02*
Y205111D01*
G01Y201764D02*
Y202158D01*
G01Y198812D02*
Y199205D01*
G01Y195859D02*
Y196252D01*
G01X1192307Y218103D02*
Y216725D01*
G01X1192288Y216823D02*
Y218004D01*
G01X1192209D02*
Y216823D01*
G01X1192150Y199402D02*
Y198615D01*
G01Y208260D02*
Y207473D01*
G01X1192111Y196449D02*
Y195662D01*
G01Y202355D02*
Y201567D01*
G01Y205308D02*
Y204520D01*
G01X1192102Y216823D02*
Y218004D01*
G01X1191995Y204520D02*
Y205308D01*
G01Y201567D02*
Y202355D01*
G01Y195662D02*
Y196449D01*
G01X1191948Y207473D02*
Y208260D01*
G01Y198615D02*
Y199402D01*
G01X1191815Y218004D02*
Y216823D01*
G01X1191756Y196449D02*
Y195662D01*
G01Y199402D02*
Y198615D01*
G01Y202355D02*
Y201567D01*
G01Y205308D02*
Y204520D01*
G01Y208260D02*
Y207473D01*
G01X1191639Y216823D02*
Y218004D01*
G01X1191461Y216823D02*
Y218004D01*
G01X1191363Y207473D02*
Y208260D01*
G01Y204520D02*
Y205308D01*
G01Y201567D02*
Y202355D01*
G01Y198615D02*
Y199402D01*
G01Y195662D02*
Y196449D01*
G01X1191323Y194638D02*
Y194520D01*
G01Y195170D02*
Y195071D01*
G01Y197040D02*
Y196941D01*
G01Y197591D02*
Y197473D01*
G01Y198123D02*
Y198024D01*
G01Y200544D02*
Y200426D01*
G01Y199993D02*
Y199894D01*
G01Y201075D02*
Y200977D01*
G01Y203497D02*
Y203378D01*
G01Y202945D02*
Y202847D01*
G01Y204028D02*
Y203930D01*
G01Y206449D02*
Y206331D01*
G01Y206981D02*
Y206882D01*
G01Y205898D02*
Y205800D01*
G01Y208851D02*
Y208752D01*
G01Y209343D02*
Y209284D01*
G01X1190831Y218103D02*
Y216725D01*
G01X1190634Y218004D02*
Y216823D01*
G01X1190186Y199402D02*
Y198615D01*
G01Y208260D02*
Y207473D01*
G01X1190142Y218004D02*
Y216823D01*
G01X1190100Y196449D02*
Y195662D01*
G01Y202355D02*
Y201567D01*
G01Y205308D02*
Y204520D01*
G01X1189822D02*
Y205308D01*
G01Y201567D02*
Y202355D01*
G01Y195662D02*
Y196449D01*
G01X1189699Y207473D02*
Y208260D01*
G01Y198615D02*
Y199402D01*
G01X1189256Y198123D02*
Y198024D01*
G01Y199993D02*
Y199894D01*
G01Y206981D02*
Y206882D01*
G01Y208851D02*
Y208752D01*
G01X1189158Y218004D02*
Y216823D01*
G01X1188961D02*
Y218004D01*
G01X1188823Y195170D02*
Y195071D01*
G01Y197040D02*
Y196941D01*
G01Y201075D02*
Y200977D01*
G01Y202945D02*
Y202847D01*
G01Y204028D02*
Y203930D01*
G01Y205898D02*
Y205800D01*
G01X1188803Y207473D02*
Y208260D01*
G01Y204520D02*
Y205308D01*
G01Y201567D02*
Y202355D01*
G01Y198615D02*
Y199402D01*
G01Y195662D02*
Y196449D01*
G01X1188567Y210721D02*
Y213674D01*
G01X1187918Y207178D02*
Y208556D01*
G01Y204225D02*
Y205603D01*
G01Y201272D02*
Y202650D01*
G01Y198319D02*
Y199697D01*
G01Y195367D02*
Y196745D01*
G01X1187386Y218004D02*
Y216823D01*
G01X1187189Y218004D02*
Y216823D01*
G01X1186205Y218004D02*
Y216823D01*
G01X1185811Y199993D02*
Y212886D01*
G01X1185713Y218004D02*
Y216823D01*
G01X1185516Y218103D02*
Y216725D01*
G01X1185418Y218004D02*
Y216823D01*
G01X1185024Y218890D02*
Y215937D01*
G01X1184433Y214264D02*
Y199697D01*
G01Y219993D02*
Y215268D01*
G01X1183843D02*
Y219993D01*
G01X1196189Y212941D02*
X1197622Y211508D01*
G01X1192307Y216725D02*
X1192701Y216331D01*
G01X1184433Y214264D02*
X1185024Y213674D01*
G01X1185811Y212886D02*
X1185418Y213280D01*
G01X1204748Y217079D02*
X1206717D01*
G01X1185024Y216823D02*
X1226441D01*
G01X1192307Y216725D02*
X1185024D01*
G01X1212426D02*
X1199040D01*
G01X1190044Y216430D02*
X1186303D01*
G01X1226441Y216331D02*
X1185024D01*
G01X1199040Y215937D02*
X1185024D01*
G01X1190044Y215445D02*
X1186303D01*
G01X1204217Y214264D02*
X1184433D01*
G01X1185024Y213674D02*
X1229512D01*
G01X1203922Y213280D02*
X1194197D01*
G01X1196189Y212941D02*
X1203779D01*
G01X1185811Y212886D02*
X1192622D01*
G01X1211500Y212493D02*
X1204217D01*
G01X1211796Y212296D02*
X1203922D01*
G01X1192229Y211705D02*
X1192622D01*
G01X1202347Y211508D02*
X1197622D01*
G01X1185024Y210721D02*
X1188567D01*
G01X1224394Y209343D02*
X1191323D01*
G01X1224394Y209284D02*
X1191323D01*
G01Y208851D02*
X1189256D01*
G01Y208752D02*
X1191323D01*
G01X1198548Y208556D02*
X1203272D01*
G01X1187918D02*
X1192642D01*
G01X1197622Y208457D02*
X1194079D01*
G01X1205890D02*
X1202347D01*
G01X1204709Y208319D02*
X1195260D01*
G01X1199630Y208260D02*
X1204473D01*
G01X1197622D02*
X1199089D01*
G01X1188803D02*
X1193646D01*
G01X1203174Y208063D02*
X1204276D01*
G01X1192347D02*
X1193449D01*
G01Y207670D02*
X1192347D01*
G01X1204276D02*
X1203174D01*
G01X1199630Y207473D02*
X1204473D01*
G01X1197622D02*
X1199089D01*
G01X1188803D02*
X1193646D01*
G01X1195260Y207414D02*
X1204709D01*
G01X1197622Y207276D02*
X1194079D01*
G01X1205890D02*
X1202347D01*
G01X1192642Y207178D02*
X1187918D01*
G01X1203272D02*
X1198548D01*
G01X1189256Y206981D02*
X1191323D01*
G01Y206882D02*
X1189256D01*
G01X1191323Y206449D02*
X1224394D01*
G01Y206331D02*
X1191323D01*
G01Y205898D02*
X1188823D01*
G01X1191323Y205800D02*
X1188823D01*
G01X1198548Y205603D02*
X1203272D01*
G01X1187918D02*
X1192642D01*
G01X1197622Y205504D02*
X1194079D01*
G01X1205890D02*
X1202347D01*
G01X1204709Y205367D02*
X1195260D01*
G01X1199630Y205308D02*
X1204670D01*
G01X1197622D02*
X1199090D01*
G01X1193685D02*
X1188803D01*
G01X1193449Y205111D02*
X1192347D01*
G01X1204276D02*
X1203174D01*
G01Y204717D02*
X1204276D01*
G01X1192347D02*
X1193449D01*
G01X1199630Y204520D02*
X1204670D01*
G01X1197622D02*
X1199090D01*
G01X1188803D02*
X1193685D01*
G01X1195260Y204461D02*
X1204709D01*
G01X1197622Y204323D02*
X1194079D01*
G01X1205890D02*
X1202347D01*
G01X1192642Y204225D02*
X1187918D01*
G01X1203272D02*
X1198548D01*
G01X1191323Y204028D02*
X1188823D01*
G01X1191323Y203930D02*
X1188823D01*
G01X1191323Y203497D02*
X1224394D01*
G01Y203378D02*
X1191323D01*
G01Y202945D02*
X1188823D01*
G01X1191323Y202847D02*
X1188823D01*
G01X1198548Y202650D02*
X1203272D01*
G01X1187918D02*
X1192642D01*
G01X1197622Y202552D02*
X1194079D01*
G01X1205890D02*
X1202347D01*
G01X1204709Y202414D02*
X1195260D01*
G01X1199630Y202355D02*
X1204670D01*
G01X1197622D02*
X1199090D01*
G01X1193685D02*
X1188803D01*
G01X1193449Y202158D02*
X1192347D01*
G01X1204276D02*
X1203174D01*
G01Y201764D02*
X1204276D01*
G01X1192347D02*
X1193449D01*
G01X1199630Y201567D02*
X1204670D01*
G01X1197622D02*
X1199090D01*
G01X1188803D02*
X1193685D01*
G01X1195260Y201508D02*
X1204709D01*
G01X1197622Y201371D02*
X1194079D01*
G01X1205890D02*
X1202347D01*
G01X1192642Y201272D02*
X1187918D01*
G01X1203272D02*
X1198548D01*
G01X1191323Y201075D02*
X1188823D01*
G01X1191323Y200977D02*
X1188823D01*
G01X1191323Y200544D02*
X1224394D01*
G01Y200426D02*
X1191323D01*
G01X1185024Y199993D02*
X1186402D01*
G01X1191323D02*
X1189256D01*
G01Y199894D02*
X1191323D01*
G01X1198548Y199697D02*
X1203272D01*
G01X1187918D02*
X1192642D01*
G01X1186992D02*
X1184433D01*
G01X1197622Y199599D02*
X1194079D01*
G01X1205890D02*
X1202347D01*
G01X1204709Y199461D02*
X1195260D01*
G01X1199630Y199402D02*
X1204473D01*
G01X1197622D02*
X1199089D01*
G01X1188803D02*
X1193646D01*
G01X1203174Y199205D02*
X1204276D01*
G01X1192347D02*
X1193449D01*
G01Y198812D02*
X1192347D01*
G01X1204276D02*
X1203174D01*
G01X1199630Y198615D02*
X1204473D01*
G01X1197622D02*
X1199089D01*
G01X1188803D02*
X1193646D01*
G01X1195260Y198556D02*
X1204709D01*
G01X1197622Y198418D02*
X1194079D01*
G01X1205890D02*
X1202347D01*
G01X1192642Y198319D02*
X1187918D01*
G01X1203272D02*
X1198548D01*
G01X1189256Y198123D02*
X1191323D01*
G01Y198024D02*
X1189256D01*
G01X1191323Y197591D02*
X1224394D01*
G01Y197473D02*
X1191323D01*
G01Y197040D02*
X1188823D01*
G01X1191323Y196941D02*
X1188823D01*
G01X1198548Y196745D02*
X1203272D01*
G01X1187918D02*
X1192642D01*
G01X1197622Y196646D02*
X1194079D01*
G01X1205890D02*
X1202347D01*
G01X1204709Y196508D02*
X1195260D01*
G01X1199630Y196449D02*
X1204670D01*
G01X1197622D02*
X1199090D01*
G01X1193685D02*
X1188803D01*
G01X1193449Y196252D02*
X1192347D01*
G01X1204276D02*
X1203174D01*
G01Y195859D02*
X1204276D01*
G01X1192347D02*
X1193449D01*
G01X1199630Y195662D02*
X1204670D01*
G01X1197622D02*
X1199090D01*
G01X1188803D02*
X1193685D01*
G01X1195260Y195603D02*
X1204709D01*
G01X1197622Y195465D02*
X1194079D01*
G01X1205890D02*
X1202347D01*
G01X1192642Y195367D02*
X1187918D01*
G01X1203272D02*
X1198548D01*
G01X1191323Y195170D02*
X1188823D01*
G01X1191323Y195071D02*
X1188823D01*
G01X1191323Y194638D02*
X1224394D01*
G01Y194520D02*
X1191323D01*
G01X1201182Y229404D02*
X1200694Y230126D01*
G01X1202156Y228682D02*
X1201182Y229404D01*
G01X1203131Y228682D02*
X1202156D01*
G01X1204105Y229404D02*
X1203131Y228682D01*
G01X1204592Y230126D02*
X1204105Y229404D01*
G01X1205079Y231569D02*
X1204592Y230126D01*
G01Y233013D02*
X1205079Y231569D01*
G01X1204105Y233735D02*
X1204592Y233013D01*
G01X1203131Y234456D02*
X1204105Y233735D01*
G01X1202156Y234456D02*
X1203131D01*
G01X1201182Y233735D02*
X1202156Y234456D01*
G01X1201669Y237344D02*
X1201182Y233735D01*
G01X1204592Y237344D02*
X1201669D01*
G01X1196797Y234456D02*
X1196310Y233735D01*
G01X1196797Y235900D02*
Y234456D01*
G01X1196310Y236622D02*
X1196797Y235900D01*
G01X1195335Y237344D02*
X1196310Y236622D01*
G01X1194361Y237344D02*
X1195335D01*
G01X1193387Y236622D02*
X1194361Y237344D01*
G01X1192899Y235900D02*
X1193387Y236622D01*
G01X1192899Y228682D02*
X1196797D01*
G01X1193387Y230848D02*
X1192899Y228682D01*
G01X1194361Y232291D02*
X1193387Y230848D01*
G01X1196310Y233735D02*
X1194361Y232291D01*
G01X1204722Y217921D02*
X1204690Y218004D01*
G01X1204742Y217836D02*
X1204722Y217921D01*
G01X1204748Y217749D02*
X1204742Y217836D01*
G01X1192307Y218103D02*
X1192701Y218497D01*
G01X1199040Y218890D02*
Y218103D01*
G01X1186303Y219382D02*
X1190044D01*
G01X1185024Y218890D02*
X1199040D01*
G01X1185024Y218497D02*
X1226441D01*
G01X1186303Y218398D02*
X1190044D01*
G01X1192307Y218103D02*
X1185024D01*
G01X1212426D02*
X1199040D01*
G01X1185024Y218004D02*
X1226441D01*
G01X1206717Y217749D02*
X1204748D01*
G01X1202347Y352040D02*
G03I-6496J0D01*
G01X1207662D02*
G03I-11811J0D01*
G01X1195851Y355977D02*
Y375784D01*
G01X1188633Y385474D02*
X1190076Y383525D01*
G01X1187911Y385961D02*
X1188633Y385474D01*
G01X1186467Y385961D02*
X1187911D01*
G01X1185746Y385474D02*
X1186467Y385961D01*
G01X1185024Y384499D02*
X1185746Y385474D01*
G01X1185024Y383525D02*
Y384499D01*
G01X1185746Y382550D02*
X1185024Y383525D01*
G01X1186467Y382063D02*
X1185746Y382550D01*
G01X1193685Y382063D02*
Y385961D01*
G01X1191520Y382550D02*
X1193685Y382063D01*
G01X1190076Y383525D02*
X1191520Y382550D01*
G01X1185024Y401551D02*
Y397654D01*
G01X1193685Y389858D02*
X1185024Y393756D01*
G01Y389858D02*
X1193685Y393756D01*
G01X1187911Y421039D02*
X1186467Y421527D01*
G01X1190798Y421039D02*
X1187911D01*
G01X1192242Y421527D02*
X1190798Y421039D01*
G01X1192963Y414706D02*
X1193685Y415193D01*
G01Y414706D02*
X1192963D01*
G01X1193685Y415193D02*
Y414706D01*
G01X1190076Y400090D02*
X1187911Y400577D01*
G01X1193685Y399602D02*
X1190076Y400090D01*
G01X1187911Y400577D02*
X1185024Y401551D01*
G01Y409347D02*
Y405449D01*
G01X1187911Y408372D02*
X1185024Y409347D01*
G01X1190076Y407885D02*
X1187911Y408372D01*
G01X1193685Y407398D02*
X1190076Y407885D01*
G01X1192963Y431758D02*
X1193685Y430784D01*
G01X1192242Y432245D02*
X1192963Y431758D01*
G01X1190798Y432732D02*
X1192242Y432245D01*
G01X1187911Y432732D02*
X1190798D01*
G01X1186467Y432245D02*
X1187911Y432732D01*
G01X1185746Y431758D02*
X1186467Y432245D01*
G01X1185024Y430784D02*
X1185746Y431758D01*
G01Y429809D02*
X1185024Y430784D01*
G01X1186467Y429322D02*
X1185746Y429809D01*
G01X1187911Y428835D02*
X1186467Y429322D01*
G01X1190798Y428835D02*
X1187911D01*
G01X1192242Y429322D02*
X1190798Y428835D01*
G01X1192963Y429809D02*
X1192242Y429322D01*
G01X1193685Y430784D02*
X1192963Y429809D01*
G01Y423963D02*
X1193685Y422988D01*
G01X1192242Y424450D02*
X1192963Y423963D01*
G01X1190798Y424937D02*
X1192242Y424450D01*
G01X1187911Y424937D02*
X1190798D01*
G01X1186467Y424450D02*
X1187911Y424937D01*
G01X1185746Y423963D02*
X1186467Y424450D01*
G01X1185024Y422988D02*
X1185746Y423963D01*
G01Y422014D02*
X1185024Y422988D01*
G01X1186467Y421527D02*
X1185746Y422014D01*
G01X1192963D02*
X1192242Y421527D01*
G01X1193685Y422988D02*
X1192963Y422014D01*
G01X1192352Y457809D02*
X1191865Y458531D01*
G01X1192839Y457087D02*
X1192352Y457809D01*
G01X1193814Y456365D02*
X1192839Y457087D01*
G01X1194788Y456365D02*
X1193814D01*
G01X1195762Y457087D02*
X1194788Y456365D01*
G01X1196250Y457809D02*
X1195762Y457087D01*
G01X1196250Y459252D02*
Y457809D01*
G01X1195762Y459974D02*
X1196250Y459252D01*
G01X1194788Y460696D02*
X1195762Y459974D01*
G01X1193814Y461418D02*
X1194788Y460696D01*
G01X1192839Y462139D02*
X1193814Y461418D01*
G01X1192352Y462862D02*
X1192839Y462139D01*
G01X1192352Y463583D02*
Y462862D01*
G01X1192839Y464305D02*
X1192352Y463583D01*
G01X1193814Y465027D02*
X1192839Y464305D01*
G01X1194788Y465027D02*
X1193814D01*
G01X1195762Y464305D02*
X1194788Y465027D01*
G01X1196250Y463583D02*
X1195762Y464305D01*
G01X1202096Y465027D02*
Y456365D01*
G01X1184015Y473495D02*
X1184502Y472773D01*
G01X1184015D02*
Y473495D01*
G01X1184502Y472773D02*
X1184015D01*
G01X1193272Y473495D02*
X1192298Y472773D01*
G01X1193759Y474216D02*
X1193272Y473495D01*
G01X1194246Y475660D02*
X1193759Y474216D01*
G01X1194246Y478547D02*
Y475660D01*
G01X1193759Y479991D02*
X1194246Y478547D01*
G01X1193272Y480712D02*
X1193759Y479991D01*
G01X1192298Y481434D02*
X1193272Y480712D01*
G01X1191323D02*
X1192298Y481434D01*
G01X1190836Y479991D02*
X1191323Y480712D01*
G01X1190349Y478547D02*
X1190836Y479991D01*
G01X1190349Y475660D02*
Y478547D01*
G01X1190836Y474216D02*
X1190349Y475660D01*
G01X1191323Y473495D02*
X1190836Y474216D01*
G01X1192298Y472773D02*
X1191323Y473495D01*
G01X1201067D02*
X1200093Y472773D01*
G01X1201555Y474216D02*
X1201067Y473495D01*
G01X1202042Y475660D02*
X1201555Y474216D01*
G01X1202042Y478547D02*
Y475660D01*
G01X1201555Y479991D02*
X1202042Y478547D01*
G01X1201067Y480712D02*
X1201555Y479991D01*
G01X1200093Y481434D02*
X1201067Y480712D01*
G01X1199118D02*
X1200093Y481434D01*
G01X1198631Y479991D02*
X1199118Y480712D01*
G01X1198144Y478547D02*
X1198631Y479991D01*
G01X1198144Y475660D02*
Y478547D01*
G01X1198631Y474216D02*
X1198144Y475660D01*
G01X1199118Y473495D02*
X1198631Y474216D01*
G01X1200093Y472773D02*
X1199118Y473495D01*
G01X1205939Y478547D02*
X1206427Y479991D01*
G01X1205939Y475660D02*
Y478547D01*
G01X1206427Y474216D02*
X1205939Y475660D01*
G01X1199161Y506880D02*
G03I-6497J0D01*
G01X1196557Y498966D02*
X1196680Y499008D01*
G01X1196024Y498841D02*
X1195901Y498799D01*
G01Y498966D02*
X1196024Y499008D01*
G01X1194712Y498966D02*
X1194835Y499008D01*
G01X1194178Y498841D02*
X1194055Y498799D01*
G01Y498966D02*
X1194178Y499008D01*
G01X1196639Y498841D02*
X1196557Y498799D01*
G01X1194794Y498841D02*
X1194712Y498799D01*
G01X1191636Y498966D02*
X1191062Y498673D01*
G01X1190775D02*
X1191554Y499092D01*
G01X1192948Y497710D02*
X1193153Y497836D01*
G01X1192456Y499595D02*
X1192251Y499469D01*
G01X1192907Y497919D02*
X1193030Y498003D01*
G01X1192497Y499385D02*
X1192374Y499301D01*
G01X1196557Y498799D02*
X1196516Y498757D01*
G01X1196434Y498841D02*
X1196557Y498966D01*
G01X1195901Y498799D02*
X1195819Y498715D01*
G01Y498883D02*
X1195901Y498966D01*
G01X1194712Y498799D02*
X1194670Y498757D01*
G01X1194588Y498841D02*
X1194712Y498966D01*
G01X1193153Y497836D02*
X1193276Y497961D01*
G01X1194055Y498799D02*
X1193974Y498715D01*
G01Y498883D02*
X1194055Y498966D01*
G01X1192251Y499469D02*
X1192128Y499343D01*
G01X1193030Y498003D02*
X1193194Y498254D01*
G01X1192374Y499301D02*
X1192210Y499050D01*
G01X1191636Y498380D02*
X1191554Y498254D01*
G01X1196516Y498757D02*
X1196475Y498673D01*
G01X1194670Y498757D02*
X1194629Y498673D01*
G01X1193276Y497961D02*
X1193358Y498129D01*
G01X1192128Y499343D02*
X1192046Y499176D01*
G01X1193358Y498129D02*
X1193399Y498254D01*
G01X1192046Y499176D02*
X1192005Y499050D01*
G01X1193399Y498254D02*
X1193440Y498464D01*
G01X1192005Y499050D02*
X1191964Y498841D01*
G01X1193194Y498254D02*
X1193235Y498506D01*
G01X1192210Y499050D02*
X1192169Y498799D01*
G01X1197131Y498673D02*
Y497668D01*
G01X1196926D02*
Y498673D01*
G01X1196475D02*
Y497668D01*
G01X1196270D02*
Y498673D01*
G01X1195819Y499008D02*
Y498883D01*
G01Y498715D02*
Y497668D01*
G01X1195614D02*
Y499008D01*
G01X1195286Y498673D02*
Y497668D01*
G01X1195081D02*
Y498673D01*
G01X1194629D02*
Y497668D01*
G01X1194424D02*
Y498673D01*
G01X1193974Y499008D02*
Y498883D01*
G01Y498715D02*
Y497668D01*
G01X1193768D02*
Y499008D01*
G01X1193440Y498464D02*
Y498841D01*
G01X1193235Y498506D02*
Y498799D01*
G01X1192169D02*
Y498506D01*
G01X1191964Y498841D02*
Y498464D01*
G01X1190446Y499636D02*
Y497668D01*
G01X1190200Y498841D02*
Y499636D01*
G01Y497668D02*
Y498589D01*
G01X1189052Y499636D02*
Y498841D01*
G01Y498589D02*
Y497668D01*
G01X1188806D02*
Y499636D01*
G01X1193235Y498799D02*
X1193194Y499050D01*
G01X1192169Y498506D02*
X1192210Y498254D01*
G01X1193440Y498841D02*
X1193399Y499050D01*
G01X1191964Y498464D02*
X1192005Y498254D01*
G01X1193399Y499050D02*
X1193358Y499176D01*
G01X1192005Y498254D02*
X1192046Y498129D01*
G01X1197049Y498883D02*
X1197131Y498673D01*
G01X1195204Y498883D02*
X1195286Y498673D01*
G01X1196926D02*
X1196885Y498757D01*
G01X1196270Y498673D02*
X1196229Y498757D01*
G01X1195081Y498673D02*
X1195040Y498757D01*
G01X1194424Y498673D02*
X1194383Y498757D01*
G01X1193358Y499176D02*
X1193276Y499343D01*
G01X1192046Y498129D02*
X1192128Y497961D01*
G01X1193194Y499050D02*
X1193030Y499301D01*
G01X1192210Y498254D02*
X1192374Y498003D01*
G01X1191554Y499092D02*
X1191636Y498966D01*
G01X1196967D02*
X1197049Y498883D01*
G01X1196885Y498757D02*
X1196844Y498799D01*
G01X1196311Y498966D02*
X1196434Y498841D01*
G01X1196229Y498757D02*
X1196188Y498799D01*
G01X1195122Y498966D02*
X1195204Y498883D01*
G01X1195040Y498757D02*
X1194999Y498799D01*
G01X1194466Y498966D02*
X1194588Y498841D01*
G01X1194383Y498757D02*
X1194342Y498799D01*
G01X1193276Y499343D02*
X1193153Y499469D01*
G01X1192128Y497961D02*
X1192251Y497836D01*
G01X1193030Y499301D02*
X1192907Y499385D01*
G01X1192374Y498003D02*
X1192497Y497919D01*
G01X1193153Y499469D02*
X1192948Y499595D01*
G01X1192251Y497836D02*
X1192456Y497710D01*
G01X1191554Y498254D02*
X1190775Y498673D01*
G01X1196844Y498799D02*
X1196762Y498841D01*
G01X1196188Y498799D02*
X1196106Y498841D01*
G01X1194999Y498799D02*
X1194916Y498841D01*
G01X1194342Y498799D02*
X1194261Y498841D01*
G01X1191062Y498673D02*
X1191636Y498380D01*
G01X1196844Y499008D02*
X1196967Y498966D01*
G01X1196188Y499008D02*
X1196311Y498966D01*
G01X1194999Y499008D02*
X1195122Y498966D01*
G01X1194342Y499008D02*
X1194466Y498966D01*
G01X1192907Y499385D02*
X1192702Y499427D01*
G01X1192497Y497919D02*
X1192702Y497877D01*
G01X1192948Y499595D02*
X1192702Y499636D01*
G01X1192456Y497710D02*
X1192702Y497668D01*
G01X1190200Y499636D02*
X1190446D01*
G01X1188806D02*
X1189052D01*
G01X1195614Y499008D02*
X1195819D01*
G01X1196024D02*
X1196188D01*
G01X1196680D02*
X1196844D01*
G01X1193768D02*
X1193974D01*
G01X1194178D02*
X1194342D01*
G01X1194835D02*
X1194999D01*
G01X1189052Y498841D02*
X1190200D01*
G01X1194916D02*
X1194794D01*
G01X1194261D02*
X1194178D01*
G01X1196762D02*
X1196639D01*
G01X1196106D02*
X1196024D01*
G01X1190200Y498589D02*
X1189052D01*
G01Y497668D02*
X1188806D01*
G01X1190446D02*
X1190200D01*
G01X1193974D02*
X1193768D01*
G01X1195286D02*
X1195081D01*
G01X1194629D02*
X1194424D01*
G01X1195819D02*
X1195614D01*
G01X1196475D02*
X1196270D01*
G01X1197131D02*
X1196926D01*
G01X1192702Y499636D02*
X1192456Y499595D01*
G01X1192702Y497668D02*
X1192948Y497710D01*
G01X1192702Y499427D02*
X1192497Y499385D01*
G01X1192702Y497877D02*
X1192907Y497919D01*
G01X1199161Y736014D02*
G03I-6497J0D01*
G01X1196526Y727761D02*
X1196646Y727720D01*
G01X1195883Y727761D02*
X1196003Y727720D01*
G01X1194717Y727761D02*
X1194838Y727720D01*
G01X1194074Y727761D02*
X1194195Y727720D01*
G01X1192668Y728130D02*
X1192467Y728171D01*
G01X1192266Y726694D02*
X1192467Y726653D01*
G01X1192708Y728336D02*
X1192467Y728376D01*
G01X1192226Y726489D02*
X1192467Y726447D01*
G01X1188649Y728376D02*
X1188890D01*
G01X1190015D02*
X1190256D01*
G01X1195320Y727761D02*
X1195521D01*
G01X1195722D02*
X1195883D01*
G01X1196365D02*
X1196526D01*
G01X1193512D02*
X1193713D01*
G01X1193914D02*
X1194074D01*
G01X1194557D02*
X1194717D01*
G01X1196646Y727720D02*
X1196727Y727638D01*
G01X1196566Y727515D02*
X1196526Y727556D01*
G01X1196003Y727720D02*
X1196124Y727597D01*
G01X1195923Y727515D02*
X1195883Y727556D01*
G01X1194838Y727720D02*
X1194918Y727638D01*
G01X1194757Y727515D02*
X1194717Y727556D01*
G01X1194195Y727720D02*
X1194315Y727597D01*
G01X1194114Y727515D02*
X1194074Y727556D01*
G01X1193029Y728089D02*
X1192909Y728212D01*
G01X1191904Y726735D02*
X1192025Y726612D01*
G01X1192788Y728048D02*
X1192668Y728130D01*
G01X1192145Y726776D02*
X1192266Y726694D01*
G01X1192909Y728212D02*
X1192708Y728336D01*
G01X1192025Y726612D02*
X1192226Y726489D01*
G01X1191341Y727022D02*
X1190578Y727433D01*
G01X1196526Y727556D02*
X1196446Y727597D01*
G01X1195883Y727556D02*
X1195802Y727597D01*
G01X1194717Y727556D02*
X1194637Y727597D01*
G01X1194074Y727556D02*
X1193994Y727597D01*
G01X1190859Y727433D02*
X1191422Y727145D01*
G01X1188890Y727597D02*
X1190015D01*
G01X1194637D02*
X1194516D01*
G01X1193994D02*
X1193914D01*
G01X1196446D02*
X1196325D01*
G01X1195802D02*
X1195722D01*
G01X1190015Y727350D02*
X1188890D01*
G01Y726447D02*
X1188649D01*
G01X1190256D02*
X1190015D01*
G01X1193713D02*
X1193512D01*
G01X1194999D02*
X1194798D01*
G01X1194355D02*
X1194155D01*
G01X1195521D02*
X1195320D01*
G01X1196807D02*
X1196606D01*
G01X1196164D02*
X1195963D01*
G01X1192467Y728376D02*
X1192226Y728336D01*
G01X1192467Y726447D02*
X1192708Y726489D01*
G01X1192467Y728171D02*
X1192266Y728130D01*
G01X1192467Y726653D02*
X1192668Y726694D01*
G01X1196606Y727433D02*
X1196566Y727515D01*
G01X1195963Y727433D02*
X1195923Y727515D01*
G01X1194798Y727433D02*
X1194757Y727515D01*
G01X1194155Y727433D02*
X1194114Y727515D01*
G01X1193110Y727925D02*
X1193029Y728089D01*
G01X1192949Y727802D02*
X1192788Y728048D01*
G01X1191985Y727022D02*
X1192145Y726776D01*
G01X1191341Y727843D02*
X1191422Y727720D01*
G01X1193150Y727802D02*
X1193110Y727925D01*
G01X1191783Y727022D02*
X1191824Y726899D01*
G01X1196727Y727638D02*
X1196807Y727433D01*
G01X1194918Y727638D02*
X1194999Y727433D01*
G01X1191824Y726899D02*
X1191904Y726735D01*
G01X1192989Y727556D02*
X1192949Y727802D01*
G01X1191944Y727269D02*
X1191985Y727022D01*
G01X1193190Y727597D02*
X1193150Y727802D01*
G01X1191743Y727227D02*
X1191783Y727022D01*
G01X1196807Y727433D02*
Y726447D01*
G01X1196606D02*
Y727433D01*
G01X1196164D02*
Y726447D01*
G01X1195963D02*
Y727433D01*
G01X1195521Y727761D02*
Y727638D01*
G01Y727474D02*
Y726447D01*
G01X1192949Y727022D02*
X1192989Y727269D01*
G01X1195320Y726447D02*
Y727761D01*
G01X1194999Y727433D02*
Y726447D01*
G01X1194798D02*
Y727433D01*
G01X1194355D02*
Y726447D01*
G01X1194155D02*
Y727433D01*
G01X1193713Y727761D02*
Y727638D01*
G01Y727474D02*
Y726447D01*
G01X1193512D02*
Y727761D01*
G01X1193190Y727227D02*
Y727597D01*
G01X1192989Y727269D02*
Y727556D01*
G01X1191944D02*
Y727269D01*
G01X1191743Y727597D02*
Y727227D01*
G01X1190256Y728376D02*
Y726447D01*
G01X1190015Y727597D02*
Y728376D01*
G01Y726447D02*
Y727350D01*
G01X1188890D02*
Y726447D01*
G01Y728376D02*
Y727597D01*
G01X1188649Y726447D02*
Y728376D01*
G01X1193110Y726899D02*
X1193150Y727022D01*
G01X1191824Y727925D02*
X1191783Y727802D01*
G01X1193150Y727022D02*
X1193190Y727227D01*
G01X1191783Y727802D02*
X1191743Y727597D01*
G01X1191985Y727802D02*
X1191944Y727556D01*
G01X1196204Y727515D02*
X1196164Y727433D01*
G01X1194396Y727515D02*
X1194355Y727433D01*
G01X1193029Y726735D02*
X1193110Y726899D01*
G01X1191904Y728089D02*
X1191824Y727925D01*
G01X1196244Y727556D02*
X1196204Y727515D01*
G01X1196124Y727597D02*
X1196244Y727720D01*
G01X1195601Y727556D02*
X1195521Y727474D01*
G01Y727638D02*
X1195601Y727720D01*
G01X1194436Y727556D02*
X1194396Y727515D01*
G01X1194315Y727597D02*
X1194436Y727720D01*
G01X1192909Y726612D02*
X1193029Y726735D01*
G01X1193793Y727556D02*
X1193713Y727474D01*
G01Y727638D02*
X1193793Y727720D01*
G01X1192788Y726776D02*
X1192949Y727022D01*
G01X1192145Y728048D02*
X1191985Y727802D01*
G01X1191422Y727145D02*
X1191341Y727022D01*
G01X1192708Y726489D02*
X1192909Y726612D01*
G01X1192668Y726694D02*
X1192788Y726776D01*
G01X1192266Y728130D02*
X1192145Y728048D01*
G01X1192025Y728212D02*
X1191904Y728089D01*
G01X1196244Y727720D02*
X1196365Y727761D01*
G01X1195722Y727597D02*
X1195601Y727556D01*
G01Y727720D02*
X1195722Y727761D01*
G01X1194436Y727720D02*
X1194557Y727761D01*
G01X1193914Y727597D02*
X1193793Y727556D01*
G01Y727720D02*
X1193914Y727761D01*
G01X1196325Y727597D02*
X1196244Y727556D01*
G01X1194516Y727597D02*
X1194436Y727556D01*
G01X1191422Y727720D02*
X1190859Y727433D01*
G01X1190578D02*
X1191341Y727843D01*
G01X1192226Y728336D02*
X1192025Y728212D01*
G01X1216483Y28231D02*
X1215996Y28953D01*
G01X1216970Y27509D02*
X1216483Y28231D01*
G01X1217945Y26787D02*
X1216970Y27509D01*
G01X1218919Y26787D02*
X1217945D01*
G01X1219894Y27509D02*
X1218919Y26787D01*
G01X1220381Y28231D02*
X1219894Y27509D01*
G01X1220381Y29675D02*
Y28231D01*
G01X1219894Y30396D02*
X1220381Y29675D01*
G01X1218919Y31118D02*
X1219894Y30396D01*
G01X1217945Y31840D02*
X1218919Y31118D01*
G01X1216970Y32562D02*
X1217945Y31840D01*
G01X1216483Y33284D02*
X1216970Y32562D01*
G01X1216483Y34005D02*
Y33284D01*
G01X1216970Y34727D02*
X1216483Y34005D01*
G01X1217945Y35449D02*
X1216970Y34727D01*
G01X1218919Y35449D02*
X1217945D01*
G01X1219894Y34727D02*
X1218919Y35449D01*
G01X1220381Y34005D02*
X1219894Y34727D01*
G01X1226227Y35449D02*
Y26787D01*
G01X1220822Y40043D02*
X1221309Y39321D01*
G01X1220822D02*
Y40043D01*
G01X1221309Y39321D02*
X1220822D01*
G01X1228130Y47261D02*
X1229105Y47983D01*
G01X1227643Y46539D02*
X1228130Y47261D01*
G01X1227156Y45096D02*
X1227643Y46539D01*
G01X1227156Y42208D02*
Y45096D01*
G01X1227643Y40765D02*
X1227156Y42208D01*
G01X1228130Y40043D02*
X1227643Y40765D01*
G01X1229105Y39321D02*
X1228130Y40043D01*
G01X1213514Y47983D02*
Y39321D01*
G01X1206724Y174274D02*
X1206717Y174363D01*
G01X1206743Y174189D02*
X1206724Y174274D01*
G01X1206775Y174107D02*
X1206743Y174189D01*
G01Y175206D02*
X1206775Y175288D01*
G01X1206724Y175121D02*
X1206743Y175206D01*
G01X1206717Y175032D02*
X1206724Y175121D01*
G01X1212579Y190487D02*
X1212619Y190544D01*
G01X1212553Y190420D02*
X1212579Y190487D01*
G01X1212544Y190347D02*
X1212553Y190420D01*
G01X1212579Y183908D02*
X1212619Y183851D01*
G01X1212553Y183975D02*
X1212579Y183908D01*
G01X1212544Y184048D02*
X1212553Y183975D01*
G01X1212579Y186861D02*
X1212619Y186804D01*
G01X1212553Y186927D02*
X1212579Y186861D01*
G01X1212544Y187000D02*
X1212553Y186927D01*
G01X1212579Y189814D02*
X1212619Y189756D01*
G01X1212553Y189880D02*
X1212579Y189814D01*
G01X1212544Y189953D02*
X1212553Y189880D01*
G01X1212579Y192767D02*
X1212619Y192709D01*
G01X1212553Y192833D02*
X1212579Y192767D01*
G01X1212544Y192906D02*
X1212553Y192833D01*
G01X1223405Y183908D02*
X1223446Y183851D01*
G01X1223379Y183975D02*
X1223405Y183908D01*
G01X1223370Y184048D02*
X1223379Y183975D01*
G01X1223405Y186861D02*
X1223446Y186804D01*
G01X1223379Y186927D02*
X1223405Y186861D01*
G01X1223370Y187000D02*
X1223379Y186927D01*
G01X1223405Y189814D02*
X1223446Y189756D01*
G01X1223379Y189880D02*
X1223405Y189814D01*
G01X1223370Y189953D02*
X1223379Y189880D01*
G01X1223405Y192767D02*
X1223446Y192709D01*
G01X1223379Y192833D02*
X1223405Y192767D01*
G01X1223370Y192906D02*
X1223379Y192833D01*
G01X1223405Y193439D02*
X1223446Y193497D01*
G01X1223379Y193373D02*
X1223405Y193439D01*
G01X1223370Y193300D02*
X1223379Y193373D01*
G01X1223405Y190487D02*
X1223446Y190544D01*
G01X1223379Y190420D02*
X1223405Y190487D01*
G01X1223370Y190347D02*
X1223379Y190420D01*
G01X1223405Y187534D02*
X1223446Y187591D01*
G01X1223379Y187467D02*
X1223405Y187534D01*
G01X1223370Y187394D02*
X1223379Y187467D01*
G01X1223405Y184581D02*
X1223446Y184638D01*
G01X1223379Y184515D02*
X1223405Y184581D01*
G01X1223370Y184441D02*
X1223379Y184515D01*
G01X1212553Y193373D02*
X1212544Y193300D01*
G01X1212579Y193439D02*
X1212553Y193373D01*
G01X1212619Y193497D02*
X1212579Y193439D01*
G01X1212553Y187468D02*
X1212544Y187394D01*
G01X1212579Y187534D02*
X1212553Y187468D01*
G01X1212619Y187591D02*
X1212579Y187534D01*
G01X1212553Y184515D02*
X1212544Y184441D01*
G01X1212579Y184581D02*
X1212553Y184515D01*
G01X1212619Y184638D02*
X1212579Y184581D01*
G01X1225162Y173713D02*
G03Y175682I0J984D01*
G01X1221422D02*
G03Y173713I0J-985D01*
G01X1221520Y178831D02*
G03X1223095Y180406I0J1575D01*
G01X1221422Y176666D02*
G03Y172729I0J-1969D01*
G01X1225162D02*
G03Y176666I0J1968D01*
G01X1221520Y178437D02*
G03X1223488Y180406I-1J1969D01*
G01X1207509Y179251D02*
X1208413Y179547D01*
G01X1207375Y179219D02*
X1206973Y179087D01*
G01Y178890D02*
X1208548Y179415D01*
G01X1207844Y181187D02*
X1207777Y181154D01*
G01X1228410Y175701D02*
X1226441Y173733D01*
G01X1228725Y178437D02*
X1229512Y179225D01*
G01X1218764Y173615D02*
X1219158Y174008D01*
G01X1213370Y180603D02*
X1211937Y179170D01*
G01X1207408Y182827D02*
X1207308Y182795D01*
G01Y185321D02*
X1207207Y185288D01*
G01X1207810Y186994D02*
X1207710Y186961D01*
G01X1207274Y191292D02*
X1207375Y191325D01*
G01X1208179Y193425D02*
X1208078Y193392D01*
G01X1207341Y194475D02*
X1207442Y194507D01*
G01X1207844Y182106D02*
X1207911Y182138D01*
G01X1207308Y182795D02*
X1207241Y182762D01*
G01X1207844Y184534D02*
X1207710Y184468D01*
G01X1207676Y184632D02*
X1207743Y184665D01*
G01X1208179Y190275D02*
X1208313Y190341D01*
G01Y193490D02*
X1208179Y193425D01*
G01X1207207Y194409D02*
X1207341Y194475D01*
G01X1207676Y182106D02*
X1207777Y182171D01*
G01X1207911Y187060D02*
X1207810Y186994D01*
G01Y187191D02*
X1207710Y187125D01*
G01X1207207Y187716D02*
X1207308Y187782D01*
G01X1207107Y187847D02*
X1207207Y187913D01*
G01X1208246Y190537D02*
X1208146Y190472D01*
G01X1208279Y193687D02*
X1208078Y193556D01*
G01X1207241Y194212D02*
X1207442Y194343D01*
G01X1207241Y182959D02*
X1207073Y182827D01*
G01X1207643Y191784D02*
X1208548Y192571D01*
G01X1207643Y192014D02*
X1208279Y192571D01*
G01X1207944Y180629D02*
X1208011Y180695D01*
G01X1207877D02*
X1207810Y180629D01*
G01X1207911Y181121D02*
X1208011Y181220D01*
G01X1207877D02*
X1207844Y181187D01*
G01X1207911Y182138D02*
X1207978Y182204D01*
G01X1207877Y183418D02*
X1207944Y183484D01*
G01X1207810D02*
X1207743Y183418D01*
G01X1207911Y184599D02*
X1207844Y184534D01*
G01X1207743Y184665D02*
X1207844Y184763D01*
G01X1207877Y185912D02*
X1207944Y185977D01*
G01X1207810D02*
X1207743Y185912D01*
G01X1207073Y185354D02*
X1207174Y185452D01*
G01X1207978Y187125D02*
X1207911Y187060D01*
G01X1207877Y187256D02*
X1207810Y187191D01*
G01X1207140Y187650D02*
X1207207Y187716D01*
G01X1207040Y187782D02*
X1207107Y187847D01*
G01X1208313Y190341D02*
X1208447Y190472D01*
G01X1207207Y191489D02*
X1207073Y191358D01*
G01X1208413Y193589D02*
X1208313Y193490D01*
G01X1207107Y194310D02*
X1207207Y194409D01*
G01X1207777Y182171D02*
X1207844Y182270D01*
G01X1207944Y183484D02*
X1208011Y183582D01*
G01X1207877D02*
X1207810Y183484D01*
G01X1207241Y182762D02*
X1207174Y182663D01*
G01X1207073Y182827D02*
X1207006Y182729D01*
G01X1207978Y184697D02*
X1207911Y184599D01*
G01X1207944Y185977D02*
X1208011Y186075D01*
G01X1207877D02*
X1207810Y185977D01*
G01X1207207Y185288D02*
X1207140Y185189D01*
G01X1208313Y190636D02*
X1208246Y190537D01*
G01X1207207Y191193D02*
X1207274Y191292D01*
G01X1208346Y193786D02*
X1208279Y193687D01*
G01X1207174Y194113D02*
X1207241Y194212D01*
G01X1208514Y193752D02*
X1208413Y193589D01*
G01X1207006Y194146D02*
X1207107Y194310D01*
G01X1207911Y181286D02*
X1207877Y181220D01*
G01X1207978Y182204D02*
X1208011Y182270D01*
G01X1207844Y184763D02*
X1207877Y184829D01*
G01X1207006Y185223D02*
X1207073Y185354D01*
G01X1208011Y187191D02*
X1207978Y187125D01*
G01X1208447Y190472D02*
X1208514Y190603D01*
G01X1207006Y187716D02*
X1207040Y187782D01*
G01X1207073Y191358D02*
X1207006Y191226D01*
G01X1208011Y180695D02*
X1208045Y180793D01*
G01X1207911D02*
X1207877Y180695D01*
G01X1208011Y181220D02*
X1208045Y181318D01*
G01X1208011Y184796D02*
X1207978Y184697D01*
G01X1208011Y182270D02*
X1208045Y182401D01*
G01X1207844Y182270D02*
X1207877Y182401D01*
G01X1208011Y183582D02*
X1208045Y183713D01*
G01X1207911D02*
X1207877Y183582D01*
G01Y184829D02*
X1207911Y184960D01*
G01X1207174Y182663D02*
X1207140Y182532D01*
G01X1208011Y186075D02*
X1208045Y186207D01*
G01X1207911D02*
X1207877Y186075D01*
G01X1207006Y182729D02*
X1206973Y182598D01*
G01X1208045Y187322D02*
X1208011Y187191D01*
G01X1228725Y179225D02*
Y192119D01*
G01X1228331Y192414D02*
Y199697D01*
G01X1228134Y210721D02*
Y181390D01*
G01X1227800Y192414D02*
Y193792D01*
G01Y189461D02*
Y190839D01*
G01Y186508D02*
Y187886D01*
G01Y183556D02*
Y184934D01*
G01X1227622Y176843D02*
Y172119D01*
G01X1227544Y199697D02*
Y192414D01*
G01X1227032Y172119D02*
Y176843D01*
G01X1226914Y184638D02*
Y183851D01*
G01Y187591D02*
Y186804D01*
G01Y190544D02*
Y189756D01*
G01Y193497D02*
Y192709D01*
G01X1226461Y189264D02*
Y189166D01*
G01Y191134D02*
Y191036D01*
G01X1226441Y172119D02*
Y176174D01*
G01X1226048Y175288D02*
Y174107D01*
G01X1226018Y190544D02*
Y189756D01*
G01X1225969Y181390D02*
Y178437D01*
G01X1225949Y175386D02*
Y174008D01*
G01X1225896Y184638D02*
Y183851D01*
G01Y187591D02*
Y186804D01*
G01Y193497D02*
Y192709D01*
G01X1225752Y175288D02*
Y174107D01*
G01X1225713Y183359D02*
Y183260D01*
G01Y185229D02*
Y185130D01*
G01Y186312D02*
Y186213D01*
G01Y188182D02*
Y188083D01*
G01Y192217D02*
Y192119D01*
G01Y194087D02*
Y193989D01*
G01X1225617Y192709D02*
Y193497D01*
G01Y186804D02*
Y187591D01*
G01Y183851D02*
Y184638D01*
G01X1225531Y189756D02*
Y190544D01*
G01X1225260Y175288D02*
Y174107D01*
G01X1224394Y191036D02*
Y191134D01*
G01Y189166D02*
Y189264D01*
G01Y182827D02*
Y182768D01*
G01Y183359D02*
Y183260D01*
G01Y185229D02*
Y185130D01*
G01Y185780D02*
Y185662D01*
G01Y186312D02*
Y186213D01*
G01Y188733D02*
Y188615D01*
G01Y188182D02*
Y188083D01*
G01Y191686D02*
Y191567D01*
G01Y192217D02*
Y192119D01*
G01Y194087D02*
Y193989D01*
G01X1224355Y184638D02*
Y183851D01*
G01Y187591D02*
Y186804D01*
G01Y190544D02*
Y189756D01*
G01Y193497D02*
Y192709D01*
G01X1224276Y175288D02*
Y174107D01*
G01X1224079Y178437D02*
Y213674D01*
G01Y174107D02*
Y175288D01*
G01X1223961Y184638D02*
Y183851D01*
G01Y187591D02*
Y186804D01*
G01Y190544D02*
Y189756D01*
G01Y193497D02*
Y192709D01*
G01X1223769Y190544D02*
Y189756D01*
G01X1223722Y184638D02*
Y183851D01*
G01Y187591D02*
Y186804D01*
G01Y193497D02*
Y192709D01*
G01X1223607Y184638D02*
Y183851D01*
G01Y187591D02*
Y186804D01*
G01Y193497D02*
Y192709D01*
G01X1223567Y190544D02*
Y189756D01*
G01X1223488Y213674D02*
Y178437D01*
G01X1223370Y184441D02*
Y184048D01*
G01Y187394D02*
Y187000D01*
G01Y190347D02*
Y189953D01*
G01Y193300D02*
Y192906D01*
G01X1223095Y180406D02*
Y211705D01*
G01X1223075Y184934D02*
Y183556D01*
G01Y187886D02*
Y186508D01*
G01Y190839D02*
Y189461D01*
G01Y193792D02*
Y192414D01*
G01X1222504Y175288D02*
Y174107D01*
G01X1222307Y175288D02*
Y174107D01*
G01X1222268Y184638D02*
Y183851D01*
G01Y187591D02*
Y186804D01*
G01Y190544D02*
Y189756D01*
G01Y193497D02*
Y192709D01*
G01X1222071Y190544D02*
Y189756D01*
G01X1222032Y184638D02*
Y183851D01*
G01Y187591D02*
Y186804D01*
G01Y193497D02*
Y192709D01*
G01X1221638Y184835D02*
Y183654D01*
G01Y187788D02*
Y186607D01*
G01Y190741D02*
Y189560D01*
G01Y193693D02*
Y192512D01*
G01X1221520Y178831D02*
Y178437D01*
G01X1221323Y175288D02*
Y174107D01*
G01X1220831Y175288D02*
Y174107D01*
G01X1220634Y174008D02*
Y175386D01*
G01X1220457Y192650D02*
Y193556D01*
G01Y189697D02*
Y190603D01*
G01Y186745D02*
Y187650D01*
G01Y183792D02*
Y184697D01*
G01X1220004Y175288D02*
Y174107D01*
G01X1219826Y175288D02*
Y174107D01*
G01X1219650Y175288D02*
Y174107D01*
G01X1219527Y183654D02*
Y179170D01*
G01Y186607D02*
Y184835D01*
G01Y189560D02*
Y187788D01*
G01Y192512D02*
Y190741D01*
G01Y195465D02*
Y193693D01*
G01X1219363Y175288D02*
Y174107D01*
G01X1208514Y194146D02*
X1208548Y193949D01*
G01X1207006Y193752D02*
X1206973Y193949D01*
G01X1208011Y185189D02*
X1208045Y184993D01*
G01X1208346Y194113D02*
X1208380Y193949D01*
G01X1207911Y187388D02*
X1207877Y187256D01*
G01X1208346Y190767D02*
X1208313Y190636D01*
G01X1207107Y187519D02*
X1207140Y187650D01*
G01X1206973Y187585D02*
X1207006Y187716D01*
G01X1207174Y191062D02*
X1207207Y191193D01*
G01X1208514Y190603D02*
X1208548Y190767D01*
G01X1208380Y193949D02*
X1208346Y193786D01*
G01X1207006Y191226D02*
X1206973Y191062D01*
G01X1207140Y193949D02*
X1207174Y194113D01*
G01X1208045Y184993D02*
X1208011Y184796D01*
G01X1208548Y193949D02*
X1208514Y193752D01*
G01X1206973Y193949D02*
X1207006Y194146D01*
G01X1207140Y185189D02*
X1207107Y184960D01*
G01X1206973Y184993D02*
X1207006Y185223D01*
G01X1219256Y175288D02*
Y174107D01*
G01X1219177Y175288D02*
Y174107D01*
G01X1219158Y175386D02*
Y174008D01*
G01X1218863Y175288D02*
Y174107D01*
G01X1218764Y173615D02*
Y175780D01*
G01X1218370Y176843D02*
Y172119D01*
G01X1218095Y192709D02*
Y193497D01*
G01Y186804D02*
Y187591D01*
G01Y183851D02*
Y184638D01*
G01Y183654D02*
Y180603D01*
G01Y186607D02*
Y184835D01*
G01Y190544D02*
Y189756D01*
G01Y189560D02*
Y187788D01*
G01Y192512D02*
Y190741D01*
G01Y195465D02*
Y193693D01*
G01X1218061Y184638D02*
Y183851D01*
G01Y187591D02*
Y186804D01*
G01Y190544D02*
Y189756D01*
G01Y193497D02*
Y192709D01*
G01X1217899D02*
Y193497D01*
G01Y186804D02*
Y187591D01*
G01Y183851D02*
Y184638D01*
G01X1217897Y189756D02*
Y190544D01*
G01X1217721Y192709D02*
Y193497D01*
G01Y189756D02*
Y190544D01*
G01Y186804D02*
Y187591D01*
G01Y183851D02*
Y184638D01*
G01X1217487Y192709D02*
Y193497D01*
G01Y189756D02*
Y190544D01*
G01Y186804D02*
Y187591D01*
G01Y183851D02*
Y184638D01*
G01X1217199D02*
Y183851D01*
G01Y187591D02*
Y186804D01*
G01Y190544D02*
Y189756D01*
G01Y193497D02*
Y192709D01*
G01X1217170Y192414D02*
Y193792D01*
G01Y189461D02*
Y190839D01*
G01Y186508D02*
Y187886D01*
G01Y183556D02*
Y184934D01*
G01X1216952Y192709D02*
Y193497D01*
G01Y186804D02*
Y187591D01*
G01Y183851D02*
Y184638D01*
G01X1216949Y189756D02*
Y190544D01*
G01X1216618Y192709D02*
Y193497D01*
G01Y189756D02*
Y190544D01*
G01Y186804D02*
Y187591D01*
G01Y183851D02*
Y184638D01*
G01X1216087Y192709D02*
Y193497D01*
G01Y186804D02*
Y187591D01*
G01Y183851D02*
Y184638D01*
G01Y190544D02*
Y189756D01*
G01X1215191Y190544D02*
Y189756D01*
G01X1215069Y184638D02*
Y183851D01*
G01Y187591D02*
Y186804D01*
G01Y193497D02*
Y192709D01*
G01X1214847Y189756D02*
Y190544D01*
G01Y184638D02*
Y183851D01*
G01Y187591D02*
Y186804D01*
G01Y193497D02*
Y192709D01*
G01X1214790D02*
Y193497D01*
G01Y186804D02*
Y187591D01*
G01Y183851D02*
Y184638D01*
G01X1214704Y189756D02*
Y190544D01*
G01X1214516D02*
Y189756D01*
G01X1214513Y184638D02*
Y183851D01*
G01Y187591D02*
Y186804D01*
G01Y193497D02*
Y192709D01*
G01X1214266D02*
Y193497D01*
G01Y189756D02*
Y190544D01*
G01Y186804D02*
Y187591D01*
G01Y183851D02*
Y184638D01*
G01X1213979D02*
Y183851D01*
G01Y187591D02*
Y186804D01*
G01Y190544D02*
Y189756D01*
G01Y193497D02*
Y192709D01*
G01X1213744Y189756D02*
Y190544D01*
G01Y184638D02*
Y183851D01*
G01Y187591D02*
Y186804D01*
G01Y193497D02*
Y192709D01*
G01X1213568Y190544D02*
Y189756D01*
G01X1213566Y184638D02*
Y183851D01*
G01Y187591D02*
Y186804D01*
G01Y193497D02*
Y192709D01*
G01X1213528D02*
Y193497D01*
G01Y186804D02*
Y187591D01*
G01Y183851D02*
Y184638D01*
G01Y190544D02*
Y189756D01*
G01X1213404Y192709D02*
Y193497D01*
G01Y189756D02*
Y190544D01*
G01Y186804D02*
Y187591D01*
G01Y183851D02*
Y184638D01*
G01X1213370Y183654D02*
Y180603D01*
G01Y184638D02*
Y183851D01*
G01Y186607D02*
Y184835D01*
G01Y187591D02*
Y186804D01*
G01Y190544D02*
Y189756D01*
G01Y189560D02*
Y187788D01*
G01Y193497D02*
Y192709D01*
G01Y192512D02*
Y190741D01*
G01Y195465D02*
Y193693D01*
G01X1213134Y192709D02*
Y193497D01*
G01Y186804D02*
Y187591D01*
G01Y183851D02*
Y184638D01*
G01Y190544D02*
Y189756D01*
G01X1213053Y184638D02*
Y183851D01*
G01Y187591D02*
Y186804D01*
G01Y193497D02*
Y192709D01*
G01X1212942Y190544D02*
Y189756D01*
G01X1212937Y184638D02*
Y183851D01*
G01Y187591D02*
Y186804D01*
G01Y193497D02*
Y192709D01*
G01X1212740Y190544D02*
Y189756D01*
G01X1212544Y184441D02*
Y184048D01*
G01Y187394D02*
Y187000D01*
G01Y190347D02*
Y189953D01*
G01Y193300D02*
Y192906D01*
G01X1212445Y184934D02*
Y183556D01*
G01Y187886D02*
Y186508D01*
G01Y190839D02*
Y189461D01*
G01Y193792D02*
Y192414D01*
G01X1212426Y174008D02*
Y173221D01*
G01Y176174D02*
Y175386D01*
G01X1211937Y193693D02*
Y195465D01*
G01Y190741D02*
Y192512D01*
G01Y187788D02*
Y189560D01*
G01Y184835D02*
Y186607D01*
G01Y179170D02*
Y183654D01*
G01X1211796Y179815D02*
Y178437D01*
G01X1211500Y179619D02*
Y177847D01*
G01X1211441Y192709D02*
Y193497D01*
G01Y186804D02*
Y187591D01*
G01Y183851D02*
Y184638D01*
G01Y190544D02*
Y189756D01*
G01X1211244Y190544D02*
Y189756D01*
G01X1211048Y192709D02*
Y193497D01*
G01Y186804D02*
Y187591D01*
G01Y183851D02*
Y184638D01*
G01X1211008Y184697D02*
Y183792D01*
G01Y187650D02*
Y186745D01*
G01Y190603D02*
Y189697D01*
G01Y193556D02*
Y192650D01*
G01X1209827Y184835D02*
Y183654D01*
G01Y187788D02*
Y186607D01*
G01Y190741D02*
Y189560D01*
G01Y193693D02*
Y192512D01*
G01X1208548Y192571D02*
Y192768D01*
G01Y190767D02*
Y191062D01*
G01Y188241D02*
Y188405D01*
G01Y183254D02*
Y183418D01*
G01Y179415D02*
Y179678D01*
G01X1208346Y191062D02*
Y190767D01*
G01X1208339Y174107D02*
Y175288D01*
G01X1208146Y191522D02*
Y191325D01*
G01X1208045Y185747D02*
Y185912D01*
G01Y186207D02*
Y186338D01*
G01Y183713D02*
Y183845D01*
G01Y182401D02*
Y182598D01*
G01Y181941D02*
Y182106D01*
G01Y180793D02*
Y180925D01*
G01Y181318D02*
Y181449D01*
G01Y180465D02*
Y180629D01*
G01Y187585D02*
Y187322D01*
G01X1207911Y181384D02*
Y181286D01*
G01Y180859D02*
Y180793D01*
G01Y187519D02*
Y187388D01*
G01X1207877Y182401D02*
Y182598D01*
G01X1207844Y191030D02*
Y191522D01*
G01X1207725Y175288D02*
Y174107D01*
G01X1207643Y192768D02*
Y193097D01*
G01Y185321D02*
Y184632D01*
G01Y191325D02*
Y191030D01*
G01Y192571D02*
Y192014D01*
G01X1207509Y184599D02*
Y185485D01*
G01Y179842D02*
Y179251D01*
G01X1207442Y193097D02*
Y192768D01*
G01Y192571D02*
Y191784D01*
G01X1207375Y179875D02*
Y179219D01*
G01X1207308Y185485D02*
Y185321D01*
G01X1207174Y190767D02*
Y191062D01*
G01X1207140Y182532D02*
Y182401D01*
G01X1207107Y187388D02*
Y187519D01*
G01X1206973Y187322D02*
Y187585D01*
G01Y179087D02*
Y178890D01*
G01Y180629D02*
Y180465D01*
G01Y180203D02*
Y180006D01*
G01Y181679D02*
Y181515D01*
G01Y181154D02*
Y180990D01*
G01Y183418D02*
Y183254D01*
G01Y182598D02*
Y182401D01*
G01Y184173D02*
Y184008D01*
G01Y185912D02*
Y185747D01*
G01Y186666D02*
Y186502D01*
G01Y188405D02*
Y188241D01*
G01Y191062D02*
Y190767D01*
G01Y192768D02*
Y192571D01*
G01X1206717Y175032D02*
Y174363D01*
G01X1206437Y182106D02*
Y181941D01*
G01X1207911Y184960D02*
X1207877Y185157D01*
G01X1207006Y184796D02*
X1206973Y184993D01*
G01X1208548Y191062D02*
X1208514Y191226D01*
G01X1207174Y193786D02*
X1207140Y193949D01*
G01X1206973Y190767D02*
X1207006Y190603D01*
G01X1208313Y191193D02*
X1208346Y191062D01*
G01X1208011Y187716D02*
X1208045Y187585D01*
G01X1207207Y190636D02*
X1207174Y190767D01*
G01X1207877Y187650D02*
X1207911Y187519D01*
G01X1207877Y186338D02*
X1207911Y186207D01*
G01X1207140Y187256D02*
X1207107Y187388D01*
G01X1207877Y183845D02*
X1207911Y183713D01*
G01X1207006Y187191D02*
X1206973Y187322D01*
G01X1208045Y182598D02*
X1208011Y182729D01*
G01X1207107Y184960D02*
X1207140Y184829D01*
G01Y182401D02*
X1207174Y182270D01*
G01X1206973Y182401D02*
X1207006Y182270D01*
G01X1208045Y186338D02*
X1208011Y186436D01*
G01X1208045Y183845D02*
X1208011Y183943D01*
G01X1207040Y184697D02*
X1207006Y184796D01*
G01X1208045Y181449D02*
X1208011Y181548D01*
G01X1208045Y180925D02*
X1208011Y181023D01*
G01X1208514Y191226D02*
X1208447Y191358D01*
G01X1207006Y190603D02*
X1207073Y190472D01*
G01X1207978Y187782D02*
X1208011Y187716D01*
G01X1207844Y186404D02*
X1207877Y186338D01*
G01X1207040Y187125D02*
X1207006Y187191D01*
G01X1207844Y183910D02*
X1207877Y183845D01*
G01X1207140Y184829D02*
X1207174Y184763D01*
G01X1207877Y182598D02*
X1207810Y182729D01*
G01X1207877Y181449D02*
X1207911Y181384D01*
G01X1207877Y180925D02*
X1207911Y180859D01*
G01X1207006Y182270D02*
X1207040Y182204D01*
G01X1208413Y194310D02*
X1208514Y194146D01*
G01X1207107Y193589D02*
X1207006Y193752D01*
G01X1208279Y194212D02*
X1208346Y194113D01*
G01X1207911Y185354D02*
X1208011Y185189D01*
G01X1207241Y193687D02*
X1207174Y193786D01*
G01X1208246Y191292D02*
X1208313Y191193D01*
G01X1207274Y190537D02*
X1207207Y190636D01*
G01X1208011Y186436D02*
X1207944Y186535D01*
G01X1207877Y185157D02*
X1207810Y185255D01*
G01X1208011Y183943D02*
X1207944Y184041D01*
G01X1207107Y184599D02*
X1207040Y184697D01*
G01X1208011Y182729D02*
X1207944Y182827D01*
G01X1207174Y182270D02*
X1207241Y182171D01*
G01X1228725Y179225D02*
X1229118Y178831D01*
G01X1219527Y179170D02*
X1218095Y180603D01*
G01X1219158Y175386D02*
X1218764Y175780D01*
G01X1208313Y194409D02*
X1208413Y194310D01*
G01X1207207Y193490D02*
X1207107Y193589D01*
G01X1208447Y191358D02*
X1208313Y191489D01*
G01X1207073Y190472D02*
X1207207Y190341D01*
G01X1207911Y187847D02*
X1207978Y187782D01*
G01X1207810Y187716D02*
X1207877Y187650D01*
G01X1207944Y186535D02*
X1207877Y186600D01*
G01X1207207Y187191D02*
X1207140Y187256D01*
G01X1207777Y186469D02*
X1207844Y186404D01*
G01X1207107Y187060D02*
X1207040Y187125D01*
G01X1207944Y184041D02*
X1207877Y184107D01*
G01X1207174Y184763D02*
X1207274Y184665D01*
G01X1207777Y183976D02*
X1207844Y183910D01*
G01X1207174Y184534D02*
X1207107Y184599D01*
G01X1207944Y182827D02*
X1207844Y182926D01*
G01X1208011Y181548D02*
X1207944Y181613D01*
G01X1207844Y181482D02*
X1207877Y181449D01*
G01X1207040Y182204D02*
X1207107Y182138D01*
G01X1208011Y181023D02*
X1207911Y181121D01*
G01X1207844Y180957D02*
X1207877Y180925D01*
G01X1207777Y185452D02*
X1207911Y185354D01*
G01X1208078Y194343D02*
X1208279Y194212D01*
G01X1207442Y193556D02*
X1207241Y193687D01*
G01X1207375Y190472D02*
X1207274Y190537D01*
G01X1207810Y187913D02*
X1207911Y187847D01*
G01X1207710Y187782D02*
X1207810Y187716D01*
G01X1207308Y187125D02*
X1207207Y187191D01*
G01Y186994D02*
X1207107Y187060D01*
G01X1207810Y185255D02*
X1207710Y185321D01*
G01X1207810Y182729D02*
X1207710Y182795D01*
G01X1207241Y182171D02*
X1207341Y182106D01*
G01X1208179Y194475D02*
X1208313Y194409D01*
G01X1207341Y193425D02*
X1207207Y193490D01*
G01Y190341D02*
X1207341Y190275D01*
G01X1207274Y184665D02*
X1207341Y184632D01*
G01X1207308Y184468D02*
X1207174Y184534D01*
G01X1207877Y184107D02*
X1207810Y184140D01*
G01X1207844Y182926D02*
X1207777Y182959D01*
G01X1207107Y182138D02*
X1207174Y182106D01*
G01X1207777Y181515D02*
X1207844Y181482D01*
G01X1207777Y180990D02*
X1207844Y180957D01*
G01X1208078Y194507D02*
X1208179Y194475D01*
G01X1207442Y193392D02*
X1207341Y193425D01*
G01X1208146Y191325D02*
X1208246Y191292D01*
G01X1207710Y187945D02*
X1207810Y187913D01*
G01X1207877Y186600D02*
X1207777Y186633D01*
G01X1207509Y190439D02*
X1207375Y190472D01*
G01X1207609Y193359D02*
X1207442Y193392D01*
G01X1207877Y194376D02*
X1208078Y194343D01*
G01X1207643Y193523D02*
X1207442Y193556D01*
G01X1207944Y181613D02*
X1207777Y181679D01*
G01X1208548Y179678D02*
X1206973Y180203D01*
G01X1207341Y184632D02*
X1207442Y184599D01*
G01X1207710Y182795D02*
X1207609Y182827D01*
G01X1208413Y179547D02*
X1207509Y179842D01*
G01X1206973Y180006D02*
X1207375Y179875D01*
G01X1207442Y186928D02*
X1207207Y186994D01*
G01X1207576Y187978D02*
X1207710Y187945D01*
G01X1207576Y187814D02*
X1207710Y187782D01*
G01X1207442Y187093D02*
X1207308Y187125D01*
G01X1207643Y185485D02*
X1207777Y185452D01*
G01X1207643Y184008D02*
X1207777Y183976D01*
G01Y182959D02*
X1207643Y182991D01*
G01X1208313Y191489D02*
X1208146Y191522D01*
G01X1207341Y190275D02*
X1207509Y190242D01*
G01X1207777Y186633D02*
X1207609Y186666D01*
G01Y186502D02*
X1207777Y186469D01*
G01X1207810Y184140D02*
X1207643Y184173D01*
G01X1207509Y184435D02*
X1207308Y184468D01*
G01X1207643Y194376D02*
X1207877D01*
G01X1225713Y194087D02*
X1224394D01*
G01X1225713Y193989D02*
X1224394D01*
G01X1217170Y193792D02*
X1212445D01*
G01X1227800D02*
X1223075D01*
G01X1213370Y193693D02*
X1209827D01*
G01X1221638D02*
X1218095D01*
G01X1220457Y193556D02*
X1211008D01*
G01X1207877Y193523D02*
X1207643D01*
G01X1222032Y193497D02*
X1226914D01*
G01X1216087D02*
X1211048D01*
G01X1218095D02*
X1216627D01*
G01X1207911Y193359D02*
X1207609D01*
G01X1212544Y193300D02*
X1211441D01*
G01X1223370D02*
X1222268D01*
G01X1207643Y193097D02*
X1207442D01*
G01X1222268Y192906D02*
X1223370D01*
G01X1211441D02*
X1212544D01*
G01X1208548Y192768D02*
X1207643D01*
G01X1207442D02*
X1206973D01*
G01X1222032Y192709D02*
X1226914D01*
G01X1211048D02*
X1216087D01*
G01X1218095D02*
X1216627D01*
G01X1211008Y192650D02*
X1220457D01*
G01X1206973Y192571D02*
X1207442D01*
G01X1208279D02*
X1207643D01*
G01X1213370Y192512D02*
X1209827D01*
G01X1221638D02*
X1218095D01*
G01X1223075Y192414D02*
X1227800D01*
G01X1212445D02*
X1217170D01*
G01X1230103D02*
X1227544D01*
G01X1225713Y192217D02*
X1224394D01*
G01X1228134Y192119D02*
X1229512D01*
G01X1225713D02*
X1224394D01*
G01X1207442Y191784D02*
X1207643D01*
G01X1207844Y191522D02*
X1207341D01*
G01X1207375Y191325D02*
X1207643D01*
G01X1226461Y191134D02*
X1224394D01*
G01X1226461Y191036D02*
X1224394D01*
G01X1207643Y191030D02*
X1207844D01*
G01X1217170Y190839D02*
X1212445D01*
G01X1227800D02*
X1223075D01*
G01X1213370Y190741D02*
X1209827D01*
G01X1221638D02*
X1218095D01*
G01X1220457Y190603D02*
X1211008D01*
G01X1222071Y190544D02*
X1226914D01*
G01X1211244D02*
X1216087D01*
G01X1218095D02*
X1216628D01*
G01X1208011Y190439D02*
X1207509D01*
G01X1212544Y190347D02*
X1211441D01*
G01X1223370D02*
X1222268D01*
G01X1207509Y190242D02*
X1208011D01*
G01X1222268Y189953D02*
X1223370D01*
G01X1211441D02*
X1212544D01*
G01X1222071Y189756D02*
X1226914D01*
G01X1211244D02*
X1216087D01*
G01X1218095D02*
X1216628D01*
G01X1211008Y189697D02*
X1220457D01*
G01X1213370Y189560D02*
X1209827D01*
G01X1221638D02*
X1218095D01*
G01X1223075Y189461D02*
X1227800D01*
G01X1212445D02*
X1217170D01*
G01X1226461Y189264D02*
X1224394D01*
G01X1226461Y189166D02*
X1224394D01*
G01X1208548Y188405D02*
X1206973D01*
G01Y188241D02*
X1208548D01*
G01X1225713Y188182D02*
X1224394D01*
G01X1225713Y188083D02*
X1224394D01*
G01X1207442Y187978D02*
X1207576D01*
G01X1217170Y187886D02*
X1212445D01*
G01X1227800D02*
X1223075D01*
G01X1207442Y187814D02*
X1207576D01*
G01X1213370Y187788D02*
X1209827D01*
G01X1221638D02*
X1218095D01*
G01X1220457Y187650D02*
X1211008D01*
G01X1222032Y187591D02*
X1226914D01*
G01X1216087D02*
X1211048D01*
G01X1218095D02*
X1216627D01*
G01X1212544Y187394D02*
X1211441D01*
G01X1223370D02*
X1222268D01*
G01X1207576Y187093D02*
X1207442D01*
G01X1222268Y187000D02*
X1223370D01*
G01X1211441D02*
X1212544D01*
G01X1207576Y186928D02*
X1207442D01*
G01X1222032Y186804D02*
X1226914D01*
G01X1211048D02*
X1216087D01*
G01X1218095D02*
X1216627D01*
G01X1211008Y186745D02*
X1220457D01*
G01X1207609Y186666D02*
X1206973D01*
G01X1213370Y186607D02*
X1209827D01*
G01X1221638D02*
X1218095D01*
G01X1223075Y186508D02*
X1227800D01*
G01X1212445D02*
X1217170D01*
G01X1206973Y186502D02*
X1207609D01*
G01X1225713Y186312D02*
X1224394D01*
G01X1225713Y186213D02*
X1224394D01*
G01X1207743Y185912D02*
X1206973D01*
G01X1208045D02*
X1207877D01*
G01X1206973Y185747D02*
X1208045D01*
G01X1207509Y185485D02*
X1207643D01*
G01X1207710Y185321D02*
X1207643D01*
G01X1225713Y185229D02*
X1224394D01*
G01X1225713Y185130D02*
X1224394D01*
G01X1217170Y184934D02*
X1212445D01*
G01X1227800D02*
X1223075D01*
G01X1213370Y184835D02*
X1209827D01*
G01X1221638D02*
X1218095D01*
G01X1220457Y184697D02*
X1211008D01*
G01X1222032Y184638D02*
X1226914D01*
G01X1216087D02*
X1211048D01*
G01X1218095D02*
X1216627D01*
G01X1207643Y184632D02*
X1207676D01*
G01X1207442Y184599D02*
X1207509D01*
G01X1212544Y184441D02*
X1211441D01*
G01X1223370D02*
X1222268D01*
G01X1207643Y184173D02*
X1206973D01*
G01X1222268Y184048D02*
X1223370D01*
G01X1211441D02*
X1212544D01*
G01X1206973Y184008D02*
X1207643D01*
G01X1222032Y183851D02*
X1226914D01*
G01X1211048D02*
X1216087D01*
G01X1218095D02*
X1216627D01*
G01X1211008Y183792D02*
X1220457D01*
G01X1213370Y183654D02*
X1209827D01*
G01X1221638D02*
X1218095D01*
G01X1223075Y183556D02*
X1227800D01*
G01X1212445D02*
X1217170D01*
G01X1207743Y183418D02*
X1206973D01*
G01X1208548D02*
X1207877D01*
G01X1225713Y183359D02*
X1224394D01*
G01X1225713Y183260D02*
X1224394D01*
G01X1206973Y183254D02*
X1208548D01*
G01X1207643Y182991D02*
X1207375D01*
G01X1207341Y182106D02*
X1207676D01*
G01X1208045D02*
X1207844D01*
G01X1207174D02*
X1206437D01*
G01Y181941D02*
X1208045D01*
G01X1207777Y181679D02*
X1206973D01*
G01Y181515D02*
X1207777D01*
G01X1229512Y181390D02*
X1225969D01*
G01X1207777Y181154D02*
X1206973D01*
G01Y180990D02*
X1207777D01*
G01X1207810Y180629D02*
X1206973D01*
G01X1208045D02*
X1207944D01*
G01X1218095Y180603D02*
X1213370D01*
G01X1206973Y180465D02*
X1208045D01*
G01X1223488Y180406D02*
X1223095D01*
G01Y179225D02*
X1228725D01*
G01X1219527Y179170D02*
X1211937D01*
G01X1211796Y178831D02*
X1221520D01*
G01X1207442Y194343D02*
X1207643Y194376D01*
G01X1208078Y193556D02*
X1207877Y193523D01*
G01X1207710Y184468D02*
X1207509Y184435D01*
G01X1208078Y193392D02*
X1207911Y193359D01*
G01X1208011Y190242D02*
X1208179Y190275D01*
G01X1207341Y191522D02*
X1207207Y191489D01*
G01X1208146Y190472D02*
X1208011Y190439D01*
G01X1207308Y187782D02*
X1207442Y187814D01*
G01X1207710Y187125D02*
X1207576Y187093D01*
G01X1207710Y186961D02*
X1207576Y186928D01*
G01X1207174Y185452D02*
X1207308Y185485D01*
G01X1207207Y187913D02*
X1207442Y187978D01*
G01X1211500Y177847D02*
X1230103D01*
G01X1236874Y176843D02*
X1218370D01*
G01X1225162Y176666D02*
X1221422D01*
G01X1212426Y176174D02*
X1226441D01*
G01X1228410Y175701D02*
X1232150D01*
G01X1225162Y175682D02*
X1221422D01*
G01X1226441Y175386D02*
X1219158D01*
G01Y174008D02*
X1226441D01*
G01X1236087Y173733D02*
X1226441D01*
G01X1221422Y173713D02*
X1225162D01*
G01X1226441Y173221D02*
X1212426D01*
G01X1221422Y172729D02*
X1225162D01*
G01X1207375Y182991D02*
X1207241Y182959D01*
G01X1206724Y216991D02*
X1206717Y217079D01*
G01X1206743Y216905D02*
X1206724Y216991D01*
G01X1206775Y216823D02*
X1206743Y216905D01*
G01X1212579Y208203D02*
X1212619Y208260D01*
G01X1212553Y208137D02*
X1212579Y208203D01*
G01X1212544Y208063D02*
X1212553Y208137D01*
G01X1212579Y199345D02*
X1212619Y199402D01*
G01X1212553Y199278D02*
X1212579Y199345D01*
G01X1212544Y199205D02*
X1212553Y199278D01*
G01X1212579Y195719D02*
X1212619Y195662D01*
G01X1212553Y195786D02*
X1212579Y195719D01*
G01X1212544Y195859D02*
X1212553Y195786D01*
G01X1212579Y198672D02*
X1212619Y198615D01*
G01X1212553Y198738D02*
X1212579Y198672D01*
G01X1212544Y198812D02*
X1212553Y198738D01*
G01X1212579Y201625D02*
X1212619Y201567D01*
G01X1212553Y201691D02*
X1212579Y201625D01*
G01X1212544Y201764D02*
X1212553Y201691D01*
G01X1212579Y204578D02*
X1212619Y204520D01*
G01X1212553Y204644D02*
X1212579Y204578D01*
G01X1212544Y204717D02*
X1212553Y204644D01*
G01X1212579Y207530D02*
X1212619Y207473D01*
G01X1212553Y207597D02*
X1212579Y207530D01*
G01X1212544Y207670D02*
X1212553Y207597D01*
G01X1223405Y195719D02*
X1223446Y195662D01*
G01X1223379Y195786D02*
X1223405Y195719D01*
G01X1223370Y195859D02*
X1223379Y195786D01*
G01X1223405Y198672D02*
X1223446Y198615D01*
G01X1223379Y198738D02*
X1223405Y198672D01*
G01X1223370Y198812D02*
X1223379Y198738D01*
G01X1223405Y201625D02*
X1223446Y201567D01*
G01X1223379Y201691D02*
X1223405Y201625D01*
G01X1223370Y201764D02*
X1223379Y201691D01*
G01X1223405Y204578D02*
X1223446Y204520D01*
G01X1223379Y204644D02*
X1223405Y204578D01*
G01X1223370Y204717D02*
X1223379Y204644D01*
G01X1223405Y207530D02*
X1223446Y207473D01*
G01X1223379Y207597D02*
X1223405Y207530D01*
G01X1223370Y207670D02*
X1223379Y207597D01*
G01X1223405Y208203D02*
X1223446Y208260D01*
G01X1223379Y208137D02*
X1223405Y208203D01*
G01X1223370Y208063D02*
X1223379Y208137D01*
G01X1223405Y205250D02*
X1223446Y205308D01*
G01X1223379Y205184D02*
X1223405Y205250D01*
G01X1223370Y205111D02*
X1223379Y205184D01*
G01X1223405Y202297D02*
X1223446Y202355D01*
G01X1223379Y202231D02*
X1223405Y202297D01*
G01X1223370Y202158D02*
X1223379Y202231D01*
G01X1223405Y199345D02*
X1223446Y199402D01*
G01X1223379Y199278D02*
X1223405Y199345D01*
G01X1223370Y199205D02*
X1223379Y199278D01*
G01X1223405Y196392D02*
X1223446Y196449D01*
G01X1223379Y196326D02*
X1223405Y196392D01*
G01X1223370Y196252D02*
X1223379Y196326D01*
G01X1212553Y205184D02*
X1212544Y205111D01*
G01X1212579Y205250D02*
X1212553Y205184D01*
G01X1212619Y205308D02*
X1212579Y205250D01*
G01X1212553Y202232D02*
X1212544Y202158D01*
G01X1212579Y202298D02*
X1212553Y202232D01*
G01X1212619Y202355D02*
X1212579Y202298D01*
G01X1212553Y196326D02*
X1212544Y196252D01*
G01X1212579Y196392D02*
X1212553Y196326D01*
G01X1212619Y196449D02*
X1212579Y196392D01*
G01X1221422Y218398D02*
G03Y216430I0J-984D01*
G01X1225162D02*
G03Y218398I0J984D01*
G01X1223095Y211705D02*
G03X1221520Y213280I-1575J0D01*
G01X1225162Y215445D02*
G03Y219382I0J1969D01*
G01X1221422D02*
G03Y215445I0J-1968D01*
G01X1223488Y211705D02*
G03X1221520Y213674I-1968J1D01*
G01X1207978Y197296D02*
X1208112Y197362D01*
G01X1208279Y196640D02*
X1208179Y196574D01*
G01X1207978Y197526D02*
X1207877Y197460D01*
G01X1206973Y197821D02*
X1207777Y198378D01*
G01X1206973Y199396D02*
X1207777Y199953D01*
G01X1206973Y200971D02*
X1207777Y201528D01*
G01X1206973Y202545D02*
X1207777Y203103D01*
G01X1206973Y204120D02*
X1207777Y204678D01*
G01X1206973Y205695D02*
X1207777Y206252D01*
G01X1207911Y198477D02*
X1208548Y198936D01*
G01X1207609Y198477D02*
X1206973Y198018D01*
G01X1207911Y200052D02*
X1208548Y200511D01*
G01X1207609Y200052D02*
X1206973Y199593D01*
G01X1207911Y201626D02*
X1208548Y202086D01*
G01X1207609Y201626D02*
X1206973Y201167D01*
G01X1207911Y203201D02*
X1208548Y203661D01*
G01X1207609Y203201D02*
X1206973Y202742D01*
G01X1207911Y204776D02*
X1208548Y205236D01*
G01X1207609Y204776D02*
X1206973Y204317D01*
G01X1207911Y206351D02*
X1208548Y206810D01*
G01X1207609Y206351D02*
X1206973Y205892D01*
G01X1208548Y199133D02*
X1207777Y198575D01*
G01X1208548Y200708D02*
X1207777Y200150D01*
G01X1208548Y202283D02*
X1207777Y201725D01*
G01X1208548Y203858D02*
X1207777Y203300D01*
G01X1208548Y205432D02*
X1207777Y204875D01*
G01X1208548Y207007D02*
X1207777Y206449D01*
G01X1208313Y196443D02*
X1208447Y196574D01*
G01X1228725Y212886D02*
X1229118Y213280D01*
G01X1218095Y211508D02*
X1219527Y212941D01*
G01X1219158Y216725D02*
X1218764Y216331D01*
G01X1207140Y196377D02*
X1207978Y197296D01*
G01X1207877Y197460D02*
X1207140Y196640D01*
G01X1208346Y196738D02*
X1208279Y196640D01*
G01X1208447Y196574D02*
X1208514Y196705D01*
G01X1228725Y199993D02*
Y212886D01*
G01X1227800Y207178D02*
Y208556D01*
G01Y204225D02*
Y205603D01*
G01Y201272D02*
Y202650D01*
G01Y198319D02*
Y199697D01*
G01Y195367D02*
Y196745D01*
G01X1227622Y219993D02*
Y215268D01*
G01X1227032Y219993D02*
Y215268D01*
G01X1226914Y196449D02*
Y195662D01*
G01Y199402D02*
Y198615D01*
G01Y202355D02*
Y201567D01*
G01Y205308D02*
Y204520D01*
G01Y208260D02*
Y207473D01*
G01X1226461Y198123D02*
Y198024D01*
G01Y199993D02*
Y199894D01*
G01Y206981D02*
Y206882D01*
G01Y208851D02*
Y208752D01*
G01X1226441Y219993D02*
Y215937D01*
G01X1226048Y218004D02*
Y216823D01*
G01X1226018Y199402D02*
Y198615D01*
G01Y208260D02*
Y207473D01*
G01X1225969Y213674D02*
Y210721D01*
G01X1225949Y218103D02*
Y216725D01*
G01X1225896Y196449D02*
Y195662D01*
G01Y202355D02*
Y201567D01*
G01Y205308D02*
Y204520D01*
G01X1225752Y218004D02*
Y216823D01*
G01X1225713Y195170D02*
Y195071D01*
G01Y197040D02*
Y196941D01*
G01Y201075D02*
Y200977D01*
G01Y202945D02*
Y202847D01*
G01Y204028D02*
Y203930D01*
G01Y205898D02*
Y205800D01*
G01X1225617Y204520D02*
Y205308D01*
G01Y201567D02*
Y202355D01*
G01Y195662D02*
Y196449D01*
G01X1225531Y207473D02*
Y208260D01*
G01Y198615D02*
Y199402D01*
G01X1225260Y218004D02*
Y216823D01*
G01X1224394Y208752D02*
Y208851D01*
G01Y206882D02*
Y206981D01*
G01Y199894D02*
Y199993D01*
G01Y198024D02*
Y198123D01*
G01Y194638D02*
Y194520D01*
G01Y195170D02*
Y195071D01*
G01Y197040D02*
Y196941D01*
G01Y197591D02*
Y197473D01*
G01Y200544D02*
Y200426D01*
G01Y201075D02*
Y200977D01*
G01Y203497D02*
Y203378D01*
G01Y202945D02*
Y202847D01*
G01Y204028D02*
Y203930D01*
G01Y206449D02*
Y206331D01*
G01Y205898D02*
Y205800D01*
G01Y209343D02*
Y209284D01*
G01X1224355Y196449D02*
Y195662D01*
G01Y199402D02*
Y198615D01*
G01Y202355D02*
Y201567D01*
G01Y205308D02*
Y204520D01*
G01Y208260D02*
Y207473D01*
G01X1224276Y218004D02*
Y216823D01*
G01X1224079D02*
Y218004D01*
G01X1223961Y196449D02*
Y195662D01*
G01Y199402D02*
Y198615D01*
G01Y202355D02*
Y201567D01*
G01Y205308D02*
Y204520D01*
G01Y208260D02*
Y207473D01*
G01X1223769Y199402D02*
Y198615D01*
G01Y208260D02*
Y207473D01*
G01X1223722Y196449D02*
Y195662D01*
G01Y202355D02*
Y201567D01*
G01Y205308D02*
Y204520D01*
G01X1223607Y196449D02*
Y195662D01*
G01Y202355D02*
Y201567D01*
G01Y205308D02*
Y204520D01*
G01X1223567Y199402D02*
Y198615D01*
G01Y208260D02*
Y207473D01*
G01X1223370Y196252D02*
Y195859D01*
G01Y199205D02*
Y198812D01*
G01Y202158D02*
Y201764D01*
G01Y205111D02*
Y204717D01*
G01Y208063D02*
Y207670D01*
G01X1223075Y196745D02*
Y195367D01*
G01Y199697D02*
Y198319D01*
G01Y202650D02*
Y201272D01*
G01Y205603D02*
Y204225D01*
G01Y208556D02*
Y207178D01*
G01X1222504Y218004D02*
Y216823D01*
G01X1222307Y218004D02*
Y216823D01*
G01X1222268Y196449D02*
Y195662D01*
G01Y199402D02*
Y198615D01*
G01Y202355D02*
Y201567D01*
G01Y205308D02*
Y204520D01*
G01Y208260D02*
Y207473D01*
G01X1222071Y199402D02*
Y198615D01*
G01Y208260D02*
Y207473D01*
G01X1222032Y196449D02*
Y195662D01*
G01Y202355D02*
Y201567D01*
G01Y205308D02*
Y204520D01*
G01X1221638Y196646D02*
Y195465D01*
G01Y199599D02*
Y198418D01*
G01Y202552D02*
Y201371D01*
G01Y205504D02*
Y204323D01*
G01Y208457D02*
Y207276D01*
G01X1221520Y213674D02*
Y213280D01*
G01X1221323Y218004D02*
Y216823D01*
G01X1220831Y218004D02*
Y216823D01*
G01X1220634Y216725D02*
Y218103D01*
G01X1220457Y207414D02*
Y208319D01*
G01Y204461D02*
Y205367D01*
G01Y201508D02*
Y202414D01*
G01Y198556D02*
Y199461D01*
G01Y195603D02*
Y196508D01*
G01X1220004Y218004D02*
Y216823D01*
G01X1219826Y218004D02*
Y216823D01*
G01X1219650Y218004D02*
Y216823D01*
G01X1219527Y198418D02*
Y196646D01*
G01Y201371D02*
Y199599D01*
G01Y204323D02*
Y202552D01*
G01Y207276D02*
Y205504D01*
G01Y212941D02*
Y208457D01*
G01X1219363Y218004D02*
Y216823D01*
G01X1208548Y197066D02*
X1208514Y197263D01*
G01Y209796D02*
X1208548Y209632D01*
G01X1208346Y197197D02*
X1208380Y197034D01*
G01X1207978Y209829D02*
X1208078Y209862D01*
G01X1207944Y210026D02*
X1208045Y210058D01*
G01X1207810Y209927D02*
X1207944Y210026D01*
G01X1207911Y209763D02*
X1207978Y209829D01*
G01X1207743Y209796D02*
X1207810Y209927D01*
G01X1207877Y209665D02*
X1207911Y209763D01*
G01X1208380Y196902D02*
X1208346Y196738D01*
G01X1208514Y196705D02*
X1208548Y196935D01*
G01X1219256Y218004D02*
Y216823D01*
G01X1219177Y218004D02*
Y216823D01*
G01X1219158Y218103D02*
Y216725D01*
G01X1218863Y218004D02*
Y216823D01*
G01X1218764Y216331D02*
Y218497D01*
G01X1218370Y219993D02*
Y215268D01*
G01X1218095Y204520D02*
Y205308D01*
G01Y201567D02*
Y202355D01*
G01Y195662D02*
Y196449D01*
G01Y198418D02*
Y196646D01*
G01Y199402D02*
Y198615D01*
G01Y201371D02*
Y199599D01*
G01Y204323D02*
Y202552D01*
G01Y208260D02*
Y207473D01*
G01Y207276D02*
Y205504D01*
G01Y211508D02*
Y208457D01*
G01X1218061Y196449D02*
Y195662D01*
G01Y199402D02*
Y198615D01*
G01Y202355D02*
Y201567D01*
G01Y205308D02*
Y204520D01*
G01Y208260D02*
Y207473D01*
G01X1217899Y204520D02*
Y205308D01*
G01Y201567D02*
Y202355D01*
G01Y195662D02*
Y196449D01*
G01X1217897Y207473D02*
Y208260D01*
G01Y198615D02*
Y199402D01*
G01X1217721Y207473D02*
Y208260D01*
G01Y204520D02*
Y205308D01*
G01Y201567D02*
Y202355D01*
G01Y198615D02*
Y199402D01*
G01Y195662D02*
Y196449D01*
G01X1217487Y207473D02*
Y208260D01*
G01Y204520D02*
Y205308D01*
G01Y201567D02*
Y202355D01*
G01Y198615D02*
Y199402D01*
G01Y195662D02*
Y196449D01*
G01X1217199D02*
Y195662D01*
G01Y199402D02*
Y198615D01*
G01Y202355D02*
Y201567D01*
G01Y205308D02*
Y204520D01*
G01Y208260D02*
Y207473D01*
G01X1217170Y207178D02*
Y208556D01*
G01Y204225D02*
Y205603D01*
G01Y201272D02*
Y202650D01*
G01Y198319D02*
Y199697D01*
G01Y195367D02*
Y196745D01*
G01X1216952Y204520D02*
Y205308D01*
G01Y201567D02*
Y202355D01*
G01Y195662D02*
Y196449D01*
G01X1216949Y207473D02*
Y208260D01*
G01Y198615D02*
Y199402D01*
G01X1216618Y207473D02*
Y208260D01*
G01Y204520D02*
Y205308D01*
G01Y201567D02*
Y202355D01*
G01Y198615D02*
Y199402D01*
G01Y195662D02*
Y196449D01*
G01X1216087Y204520D02*
Y205308D01*
G01Y201567D02*
Y202355D01*
G01Y195662D02*
Y196449D01*
G01Y199402D02*
Y198615D01*
G01Y208260D02*
Y207473D01*
G01X1215191Y199402D02*
Y198615D01*
G01Y208260D02*
Y207473D01*
G01X1215069Y196449D02*
Y195662D01*
G01Y202355D02*
Y201567D01*
G01Y205308D02*
Y204520D01*
G01X1214847Y207473D02*
Y208260D01*
G01Y198615D02*
Y199402D01*
G01Y196449D02*
Y195662D01*
G01Y202355D02*
Y201567D01*
G01Y205308D02*
Y204520D01*
G01X1214790D02*
Y205308D01*
G01Y201567D02*
Y202355D01*
G01Y195662D02*
Y196449D01*
G01X1214704Y207473D02*
Y208260D01*
G01Y198615D02*
Y199402D01*
G01X1214516D02*
Y198615D01*
G01Y208260D02*
Y207473D01*
G01X1214513Y196449D02*
Y195662D01*
G01Y202355D02*
Y201567D01*
G01Y205308D02*
Y204520D01*
G01X1214266Y207473D02*
Y208260D01*
G01Y204520D02*
Y205308D01*
G01Y201567D02*
Y202355D01*
G01Y198615D02*
Y199402D01*
G01Y195662D02*
Y196449D01*
G01X1213979D02*
Y195662D01*
G01Y199402D02*
Y198615D01*
G01Y202355D02*
Y201567D01*
G01Y205308D02*
Y204520D01*
G01Y208260D02*
Y207473D01*
G01X1213744D02*
Y208260D01*
G01Y198615D02*
Y199402D01*
G01Y196449D02*
Y195662D01*
G01Y202355D02*
Y201567D01*
G01Y205308D02*
Y204520D01*
G01X1213568Y199402D02*
Y198615D01*
G01Y208260D02*
Y207473D01*
G01X1213566Y196449D02*
Y195662D01*
G01Y202355D02*
Y201567D01*
G01Y205308D02*
Y204520D01*
G01X1213528D02*
Y205308D01*
G01Y201567D02*
Y202355D01*
G01Y195662D02*
Y196449D01*
G01Y199402D02*
Y198615D01*
G01Y208260D02*
Y207473D01*
G01X1213404D02*
Y208260D01*
G01Y204520D02*
Y205308D01*
G01Y201567D02*
Y202355D01*
G01Y198615D02*
Y199402D01*
G01Y195662D02*
Y196449D01*
G01X1213370D02*
Y195662D01*
G01Y198418D02*
Y196646D01*
G01Y199402D02*
Y198615D01*
G01Y201371D02*
Y199599D01*
G01Y202355D02*
Y201567D01*
G01Y205308D02*
Y204520D01*
G01Y204323D02*
Y202552D01*
G01Y208260D02*
Y207473D01*
G01Y207276D02*
Y205504D01*
G01Y211508D02*
Y208457D01*
G01X1213134Y204520D02*
Y205308D01*
G01Y201567D02*
Y202355D01*
G01Y195662D02*
Y196449D01*
G01Y199402D02*
Y198615D01*
G01Y208260D02*
Y207473D01*
G01X1213053Y196449D02*
Y195662D01*
G01Y202355D02*
Y201567D01*
G01Y205308D02*
Y204520D01*
G01X1212942Y199402D02*
Y198615D01*
G01Y208260D02*
Y207473D01*
G01X1212937Y196449D02*
Y195662D01*
G01Y202355D02*
Y201567D01*
G01Y205308D02*
Y204520D01*
G01X1212740Y199402D02*
Y198615D01*
G01Y208260D02*
Y207473D01*
G01X1212544Y196252D02*
Y195859D01*
G01Y199205D02*
Y198812D01*
G01Y202158D02*
Y201764D01*
G01Y205111D02*
Y204717D01*
G01Y208063D02*
Y207670D01*
G01X1212445Y196745D02*
Y195367D01*
G01Y199697D02*
Y198319D01*
G01Y202650D02*
Y201272D01*
G01Y205603D02*
Y204225D01*
G01Y208556D02*
Y207178D01*
G01X1212426Y216725D02*
Y215937D01*
G01X1211937Y208457D02*
Y212941D01*
G01Y205504D02*
Y207276D01*
G01Y202552D02*
Y204323D01*
G01Y199599D02*
Y201371D01*
G01Y196646D02*
Y198418D01*
G01X1211796Y213674D02*
Y212296D01*
G01X1211500Y214264D02*
Y212493D01*
G01X1211441Y204520D02*
Y205308D01*
G01Y201567D02*
Y202355D01*
G01Y195662D02*
Y196449D01*
G01Y199402D02*
Y198615D01*
G01Y208260D02*
Y207473D01*
G01X1211244Y199402D02*
Y198615D01*
G01Y208260D02*
Y207473D01*
G01X1211048Y204520D02*
Y205308D01*
G01Y201567D02*
Y202355D01*
G01Y195662D02*
Y196449D01*
G01X1211008Y196508D02*
Y195603D01*
G01Y199461D02*
Y198556D01*
G01Y202414D02*
Y201508D01*
G01Y205367D02*
Y204461D01*
G01Y208319D02*
Y207414D01*
G01X1209827Y196646D02*
Y195465D01*
G01Y199599D02*
Y198418D01*
G01Y202552D02*
Y201371D01*
G01Y205504D02*
Y204323D01*
G01Y208457D02*
Y207276D01*
G01X1208548Y212453D02*
Y212650D01*
G01Y211075D02*
Y211272D01*
G01Y211732D02*
Y211994D01*
G01Y207270D02*
Y207467D01*
G01Y208385D02*
Y208582D01*
G01Y205695D02*
Y205892D01*
G01Y206810D02*
Y207007D01*
G01Y204120D02*
Y204317D01*
G01Y205236D02*
Y205432D01*
G01Y202545D02*
Y202742D01*
G01Y203661D02*
Y203858D01*
G01Y200971D02*
Y201167D01*
G01Y202086D02*
Y202283D01*
G01Y200511D02*
Y200708D01*
G01Y199396D02*
Y199593D01*
G01Y198936D02*
Y199133D01*
G01Y197821D02*
Y198018D01*
G01Y196935D02*
Y197066D01*
G01Y195918D02*
Y196115D01*
G01Y194802D02*
Y194999D01*
G01Y209632D02*
Y208845D01*
G01X1208380Y197034D02*
Y196902D01*
G01Y209665D02*
Y209041D01*
G01X1208339Y216823D02*
Y218004D01*
G01X1208179Y196574D02*
Y196410D01*
G01X1207911Y207467D02*
Y208385D01*
G01Y194999D02*
Y195918D01*
G01X1207877Y209041D02*
Y209665D01*
G01X1207725Y218004D02*
Y216823D01*
G01X1207710Y210354D02*
Y210813D01*
G01Y195918D02*
Y194999D01*
G01Y208385D02*
Y207467D01*
G01X1207676Y209041D02*
Y209599D01*
G01X1207542Y210813D02*
Y210354D01*
G01X1207140Y196640D02*
Y197558D01*
G01X1206973Y208845D02*
Y209041D01*
G01Y209862D02*
Y210091D01*
G01Y194999D02*
Y194802D01*
G01Y196115D02*
Y195918D01*
G01Y198018D02*
Y197821D01*
G01Y197558D02*
Y196377D01*
G01Y199593D02*
Y199396D01*
G01Y199133D02*
Y198936D01*
G01Y201167D02*
Y200971D01*
G01Y202283D02*
Y202086D01*
G01Y200708D02*
Y200511D01*
G01Y202742D02*
Y202545D01*
G01Y203858D02*
Y203661D01*
G01Y204317D02*
Y204120D01*
G01Y205432D02*
Y205236D01*
G01Y205892D02*
Y205695D01*
G01Y207007D02*
Y206810D01*
G01Y207467D02*
Y207270D01*
G01Y208582D02*
Y208385D01*
G01Y211600D02*
Y211338D01*
G01Y212388D02*
Y212125D01*
G01X1206717Y217749D02*
Y217079D01*
G01X1208346Y209763D02*
X1208380Y209665D01*
G01X1208514Y197263D02*
X1208447Y197394D01*
G01X1208279Y197296D02*
X1208346Y197197D01*
G01X1208413Y209927D02*
X1208514Y209796D01*
G01X1228410Y216410D02*
X1226441Y218378D01*
G01X1229512Y212886D02*
X1228725Y213674D01*
G01X1213370Y211508D02*
X1211937Y212941D01*
G01X1208279Y209829D02*
X1208346Y209763D01*
G01X1208447Y197394D02*
X1208313Y197526D01*
G01X1208279Y210026D02*
X1208413Y209927D01*
G01X1207777Y206252D02*
X1208548Y205695D01*
G01X1207777Y204678D02*
X1208548Y204120D01*
G01X1207777Y203103D02*
X1208548Y202545D01*
G01X1207777Y201528D02*
X1208548Y200971D01*
G01X1207777Y199953D02*
X1208548Y199396D01*
G01X1207777Y198378D02*
X1208548Y197821D01*
G01Y205892D02*
X1207911Y206351D01*
G01X1206973Y206810D02*
X1207609Y206351D01*
G01X1208548Y204317D02*
X1207911Y204776D01*
G01X1206973Y205236D02*
X1207609Y204776D01*
G01X1208548Y202742D02*
X1207911Y203201D01*
G01X1206973Y203661D02*
X1207609Y203201D01*
G01X1208548Y201167D02*
X1207911Y201626D01*
G01X1206973Y202086D02*
X1207609Y201626D01*
G01X1208548Y199593D02*
X1207911Y200052D01*
G01X1206973Y200511D02*
X1207609Y200052D01*
G01X1208548Y198018D02*
X1207911Y198477D01*
G01X1206973Y198936D02*
X1207609Y198477D01*
G01X1207777Y206449D02*
X1206973Y207007D01*
G01X1207777Y204875D02*
X1206973Y205432D01*
G01X1207777Y203300D02*
X1206973Y203858D01*
G01X1207777Y201725D02*
X1206973Y202283D01*
G01X1207777Y200150D02*
X1206973Y200708D01*
G01X1207777Y198575D02*
X1206973Y199133D01*
G01X1208179Y197362D02*
X1208279Y197296D01*
G01X1206973Y210091D02*
X1207743Y209796D01*
G01X1207676Y209599D02*
X1206973Y209862D01*
G01X1208179Y210058D02*
X1208279Y210026D01*
G01X1208179Y209862D02*
X1208279Y209829D01*
G01X1208548Y211994D02*
X1207341Y212256D01*
G01X1208313Y197526D02*
X1208179Y197558D01*
G01X1206973Y212125D02*
X1208246Y211863D01*
G01X1207911Y194540D02*
X1208078Y194507D01*
G01X1206973Y211338D02*
X1208548Y211075D01*
G01Y211272D02*
X1207341Y211469D01*
G01X1219158Y216725D02*
X1226441D01*
G01X1225162Y216430D02*
X1221422D01*
G01X1232150Y216410D02*
X1228410D01*
G01X1226441Y215937D02*
X1212426D01*
G01X1225162Y215445D02*
X1221422D01*
G01X1236874Y215268D02*
X1218370D01*
G01X1230103Y214264D02*
X1211500D01*
G01X1221520Y213280D02*
X1211796D01*
G01X1211937Y212941D02*
X1219527D01*
G01X1228725Y212886D02*
X1223095D01*
G01Y211705D02*
X1223488D01*
G01X1218095Y211508D02*
X1213370D01*
G01X1207710Y210813D02*
X1207542D01*
G01X1229512Y210721D02*
X1225969D01*
G01X1207542Y210354D02*
X1207710D01*
G01X1208045Y210058D02*
X1208179D01*
G01X1208078Y209862D02*
X1208179D01*
G01X1206973Y209041D02*
X1207676D01*
G01X1208380D02*
X1207877D01*
G01X1226461Y208851D02*
X1224394D01*
G01X1208548Y208845D02*
X1206973D01*
G01X1226461Y208752D02*
X1224394D01*
G01X1208548Y208582D02*
X1206973D01*
G01X1217170Y208556D02*
X1212445D01*
G01X1227800D02*
X1223075D01*
G01X1213370Y208457D02*
X1209827D01*
G01X1221638D02*
X1218095D01*
G01X1207911Y208385D02*
X1208548D01*
G01X1206973D02*
X1207710D01*
G01X1220457Y208319D02*
X1211008D01*
G01X1222071Y208260D02*
X1226914D01*
G01X1211244D02*
X1216087D01*
G01X1218095D02*
X1216628D01*
G01X1212544Y208063D02*
X1211441D01*
G01X1223370D02*
X1222268D01*
G01Y207670D02*
X1223370D01*
G01X1211441D02*
X1212544D01*
G01X1222071Y207473D02*
X1226914D01*
G01X1211244D02*
X1216087D01*
G01X1218095D02*
X1216628D01*
G01X1207710Y207467D02*
X1206973D01*
G01X1208548D02*
X1207911D01*
G01X1211008Y207414D02*
X1220457D01*
G01X1213370Y207276D02*
X1209827D01*
G01X1221638D02*
X1218095D01*
G01X1206973Y207270D02*
X1208548D01*
G01X1223075Y207178D02*
X1227800D01*
G01X1212445D02*
X1217170D01*
G01X1226461Y206981D02*
X1224394D01*
G01X1226461Y206882D02*
X1224394D01*
G01X1225713Y205898D02*
X1224394D01*
G01X1225713Y205800D02*
X1224394D01*
G01X1217170Y205603D02*
X1212445D01*
G01X1227800D02*
X1223075D01*
G01X1213370Y205504D02*
X1209827D01*
G01X1221638D02*
X1218095D01*
G01X1220457Y205367D02*
X1211008D01*
G01X1222032Y205308D02*
X1226914D01*
G01X1216087D02*
X1211048D01*
G01X1218095D02*
X1216627D01*
G01X1212544Y205111D02*
X1211441D01*
G01X1223370D02*
X1222268D01*
G01Y204717D02*
X1223370D01*
G01X1211441D02*
X1212544D01*
G01X1222032Y204520D02*
X1226914D01*
G01X1211048D02*
X1216087D01*
G01X1218095D02*
X1216627D01*
G01X1211008Y204461D02*
X1220457D01*
G01X1213370Y204323D02*
X1209827D01*
G01X1221638D02*
X1218095D01*
G01X1223075Y204225D02*
X1227800D01*
G01X1212445D02*
X1217170D01*
G01X1225713Y204028D02*
X1224394D01*
G01X1225713Y203930D02*
X1224394D01*
G01X1225713Y202945D02*
X1224394D01*
G01X1225713Y202847D02*
X1224394D01*
G01X1217170Y202650D02*
X1212445D01*
G01X1227800D02*
X1223075D01*
G01X1213370Y202552D02*
X1209827D01*
G01X1221638D02*
X1218095D01*
G01X1220457Y202414D02*
X1211008D01*
G01X1222032Y202355D02*
X1226914D01*
G01X1216087D02*
X1211048D01*
G01X1218095D02*
X1216627D01*
G01X1212544Y202158D02*
X1211441D01*
G01X1223370D02*
X1222268D01*
G01Y201764D02*
X1223370D01*
G01X1211441D02*
X1212544D01*
G01X1222032Y201567D02*
X1226914D01*
G01X1211048D02*
X1216087D01*
G01X1218095D02*
X1216627D01*
G01X1211008Y201508D02*
X1220457D01*
G01X1213370Y201371D02*
X1209827D01*
G01X1221638D02*
X1218095D01*
G01X1223075Y201272D02*
X1227800D01*
G01X1212445D02*
X1217170D01*
G01X1225713Y201075D02*
X1224394D01*
G01X1225713Y200977D02*
X1224394D01*
G01X1228134Y199993D02*
X1229512D01*
G01X1226461D02*
X1224394D01*
G01X1226461Y199894D02*
X1224394D01*
G01X1217170Y199697D02*
X1212445D01*
G01X1227800D02*
X1223075D01*
G01X1230103D02*
X1227544D01*
G01X1213370Y199599D02*
X1209827D01*
G01X1221638D02*
X1218095D01*
G01X1220457Y199461D02*
X1211008D01*
G01X1222071Y199402D02*
X1226914D01*
G01X1211244D02*
X1216087D01*
G01X1218095D02*
X1216628D01*
G01X1212544Y199205D02*
X1211441D01*
G01X1223370D02*
X1222268D01*
G01X1207341Y212256D02*
X1208548Y212453D01*
G01Y212650D02*
X1206973Y212388D01*
G01X1208246Y211863D02*
X1206973Y211600D01*
G01X1207341Y211469D02*
X1208548Y211732D01*
G01X1222268Y198812D02*
X1223370D01*
G01X1211441D02*
X1212544D01*
G01X1222071Y198615D02*
X1226914D01*
G01X1211244D02*
X1216087D01*
G01X1218095D02*
X1216628D01*
G01X1211008Y198556D02*
X1220457D01*
G01X1213370Y198418D02*
X1209827D01*
G01X1221638D02*
X1218095D01*
G01X1223075Y198319D02*
X1227800D01*
G01X1212445D02*
X1217170D01*
G01X1226461Y198123D02*
X1224394D01*
G01X1226461Y198024D02*
X1224394D01*
G01X1207140Y197558D02*
X1206973D01*
G01X1208179D02*
X1208112D01*
G01Y197362D02*
X1208179D01*
G01X1225713Y197040D02*
X1224394D01*
G01X1225713Y196941D02*
X1224394D01*
G01X1217170Y196745D02*
X1212445D01*
G01X1227800D02*
X1223075D01*
G01X1213370Y196646D02*
X1209827D01*
G01X1221638D02*
X1218095D01*
G01X1220457Y196508D02*
X1211008D01*
G01X1222032Y196449D02*
X1226914D01*
G01X1216087D02*
X1211048D01*
G01X1218095D02*
X1216627D01*
G01X1206973Y196377D02*
X1207140D01*
G01X1212544Y196252D02*
X1211441D01*
G01X1223370D02*
X1222268D01*
G01X1208548Y196115D02*
X1206973D01*
G01X1207911Y195918D02*
X1208548D01*
G01X1206973D02*
X1207710D01*
G01X1222268Y195859D02*
X1223370D01*
G01X1211441D02*
X1212544D01*
G01X1222032Y195662D02*
X1226914D01*
G01X1211048D02*
X1216087D01*
G01X1218095D02*
X1216627D01*
G01X1211008Y195603D02*
X1220457D01*
G01X1213370Y195465D02*
X1209827D01*
G01X1221638D02*
X1218095D01*
G01X1223075Y195367D02*
X1227800D01*
G01X1212445D02*
X1217170D01*
G01X1225713Y195170D02*
X1224394D01*
G01X1225713Y195071D02*
X1224394D01*
G01X1207710Y194999D02*
X1206973D01*
G01X1208548D02*
X1207911D01*
G01X1206973Y194802D02*
X1208548D01*
G01X1207609Y194540D02*
X1207911D01*
G01X1207442Y194507D02*
X1207609Y194540D01*
G01X1208112Y197558D02*
X1207978Y197526D01*
G01X1208179Y196410D02*
X1208313Y196443D01*
G01X1209951Y229404D02*
X1210439Y228682D01*
G01X1209951D02*
Y229404D01*
G01X1210439Y228682D02*
X1209951D01*
G01X1219208Y229404D02*
X1218234Y228682D01*
G01X1219696Y230126D02*
X1219208Y229404D01*
G01X1220183Y231569D02*
X1219696Y230126D01*
G01X1220183Y234456D02*
Y231569D01*
G01X1219696Y235900D02*
X1220183Y234456D01*
G01X1219208Y236622D02*
X1219696Y235900D01*
G01X1218234Y237344D02*
X1219208Y236622D01*
G01X1217260D02*
X1218234Y237344D01*
G01X1216772Y235900D02*
X1217260Y236622D01*
G01X1216285Y234456D02*
X1216772Y235900D01*
G01X1216285Y231569D02*
Y234456D01*
G01X1216772Y230126D02*
X1216285Y231569D01*
G01X1217260Y229404D02*
X1216772Y230126D01*
G01X1218234Y228682D02*
X1217260Y229404D01*
G01X1227003D02*
X1226029Y228682D01*
G01X1227491Y230126D02*
X1227003Y229404D01*
G01X1227978Y231569D02*
X1227491Y230126D01*
G01X1227978Y234456D02*
Y231569D01*
G01X1227491Y235900D02*
X1227978Y234456D01*
G01X1227003Y236622D02*
X1227491Y235900D01*
G01X1226029Y237344D02*
X1227003Y236622D01*
G01X1225055D02*
X1226029Y237344D01*
G01X1224568Y235900D02*
X1225055Y236622D01*
G01X1224081Y234456D02*
X1224568Y235900D01*
G01X1224081Y231569D02*
Y234456D01*
G01X1224568Y230126D02*
X1224081Y231569D01*
G01X1225055Y229404D02*
X1224568Y230126D01*
G01X1226029Y228682D02*
X1225055Y229404D01*
G01X1206743Y217923D02*
X1206775Y218004D01*
G01X1206724Y217837D02*
X1206743Y217923D01*
G01X1206717Y217749D02*
X1206724Y217837D01*
G01X1212426Y218890D02*
Y218103D01*
G01X1218764Y218497D02*
X1219158Y218103D01*
G01X1221422Y219382D02*
X1225162D01*
G01X1212426Y218890D02*
X1226441D01*
G01X1221422Y218398D02*
X1225162D01*
G01X1226441Y218378D02*
X1236087D01*
G01X1226441Y218103D02*
X1219158D01*
G01X1215738Y465027D02*
X1219635D01*
G01X1215738Y456365D02*
Y465027D01*
G01X1219635Y456365D02*
X1215738D01*
G01X1207942D02*
Y465027D01*
G01X1209891Y456365D02*
X1207942D01*
G01X1210866Y457087D02*
X1209891Y456365D01*
G01X1211353Y457809D02*
X1210866Y457087D01*
G01X1211840Y458531D02*
X1211353Y457809D01*
G01X1212327Y460696D02*
X1211840Y458531D01*
G01Y462862D02*
X1212327Y460696D01*
G01X1211353Y463583D02*
X1211840Y462862D01*
G01X1210866Y464305D02*
X1211353Y463583D01*
G01X1209891Y465027D02*
X1210866Y464305D01*
G01X1207942Y465027D02*
X1209891D01*
G01X1215738Y460696D02*
X1218174D01*
G01X1208863Y473495D02*
X1207888Y472773D01*
G01X1209350Y474216D02*
X1208863Y473495D01*
G01X1209837Y475660D02*
X1209350Y474216D01*
G01X1209837Y478547D02*
Y475660D01*
G01X1209350Y479991D02*
X1209837Y478547D01*
G01X1208863Y480712D02*
X1209350Y479991D01*
G01X1207888Y481434D02*
X1208863Y480712D01*
G01X1206914D02*
X1207888Y481434D01*
G01X1206427Y479991D02*
X1206914Y480712D01*
G01Y473495D02*
X1206427Y474216D01*
G01X1207888Y472773D02*
X1206914Y473495D01*
G01X1239869Y35449D02*
X1243766D01*
G01X1239869Y26787D02*
Y35449D01*
G01X1243766Y26787D02*
X1239869D01*
G01X1234997Y34727D02*
X1235971Y33284D01*
G01X1234022Y35449D02*
X1234997Y34727D01*
G01X1232074Y35449D02*
X1234022D01*
G01X1232074Y26787D02*
Y35449D01*
G01X1234022Y26787D02*
X1232074D01*
G01X1234997Y27509D02*
X1234022Y26787D01*
G01X1235484Y28231D02*
X1234997Y27509D01*
G01X1235971Y28953D02*
X1235484Y28231D01*
G01X1236459Y31118D02*
X1235971Y28953D01*
G01Y33284D02*
X1236459Y31118D01*
G01X1239869D02*
X1242305D01*
G01X1230079Y40043D02*
X1229105Y39321D01*
G01X1230566Y40765D02*
X1230079Y40043D01*
G01X1231053Y42208D02*
X1230566Y40765D01*
G01X1231053Y45096D02*
Y42208D01*
G01X1230566Y46539D02*
X1231053Y45096D01*
G01X1230079Y47261D02*
X1230566Y46539D01*
G01X1229105Y47983D02*
X1230079Y47261D01*
G01X1237874Y40043D02*
X1236900Y39321D01*
G01X1238361Y40765D02*
X1237874Y40043D01*
G01X1238849Y42208D02*
X1238361Y40765D01*
G01X1238849Y45096D02*
Y42208D01*
G01X1238361Y46539D02*
X1238849Y45096D01*
G01X1237874Y47261D02*
X1238361Y46539D01*
G01X1236900Y47983D02*
X1237874Y47261D01*
G01X1235926D02*
X1236900Y47983D01*
G01X1235438Y46539D02*
X1235926Y47261D01*
G01X1234951Y45096D02*
X1235438Y46539D01*
G01X1234951Y42208D02*
Y45096D01*
G01X1235438Y40765D02*
X1234951Y42208D01*
G01X1235926Y40043D02*
X1235438Y40765D01*
G01X1236900Y39321D02*
X1235926Y40043D01*
G01X1245670D02*
X1244695Y39321D01*
G01X1246157Y40765D02*
X1245670Y40043D01*
G01X1246644Y42208D02*
X1246157Y40765D01*
G01X1246644Y45096D02*
Y42208D01*
G01X1246157Y46539D02*
X1246644Y45096D01*
G01X1245670Y47261D02*
X1246157Y46539D01*
G01X1244695Y47983D02*
X1245670Y47261D01*
G01X1243721D02*
X1244695Y47983D01*
G01X1243233Y46539D02*
X1243721Y47261D01*
G01X1242746Y45096D02*
X1243233Y46539D01*
G01X1242746Y42208D02*
Y45096D01*
G01X1243233Y40765D02*
X1242746Y42208D01*
G01X1243721Y40043D02*
X1243233Y40765D01*
G01X1244695Y39321D02*
X1243721Y40043D01*
G01X1234118Y177670D02*
X1232150Y175701D01*
G01X1237859Y183752D02*
X1236874Y182768D01*
G01X1237859Y183752D02*
Y208359D01*
G01X1236874Y182768D02*
Y172119D01*
G01X1236087Y218378D02*
Y173733D01*
G01X1234118Y177670D02*
Y214441D01*
G01X1232937Y203989D02*
Y188123D01*
G01X1231953Y209343D02*
Y182768D01*
G01X1230103Y177847D02*
Y192414D01*
G01X1229512Y178437D02*
Y213674D01*
G01X1233134Y176686D02*
X1236087Y173733D01*
G01X1229512Y178437D02*
X1230103Y177847D01*
G01X1237859Y190091D02*
X1234118D01*
G01X1237859Y188123D02*
X1232937D01*
G01X1236874Y182768D02*
X1231953D01*
G01X1235300Y214678D02*
X1231208Y212315D01*
G01X1233134Y215426D02*
X1236087Y218378D01*
G01X1229512Y213674D02*
X1230103Y214264D01*
G01X1236874Y219993D02*
Y209343D01*
G01X1235300Y214678D02*
Y209953D01*
G01X1230103Y199697D02*
Y214264D01*
G01X1234118Y214441D02*
X1232150Y216410D01*
G01X1237859Y208359D02*
X1236874Y209343D01*
G01X1231208Y212315D02*
X1235300Y209953D01*
G01X1236874Y209343D02*
X1231953D01*
G01X1237859Y203989D02*
X1232937D01*
G01X1234118Y202020D02*
X1237859D01*
G01X1249533Y226517D02*
X1234257D01*
G01X1258192Y207552D02*
X1249533Y226517D01*
G01X1241267Y627235D02*
G03X1243235Y625266I1969J0D01*
G01D02*
X1258983D01*
G01X1243235Y646920D02*
G03X1241267Y644951I1J-1969D01*
G01D02*
Y627235D01*
G01X1258983Y646920D02*
X1243235D01*
G01X1241267Y692983D02*
G03X1243235Y691014I1969J0D01*
G01D02*
X1258983D01*
G01X1241267Y710699D02*
Y692983D01*
G01X1243235Y712668D02*
G03X1241267Y710699I1J-1969D01*
G01X1258983Y712668D02*
X1243235D01*
G01X1255984Y-224061D02*
Y-314191D01*
G01X1259652Y-269380D02*
X1673307D01*
G01X1265798Y53357D02*
X1265076Y52870D01*
G01X1266520Y54332D02*
X1265798Y53357D01*
G01Y55306D02*
X1266520Y54332D01*
G01X1265076Y55793D02*
X1265798Y55306D01*
G01X1263633Y56280D02*
X1265076Y55793D01*
G01X1260746Y56280D02*
X1263633D01*
G01X1259302Y55793D02*
X1260746Y56280D01*
G01X1258580Y55306D02*
X1259302Y55793D01*
G01X1257859Y54332D02*
X1258580Y55306D01*
G01Y53357D02*
X1257859Y54332D01*
G01X1259302Y52870D02*
X1258580Y53357D01*
G01X1260746Y52383D02*
X1259302Y52870D01*
G01X1262189D02*
X1260746Y52383D01*
G01X1262911Y54332D02*
X1262189Y52870D01*
G01Y55793D02*
X1262911Y54332D01*
G01X1260746Y56280D02*
X1262189Y55793D01*
G01X1265798Y76256D02*
X1265076Y75769D01*
G01X1266520Y77230D02*
X1265798Y76256D01*
G01X1266520Y78204D02*
Y77230D01*
G01X1265798Y79179D02*
X1266520Y78204D01*
G01X1265076Y79666D02*
X1265798Y79179D01*
G01X1263633Y80153D02*
X1265076Y79666D01*
G01X1262189D02*
X1263633Y80153D01*
G01X1261467Y79179D02*
X1262189Y79666D01*
G01X1260746Y78204D02*
X1261467Y79179D01*
G01X1260746Y77230D02*
Y78204D01*
G01X1261467Y76256D02*
X1260746Y77230D01*
G01X1257859Y76743D02*
X1261467Y76256D01*
G01X1257859Y79666D02*
Y76743D01*
G01X1265798Y60665D02*
X1265076Y60178D01*
G01X1266520Y61639D02*
X1265798Y60665D01*
G01X1266520Y62614D02*
Y61639D01*
G01X1265798Y63588D02*
X1266520Y62614D01*
G01X1265076Y64076D02*
X1265798Y63588D01*
G01X1263633Y64563D02*
X1265076Y64076D01*
G01X1262189D02*
X1263633Y64563D01*
G01X1261467Y63588D02*
X1262189Y64076D01*
G01X1260746Y62614D02*
X1261467Y63588D01*
G01X1260746Y61639D02*
Y62614D01*
G01X1261467Y60665D02*
X1260746Y61639D01*
G01X1257859Y61152D02*
X1261467Y60665D01*
G01X1257859Y64076D02*
Y61152D01*
G01X1265798Y69435D02*
X1266520Y69922D01*
G01Y69435D02*
X1265798D01*
G01X1266520Y69922D02*
Y69435D01*
G01X1268685Y109126D02*
Y93741D01*
G01X1265798Y86487D02*
X1266520Y85513D01*
G01X1265076Y86974D02*
X1265798Y86487D01*
G01X1263633Y87462D02*
X1265076Y86974D01*
G01X1260746Y87462D02*
X1263633D01*
G01X1259302Y86974D02*
X1260746Y87462D01*
G01X1258580Y86487D02*
X1259302Y86974D01*
G01X1257859Y85513D02*
X1258580Y86487D01*
G01Y84538D02*
X1257859Y85513D01*
G01X1259302Y84051D02*
X1258580Y84538D01*
G01X1260746Y83564D02*
X1259302Y84051D01*
G01X1263633Y83564D02*
X1260746D01*
G01X1265076Y84051D02*
X1263633Y83564D01*
G01X1265798Y84538D02*
X1265076Y84051D01*
G01X1266520Y85513D02*
X1265798Y84538D01*
G01X1264748Y109126D02*
G03X1268685Y113063I0J3937D01*
G01X1264748Y109126D02*
G03X1268685Y113063I0J3937D01*
G01D02*
Y203615D01*
G01Y113063D02*
Y203615D01*
G01Y207552D02*
X1258192D01*
G01X1272622D02*
G03X1268685Y203615I0J-3937D01*
G01X1272622Y207552D02*
G03X1268685Y203615I0J-3937D01*
G01X1354709Y207552D02*
X1272622D01*
G01X1354709D02*
X1272622D01*
G01X1268685Y275461D02*
G03X1270654Y273492I1969J0D01*
G01X1268685Y289240D02*
Y275461D01*
G01X1270654Y273492D02*
X1376953D01*
G01X1270654Y291209D02*
G03X1268685Y289240I0J-1969D01*
G01X1376953Y291209D02*
X1270654D01*
G01X1261562Y493101D02*
G03X1265499Y497038I0J3937D01*
G01X1261562Y493101D02*
G03X1265499Y497038I0J3937D01*
G01D02*
Y587589D01*
G01Y497038D02*
Y587589D01*
G01X1269436Y591526D02*
G03X1265499Y587589I0J-3937D01*
G01X1269436Y591526D02*
G03X1265499Y587589I0J-3937D01*
G01X1351523Y591526D02*
X1269436D01*
G01X1351523D02*
X1269436D01*
G01X1262330Y628613D02*
X1258983Y625266D01*
G01X1273026Y635797D02*
X1272999Y635727D01*
G01X1273098Y635848D02*
X1273026Y635797D01*
G01X1273196Y635867D02*
X1273098Y635848D01*
G01X1268026Y635797D02*
X1267999Y635727D01*
G01X1268098Y635848D02*
X1268026Y635797D01*
G01X1268196Y635867D02*
X1268098Y635848D01*
G01X1269554D02*
X1269456Y635867D01*
G01X1269626Y635797D02*
X1269554Y635848D01*
G01X1269653Y635727D02*
X1269626Y635797D01*
G01X1269653Y636296D02*
G03X1269456Y636493I-197J0D01*
G01X1268196D02*
G03X1267999Y636296I0J-197D01*
G01X1273196Y636493D02*
G03X1272999Y636296I0J-197D01*
G01X1251739Y633534D02*
G03X1252920Y632353I1181J0D01*
G01Y639833D02*
G03X1251739Y638652I0J-1181D01*
G01X1273196Y635109D02*
Y636493D01*
G01X1272999Y636295D02*
Y635109D01*
G01X1269653D02*
Y636295D01*
G01X1269456Y635109D02*
Y636493D01*
G01X1268196Y635109D02*
Y636493D01*
G01X1267999Y636295D02*
Y635109D01*
G01X1265007D02*
Y640621D01*
G01X1263826Y633928D02*
Y641802D01*
G01X1261464Y632353D02*
Y629203D01*
G01Y642983D02*
Y639833D01*
G01X1260086Y629203D02*
Y642983D01*
G01X1258117Y634912D02*
Y637274D01*
G01X1258983Y646920D02*
X1262330Y643573D01*
G01X1265007Y640621D02*
X1263826Y641802D01*
G01X1256424Y634912D02*
Y637274D01*
G01X1251739Y633534D02*
Y638652D01*
G01X1260086Y633608D02*
X1258117Y634912D01*
G01X1252195Y639584D02*
X1256424Y637274D01*
G01X1265007Y635109D02*
X1263826Y633928D01*
G01X1256424Y634912D02*
X1252195Y632602D01*
G01X1258117Y637274D02*
X1260086Y638578D01*
G01X1262330Y643573D02*
X1298669D01*
G01X1260086Y642983D02*
X1298511D01*
G01X1263826Y641802D02*
X1398826D01*
G01X1265007Y640621D02*
X1397645D01*
G01X1252920Y639833D02*
X1261464D01*
G01X1256424Y637274D02*
X1258117D01*
G01X1269456Y636493D02*
X1268196D01*
G01X1274456D02*
X1273196D01*
G01X1269456Y635867D02*
X1268196D01*
G01X1274456D02*
X1273196D01*
G01X1301464Y635109D02*
X1265007D01*
G01X1258117Y634912D02*
X1256424D01*
G01X1300283Y633928D02*
X1263826D01*
G01X1252920Y632353D02*
X1261464D01*
G01X1260086Y629203D02*
X1402566D01*
G01X1400322Y628613D02*
X1262330D01*
G01X1265499Y659435D02*
G03X1267468Y657467I1968J0D01*
G01X1265499Y673215D02*
Y659435D01*
G01X1267468Y657467D02*
X1373767D01*
G01X1267468Y675183D02*
G03X1265499Y673215I-1J-1968D01*
G01X1373767Y675183D02*
X1267468D01*
G01X1262330Y694361D02*
X1258983Y691014D01*
G01X1273026Y701545D02*
X1272999Y701475D01*
G01X1273098Y701596D02*
X1273026Y701545D01*
G01X1273196Y701615D02*
X1273098Y701596D01*
G01X1268026Y701545D02*
X1267999Y701475D01*
G01X1268098Y701596D02*
X1268026Y701545D01*
G01X1268196Y701615D02*
X1268098Y701596D01*
G01X1269554D02*
X1269456Y701615D01*
G01X1269626Y701545D02*
X1269554Y701596D01*
G01X1269653Y701475D02*
X1269626Y701545D01*
G01X1269653Y702044D02*
G03X1269456Y702241I-197J0D01*
G01X1268196D02*
G03X1267999Y702044I0J-197D01*
G01X1273196Y702241D02*
G03X1272999Y702044I0J-197D01*
G01X1251739Y699282D02*
G03X1252920Y698101I1181J0D01*
G01Y705581D02*
G03X1251739Y704400I0J-1181D01*
G01X1258983Y712668D02*
X1262330Y709321D01*
G01X1265007Y706369D02*
X1263826Y707550D01*
G01X1260086Y699356D02*
X1258117Y700660D01*
G01X1252195Y705332D02*
X1256424Y703022D01*
G01X1262330Y709321D02*
X1298669D01*
G01X1260086Y708731D02*
X1298511D01*
G01X1263826Y707550D02*
X1398826D01*
G01X1273196Y700857D02*
Y702241D01*
G01X1272999Y702043D02*
Y700857D01*
G01X1269653D02*
Y702043D01*
G01X1269456Y700857D02*
Y702241D01*
G01X1268196Y700857D02*
Y702241D01*
G01X1267999Y702043D02*
Y700857D01*
G01X1265007D02*
Y706369D01*
G01X1263826Y699676D02*
Y707550D01*
G01X1261464Y698101D02*
Y694951D01*
G01Y708731D02*
Y705581D01*
G01X1260086Y694951D02*
Y708731D01*
G01X1258117Y700660D02*
Y703022D01*
G01X1265007Y706369D02*
X1397645D01*
G01X1252920Y705581D02*
X1261464D01*
G01X1256424Y703022D02*
X1258117D01*
G01X1269456Y702241D02*
X1268196D01*
G01X1274456D02*
X1273196D01*
G01X1269456Y701615D02*
X1268196D01*
G01X1274456D02*
X1273196D01*
G01X1301464Y700857D02*
X1265007D01*
G01X1258117Y700660D02*
X1256424D01*
G01X1300283Y699676D02*
X1263826D01*
G01X1252920Y698101D02*
X1261464D01*
G01X1260086Y694951D02*
X1402566D01*
G01X1400322Y694361D02*
X1262330D01*
G01X1256424Y700660D02*
Y703022D01*
G01X1251739Y699282D02*
Y704400D01*
G01X1265007Y700857D02*
X1263826Y699676D01*
G01X1256424Y700660D02*
X1252195Y698350D01*
G01X1258117Y703022D02*
X1260086Y704326D01*
G01X1285006Y125072D02*
X1288903D01*
G01X1285493Y127237D02*
X1285006Y125072D01*
G01X1292801D02*
X1296699Y133733D01*
G01X1292801D02*
X1296699Y125072D01*
G01X1288416Y130124D02*
X1286468Y128680D01*
G01X1288903Y130846D02*
X1288416Y130124D01*
G01X1288903Y132289D02*
Y130846D01*
G01X1288416Y133011D02*
X1288903Y132289D01*
G01X1287442Y133733D02*
X1288416Y133011D01*
G01X1286468Y133733D02*
X1287442D01*
G01X1285493Y133011D02*
X1286468Y133733D01*
G01X1285006Y132289D02*
X1285493Y133011D01*
G01X1286468Y128680D02*
X1285493Y127237D01*
G01X1293544Y614282D02*
Y603731D01*
G01X1292225Y610017D02*
Y614282D01*
G01Y603731D02*
Y608670D01*
G01X1286070D02*
Y603731D01*
G01Y614282D02*
Y610017D01*
G01X1284751Y603731D02*
Y614282D01*
G01X1299918Y610690D02*
X1296841Y609119D01*
G01X1295302D02*
X1299479Y611364D01*
G01Y606874D02*
X1295302Y609119D01*
G01X1296841D02*
X1299918Y607547D01*
G01X1292225Y614282D02*
X1293544D01*
G01X1284751D02*
X1286070D01*
G01Y610017D02*
X1292225D01*
G01Y608670D02*
X1286070D01*
G01Y603731D02*
X1284751D01*
G01X1293544D02*
X1292225D01*
G01X1293026Y635797D02*
X1292999Y635727D01*
G01X1293098Y635848D02*
X1293026Y635797D01*
G01X1293196Y635867D02*
X1293098Y635848D01*
G01X1288026Y635797D02*
X1287999Y635727D01*
G01X1288098Y635848D02*
X1288026Y635797D01*
G01X1288196Y635867D02*
X1288098Y635848D01*
G01X1283026Y635797D02*
X1282999Y635727D01*
G01X1283098Y635848D02*
X1283026Y635797D01*
G01X1283196Y635867D02*
X1283098Y635848D01*
G01X1278026Y635797D02*
X1277999Y635727D01*
G01X1278098Y635848D02*
X1278026Y635797D01*
G01X1278196Y635867D02*
X1278098Y635848D01*
G01X1274554D02*
X1274456Y635867D01*
G01X1274626Y635797D02*
X1274554Y635848D01*
G01X1274653Y635727D02*
X1274626Y635797D01*
G01X1279554Y635848D02*
X1279456Y635867D01*
G01X1279626Y635797D02*
X1279554Y635848D01*
G01X1279653Y635727D02*
X1279626Y635797D01*
G01X1284554Y635848D02*
X1284456Y635867D01*
G01X1284626Y635797D02*
X1284554Y635848D01*
G01X1284653Y635727D02*
X1284626Y635797D01*
G01X1289554Y635848D02*
X1289456Y635867D01*
G01X1289626Y635797D02*
X1289554Y635848D01*
G01X1289653Y635727D02*
X1289626Y635797D01*
G01X1294554Y635848D02*
X1294456Y635867D01*
G01X1294626Y635797D02*
X1294554Y635848D01*
G01X1294653Y635727D02*
X1294626Y635797D01*
G01X1274653Y636296D02*
G03X1274456Y636493I-197J0D01*
G01X1279653Y636296D02*
G03X1279456Y636493I-197J0D01*
G01X1278196D02*
G03X1277999Y636296I0J-197D01*
G01X1284653D02*
G03X1284456Y636493I-197J0D01*
G01X1283196D02*
G03X1282999Y636296I0J-197D01*
G01X1289653D02*
G03X1289456Y636493I-197J0D01*
G01X1288196D02*
G03X1287999Y636296I0J-197D01*
G01X1294653D02*
G03X1294456Y636493I-197J0D01*
G01X1293196D02*
G03X1292999Y636296I0J-197D01*
G01X1294653Y635109D02*
Y636295D01*
G01X1294456Y635109D02*
Y636493D01*
G01X1293196Y635109D02*
Y636493D01*
G01X1292999Y636295D02*
Y635109D01*
G01X1289653D02*
Y636295D01*
G01X1289456Y635109D02*
Y636493D01*
G01X1288196Y635109D02*
Y636493D01*
G01X1287999Y636295D02*
Y635109D01*
G01X1284653D02*
Y636295D01*
G01X1284456Y635109D02*
Y636493D01*
G01X1283196Y635109D02*
Y636493D01*
G01X1282999Y636295D02*
Y635109D01*
G01X1279653D02*
Y636295D01*
G01X1279456Y635109D02*
Y636493D01*
G01X1278196Y635109D02*
Y636493D01*
G01X1277999Y636295D02*
Y635109D01*
G01X1274653D02*
Y636295D01*
G01X1274456Y635109D02*
Y636493D01*
G01X1279456D02*
X1278196D01*
G01X1284456D02*
X1283196D01*
G01X1289456D02*
X1288196D01*
G01X1294456D02*
X1293196D01*
G01X1279456Y635867D02*
X1278196D01*
G01X1284456D02*
X1283196D01*
G01X1289456D02*
X1288196D01*
G01X1294456D02*
X1293196D01*
G01X1295945Y690424D02*
Y679873D01*
G01X1294626Y686158D02*
Y690424D01*
G01Y679873D02*
Y684812D01*
G01X1288472D02*
Y679873D01*
G01Y690424D02*
Y686158D01*
G01X1287153Y679873D02*
Y690424D01*
G01X1294626D02*
X1295945D01*
G01X1287153D02*
X1288472D01*
G01Y686158D02*
X1294626D01*
G01Y684812D02*
X1288472D01*
G01Y679873D02*
X1287153D01*
G01X1295945D02*
X1294626D01*
G01X1293026Y701545D02*
X1292999Y701475D01*
G01X1293098Y701596D02*
X1293026Y701545D01*
G01X1293196Y701615D02*
X1293098Y701596D01*
G01X1288026Y701545D02*
X1287999Y701475D01*
G01X1288098Y701596D02*
X1288026Y701545D01*
G01X1288196Y701615D02*
X1288098Y701596D01*
G01X1283026Y701545D02*
X1282999Y701475D01*
G01X1283098Y701596D02*
X1283026Y701545D01*
G01X1283196Y701615D02*
X1283098Y701596D01*
G01X1278026Y701545D02*
X1277999Y701475D01*
G01X1278098Y701596D02*
X1278026Y701545D01*
G01X1278196Y701615D02*
X1278098Y701596D01*
G01X1274554D02*
X1274456Y701615D01*
G01X1274626Y701545D02*
X1274554Y701596D01*
G01X1274653Y701475D02*
X1274626Y701545D01*
G01X1279554Y701596D02*
X1279456Y701615D01*
G01X1279626Y701545D02*
X1279554Y701596D01*
G01X1279653Y701475D02*
X1279626Y701545D01*
G01X1284554Y701596D02*
X1284456Y701615D01*
G01X1284626Y701545D02*
X1284554Y701596D01*
G01X1284653Y701475D02*
X1284626Y701545D01*
G01X1289554Y701596D02*
X1289456Y701615D01*
G01X1289626Y701545D02*
X1289554Y701596D01*
G01X1289653Y701475D02*
X1289626Y701545D01*
G01X1294554Y701596D02*
X1294456Y701615D01*
G01X1294626Y701545D02*
X1294554Y701596D01*
G01X1294653Y701475D02*
X1294626Y701545D01*
G01X1274653Y702044D02*
G03X1274456Y702241I-197J0D01*
G01X1279653Y702044D02*
G03X1279456Y702241I-197J0D01*
G01X1278196D02*
G03X1277999Y702044I0J-197D01*
G01X1284653D02*
G03X1284456Y702241I-197J0D01*
G01X1283196D02*
G03X1282999Y702044I0J-197D01*
G01X1289653D02*
G03X1289456Y702241I-197J0D01*
G01X1288196D02*
G03X1287999Y702044I0J-197D01*
G01X1294653D02*
G03X1294456Y702241I-197J0D01*
G01X1293196D02*
G03X1292999Y702044I0J-197D01*
G01X1294653Y700857D02*
Y702043D01*
G01X1294456Y700857D02*
Y702241D01*
G01X1293196Y700857D02*
Y702241D01*
G01X1292999Y702043D02*
Y700857D01*
G01X1289653D02*
Y702043D01*
G01X1289456Y700857D02*
Y702241D01*
G01X1288196Y700857D02*
Y702241D01*
G01X1287999Y702043D02*
Y700857D01*
G01X1284653D02*
Y702043D01*
G01X1284456Y700857D02*
Y702241D01*
G01X1283196Y700857D02*
Y702241D01*
G01X1282999Y702043D02*
Y700857D01*
G01X1279653D02*
Y702043D01*
G01X1279456Y700857D02*
Y702241D01*
G01X1278196Y700857D02*
Y702241D01*
G01X1277999Y702043D02*
Y700857D01*
G01X1274653D02*
Y702043D01*
G01X1274456Y700857D02*
Y702241D01*
G01X1279456D02*
X1278196D01*
G01X1284456D02*
X1283196D01*
G01X1289456D02*
X1288196D01*
G01X1294456D02*
X1293196D01*
G01X1279456Y701615D02*
X1278196D01*
G01X1284456D02*
X1283196D01*
G01X1289456D02*
X1288196D01*
G01X1294456D02*
X1293196D01*
G01X1295217Y736014D02*
X1296536D01*
G01X1287743D02*
X1289062D01*
G01Y731749D02*
X1295217D01*
G01Y730402D02*
X1289062D01*
G01X1296536Y736014D02*
Y725463D01*
G01X1295217Y731749D02*
Y736014D01*
G01Y725463D02*
Y730402D01*
G01X1289062D02*
Y725463D01*
G01Y736014D02*
Y731749D01*
G01X1287743Y725463D02*
Y736014D01*
G01X1289062Y725463D02*
X1287743D01*
G01X1296536D02*
X1295217D01*
G01X1296929Y-390518D02*
Y-407840D01*
G01X1309853Y125793D02*
X1310340Y125072D01*
G01X1309853D02*
Y125793D01*
G01X1310340Y125072D02*
X1309853D01*
G01X1316674Y125793D02*
X1316187Y126515D01*
G01X1317649Y125072D02*
X1316674Y125793D01*
G01X1318623Y125072D02*
X1317649D01*
G01X1319598Y125793D02*
X1318623Y125072D01*
G01X1320085Y126515D02*
X1319598Y125793D01*
G01X1301084D02*
X1300596Y126515D01*
G01X1302058Y125072D02*
X1301084Y125793D01*
G01X1303032Y125072D02*
X1302058D01*
G01X1304007Y125793D02*
X1303032Y125072D01*
G01X1304981Y127237D02*
X1304007Y125793D01*
G01X1319598Y130124D02*
X1320085Y129402D01*
G01X1318623Y130846D02*
X1319598Y130124D01*
G01X1317649Y130846D02*
X1318623D01*
G01X1316674Y130124D02*
X1317649Y130846D01*
G01X1317161Y133733D02*
X1316674Y130124D01*
G01X1320085Y133733D02*
X1317161D01*
G01X1304981Y127959D02*
Y127237D01*
G01X1304494Y128680D02*
X1304981Y127959D01*
G01X1304007Y129402D02*
X1304494Y128680D01*
G01X1303032Y130124D02*
X1304007Y129402D01*
G01Y130846D02*
X1303032Y130124D01*
G01X1304494Y131567D02*
X1304007Y130846D01*
G01X1304494Y132289D02*
Y131567D01*
G01X1304007Y133011D02*
X1304494Y132289D01*
G01X1303032Y133733D02*
X1304007Y133011D01*
G01X1302058Y133733D02*
X1303032D01*
G01X1301084Y133011D02*
X1302058Y133733D01*
G01Y130124D02*
X1303032D01*
G01X1319138Y246526D02*
Y239048D01*
G01X1316697D02*
Y249019D01*
G01X1315172Y246838D02*
Y239048D01*
G01X1311815D02*
Y246526D01*
G01X1310290D02*
Y239048D01*
G01X1306933D02*
Y246526D01*
G01X1305408D02*
Y239048D01*
G01X1319138D02*
X1320664D01*
G01X1315172D02*
X1316697D01*
G01X1310290D02*
X1311815D01*
G01X1305408D02*
X1306933D01*
G01X1319748Y248085D02*
X1319138Y246526D01*
G01X1315172Y249019D02*
Y248085D01*
G01X1309985Y247150D02*
X1310290Y246526D01*
G01X1315172Y248085D02*
X1314561Y248708D01*
G01Y247462D02*
X1315172Y246838D01*
G01X1311815Y246526D02*
X1312120Y247150D01*
G01X1306933Y246526D02*
X1307238Y247150D01*
G01X1306018Y248085D02*
X1305408Y246526D01*
G01X1310595Y247773D02*
X1309679Y248708D01*
G01Y247462D02*
X1309985Y247150D01*
G01X1312120D02*
X1312426Y247462D01*
G01X1311510Y248708D02*
X1310595Y247773D01*
G01X1307238Y247150D02*
X1307544Y247462D01*
G01X1306628Y248708D02*
X1306018Y248085D01*
G01X1309069Y247773D02*
X1309679Y247462D01*
G01X1314561Y248708D02*
X1313646Y249019D01*
G01Y247773D02*
X1314561Y247462D01*
G01X1309679Y248708D02*
X1308764Y249019D01*
G01X1312426Y247462D02*
X1313036Y247773D01*
G01X1307544Y247462D02*
X1308154Y247773D01*
G01X1312426Y249019D02*
X1311510Y248708D01*
G01X1307544Y249019D02*
X1306628Y248708D01*
G01X1308764Y249019D02*
X1307544D01*
G01X1313646D02*
X1312426D01*
G01X1316697D02*
X1315172D01*
G01X1313036Y247773D02*
X1313646D01*
G01X1308154D02*
X1309069D01*
G01X1310811Y307543D02*
X1311116Y306920D01*
G01X1315388Y307855D02*
X1315998Y307232D01*
G01X1310506Y307855D02*
X1310811Y307543D01*
G01X1317524Y299441D02*
Y309413D01*
G01X1315998Y307232D02*
Y299441D01*
G01X1312642D02*
Y306920D01*
G01X1311116D02*
Y299441D01*
G01X1307760D02*
Y306920D01*
G01X1306235D02*
Y299441D01*
G01X1309896Y308167D02*
X1310506Y307855D01*
G01X1314473Y308167D02*
X1315388Y307855D01*
G01X1312642Y306920D02*
X1312947Y307543D01*
G01X1307760Y306920D02*
X1308065Y307543D01*
G01X1306845Y308478D02*
X1306235Y306920D01*
G01X1315998Y299441D02*
X1317524D01*
G01X1311116D02*
X1312642D01*
G01X1306235D02*
X1307760D01*
G01X1312947Y307543D02*
X1313252Y307855D01*
G01X1308065Y307543D02*
X1308370Y307855D01*
G01X1313252D02*
X1313863Y308167D01*
G01X1308370Y307855D02*
X1308981Y308167D01*
G01X1315998Y308478D02*
X1315388Y309102D01*
G01X1311422Y308167D02*
X1310506Y309102D01*
G01X1315998Y309413D02*
Y308478D01*
G01X1315388Y309102D02*
X1314473Y309413D01*
G01X1310506Y309102D02*
X1309591Y309413D01*
G01D02*
X1308370D01*
G01X1314473D02*
X1313252D01*
G01X1317524D02*
X1315998D01*
G01X1313863Y308167D02*
X1314473D01*
G01X1308981D02*
X1309896D01*
G01X1312337Y309102D02*
X1311422Y308167D01*
G01X1307455Y309102D02*
X1306845Y308478D01*
G01X1313252Y309413D02*
X1312337Y309102D01*
G01X1308370Y309413D02*
X1307455Y309102D01*
G01X1316624Y611588D02*
X1316185Y612711D01*
G01X1316844Y607099D02*
X1316405Y608221D01*
G01X1316185Y610017D02*
X1316624Y610915D01*
G01X1316405Y605302D02*
X1316844Y606425D01*
G01X1309370Y608221D02*
X1308931Y607099D01*
G01X1309590Y612711D02*
X1309151Y611588D01*
G01X1318603Y603731D02*
Y610915D01*
G01X1316844Y606425D02*
Y607099D01*
G01X1316624Y610915D02*
Y611588D01*
G01X1315745Y606425D02*
Y607099D01*
G01X1315525Y611139D02*
Y611588D01*
G01X1310250D02*
Y611139D01*
G01X1310030Y607099D02*
Y606425D01*
G01X1309151Y611588D02*
Y610915D01*
G01X1308931Y607099D02*
Y606425D01*
G01X1307172Y604853D02*
Y603731D01*
G01X1306073D02*
Y604853D01*
G01X1304314Y614282D02*
Y603731D01*
G01X1302996D02*
Y612486D01*
G01X1301677Y610915D02*
Y612711D01*
G01X1308931Y606425D02*
X1309370Y605302D01*
G01X1309151Y610915D02*
X1309590Y610017D01*
G01X1315525Y611588D02*
X1315086Y612262D01*
G01X1310250Y611139D02*
X1310689Y610466D01*
G01X1315745Y607099D02*
X1315086Y607996D01*
G01X1315745Y604629D02*
X1316405Y605302D01*
G01X1315525Y609343D02*
X1316185Y610017D01*
G01X1315086Y605527D02*
X1315745Y606425D01*
G01X1310689Y607996D02*
X1310030Y607099D01*
G01X1315086Y610466D02*
X1315525Y611139D01*
G01X1310689Y612262D02*
X1310250Y611588D01*
G01X1299918Y607547D02*
X1299479Y606874D01*
G01Y611364D02*
X1299918Y610690D01*
G01X1310030Y606425D02*
X1310689Y605527D01*
G01X1316185Y612711D02*
X1315525Y613384D01*
G01X1309590Y610017D02*
X1310250Y609343D01*
G01X1309370Y605302D02*
X1310030Y604629D01*
G01X1314646Y603956D02*
X1315745Y604629D01*
G01X1314206Y609792D02*
X1315086Y610466D01*
G01X1310250Y608894D02*
X1309370Y608221D01*
G01X1311568Y612935D02*
X1310689Y612262D01*
G01X1310250Y613384D02*
X1309590Y612711D01*
G01X1302996Y612486D02*
X1301677Y610915D01*
G01Y612711D02*
X1302996Y614282D01*
G01X1315086Y612262D02*
X1314206Y612935D01*
G01X1316405Y608221D02*
X1315525Y608894D01*
G01X1310689Y610466D02*
X1311568Y609792D01*
G01X1315525Y613384D02*
X1314426Y614058D01*
G01X1314206Y605078D02*
X1315086Y605527D01*
G01Y609119D02*
X1315525Y609343D01*
G01X1311568Y608445D02*
X1310689Y607996D01*
G01Y609119D02*
X1310250Y608894D01*
G01X1311349Y614058D02*
X1310250Y613384D01*
G01X1310030Y604629D02*
X1311129Y603956D01*
G01X1315525Y608894D02*
X1315086Y609119D01*
G01Y607996D02*
X1314206Y608445D01*
G01X1310250Y609343D02*
X1310689Y609119D01*
G01Y605527D02*
X1311568Y605078D01*
G01X1314206Y612935D02*
X1313327Y613160D01*
G01X1311568Y609792D02*
X1312448Y609568D01*
G01X1314206Y608445D02*
X1313327Y608670D01*
G01X1311568Y605078D02*
X1312448Y604853D01*
G01X1314426Y614058D02*
X1313327Y614282D01*
G01X1311129Y603956D02*
X1312228Y603731D01*
G01X1302996Y614282D02*
X1304314D01*
G01X1313327D02*
X1312448D01*
G01X1313327Y613160D02*
X1312448D01*
G01X1318603Y610915D02*
X1319702D01*
G01X1312448Y609568D02*
X1313327D01*
G01Y608670D02*
X1312448D01*
G01Y604853D02*
X1313327D01*
G01X1306073D02*
X1307172D01*
G01X1312228Y603731D02*
X1313547D01*
G01X1304314D02*
X1302996D01*
G01X1307172D02*
X1306073D01*
G01X1319702D02*
X1318603D01*
G01X1312448Y614282D02*
X1311349Y614058D01*
G01X1313547Y603731D02*
X1314646Y603956D01*
G01X1312448Y613160D02*
X1311568Y612935D01*
G01X1313327Y609568D02*
X1314206Y609792D01*
G01X1312448Y608670D02*
X1311568Y608445D01*
G01X1313327Y604853D02*
X1314206Y605078D01*
G01X1298026Y635797D02*
X1297999Y635727D01*
G01X1298098Y635848D02*
X1298026Y635797D01*
G01X1298196Y635867D02*
X1298098Y635848D01*
G01X1301274Y640106D02*
X1301247Y640175D01*
G01X1301346Y640056D02*
X1301274Y640106D01*
G01X1301444Y640037D02*
X1301346Y640056D01*
G01X1304423Y640106D02*
X1304397Y640175D01*
G01X1304495Y640056D02*
X1304423Y640106D01*
G01X1304594Y640037D02*
X1304495Y640056D01*
G01X1307573Y640106D02*
X1307546Y640175D01*
G01X1307645Y640056D02*
X1307573Y640106D01*
G01X1307743Y640037D02*
X1307645Y640056D01*
G01X1310722Y640106D02*
X1310696Y640175D01*
G01X1310794Y640056D02*
X1310722Y640106D01*
G01X1310893Y640037D02*
X1310794Y640056D01*
G01X1313872Y640106D02*
X1313846Y640175D01*
G01X1313944Y640056D02*
X1313872Y640106D01*
G01X1314042Y640037D02*
X1313944Y640056D01*
G01X1317022Y640106D02*
X1316995Y640175D01*
G01X1317094Y640056D02*
X1317022Y640106D01*
G01X1317192Y640037D02*
X1317094Y640056D01*
G01X1302409D02*
X1302310Y640037D01*
G01X1302481Y640106D02*
X1302409Y640056D01*
G01X1302507Y640175D02*
X1302481Y640106D01*
G01X1305558Y640056D02*
X1305460Y640037D01*
G01X1305630Y640106D02*
X1305558Y640056D01*
G01X1305657Y640175D02*
X1305630Y640106D01*
G01X1308708Y640056D02*
X1308609Y640037D01*
G01X1308780Y640106D02*
X1308708Y640056D01*
G01X1308806Y640175D02*
X1308780Y640106D01*
G01X1311857Y640056D02*
X1311759Y640037D01*
G01X1311929Y640106D02*
X1311857Y640056D01*
G01X1311956Y640175D02*
X1311929Y640106D01*
G01X1315007Y640056D02*
X1314909Y640037D01*
G01X1315079Y640106D02*
X1315007Y640056D01*
G01X1315105Y640175D02*
X1315079Y640106D01*
G01X1299554Y635848D02*
X1299456Y635867D01*
G01X1299626Y635797D02*
X1299554Y635848D01*
G01X1299653Y635727D02*
X1299626Y635797D01*
G01X1318157Y640056D02*
X1318058Y640037D01*
G01X1318229Y640106D02*
X1318157Y640056D01*
G01X1318255Y640175D02*
X1318229Y640106D01*
G01X1316995Y639577D02*
G03X1317192Y639380I197J0D01*
G01X1318058D02*
G03X1318255Y639577I0J197D01*
G01X1313846D02*
G03X1314042Y639380I197J0D01*
G01X1314909D02*
G03X1315105Y639577I-1J197D01*
G01X1310696D02*
G03X1310893Y639380I197J0D01*
G01X1311759D02*
G03X1311956Y639577I0J197D01*
G01X1307546D02*
G03X1307743Y639380I197J0D01*
G01X1308609D02*
G03X1308806Y639577I0J197D01*
G01X1304397D02*
G03X1304594Y639380I197J0D01*
G01X1305460D02*
G03X1305657Y639577I0J197D01*
G01X1301247D02*
G03X1301444Y639380I197J0D01*
G01X1302310D02*
G03X1302507Y639577I0J197D01*
G01X1299653Y636296D02*
G03X1299456Y636493I-197J0D01*
G01X1298196D02*
G03X1297999Y636296I0J-197D01*
G01X1318255Y639578D02*
Y640621D01*
G01X1318058Y639380D02*
Y640424D01*
G01X1317192D02*
Y639380D01*
G01X1316995Y640621D02*
Y639578D01*
G01X1315105D02*
Y640621D01*
G01X1314909Y639380D02*
Y640424D01*
G01X1314042D02*
Y639380D01*
G01X1313846Y640621D02*
Y639578D01*
G01X1311956D02*
Y640621D01*
G01X1311759Y639380D02*
Y640424D01*
G01X1310893D02*
Y639380D01*
G01X1310696Y640621D02*
Y639578D01*
G01X1308806D02*
Y640621D01*
G01X1308609Y639380D02*
Y640424D01*
G01X1307743D02*
Y639380D01*
G01X1307546Y640621D02*
Y639578D01*
G01X1305657D02*
Y640621D01*
G01X1305460Y639380D02*
Y640424D01*
G01X1304594D02*
Y639380D01*
G01X1304397Y640621D02*
Y639578D01*
G01X1302507D02*
Y640621D01*
G01X1302310Y639380D02*
Y640424D01*
G01X1301464Y631172D02*
Y635109D01*
G01X1301444Y640424D02*
Y639380D01*
G01X1301247Y640621D02*
Y639578D01*
G01X1300283Y629991D02*
Y633928D01*
G01X1299653Y635109D02*
Y636295D01*
G01X1299456Y635109D02*
Y636493D01*
G01X1298511Y642983D02*
X1299566Y646920D01*
G01X1298196Y635109D02*
Y636493D01*
G01X1297999Y636295D02*
Y635109D01*
G01X1301464Y631172D02*
X1300283Y629991D01*
G01X1301464Y635109D02*
X1300283Y633928D01*
G01X1323086Y646920D02*
X1299566D01*
G01X1323455Y645542D02*
X1299196D01*
G01X1318058Y640424D02*
X1318255D01*
G01X1316995D02*
X1317192D01*
G01X1314909D02*
X1315105D01*
G01X1313846D02*
X1314042D01*
G01X1311759D02*
X1311956D01*
G01X1310696D02*
X1310893D01*
G01X1308609D02*
X1308806D01*
G01X1307546D02*
X1307743D01*
G01X1305460D02*
X1305657D01*
G01X1304397D02*
X1304594D01*
G01X1302310D02*
X1302507D01*
G01X1301247D02*
X1301444D01*
G01X1317192Y640037D02*
X1318058D01*
G01X1314042D02*
X1314909D01*
G01X1310893D02*
X1311759D01*
G01X1307743D02*
X1308609D01*
G01X1304594D02*
X1305460D01*
G01X1301444D02*
X1302310D01*
G01X1317192Y639380D02*
X1318058D01*
G01X1314042D02*
X1314909D01*
G01X1310893D02*
X1311759D01*
G01X1307743D02*
X1308609D01*
G01X1304594D02*
X1305460D01*
G01X1301444D02*
X1302310D01*
G01X1299456Y636493D02*
X1298196D01*
G01X1299456Y635867D02*
X1298196D01*
G01X1321188Y631172D02*
X1301464D01*
G01X1322369Y629991D02*
X1300283D01*
G01X1319026Y687730D02*
X1318586Y688852D01*
G01X1319246Y683240D02*
X1318806Y684363D01*
G01X1311332Y682567D02*
X1311772Y681444D01*
G01X1311552Y687056D02*
X1311992Y686158D01*
G01X1317927Y687730D02*
X1317487Y688403D01*
G01X1312651Y687281D02*
X1313091Y686608D01*
G01X1318147Y683240D02*
X1317487Y684138D01*
G01X1312431Y682567D02*
X1313091Y681669D01*
G01X1318586Y688852D02*
X1317927Y689526D01*
G01X1301880Y687506D02*
X1302320Y686832D01*
G01X1311992Y686158D02*
X1312651Y685485D01*
G01X1311772Y681444D02*
X1312431Y680771D01*
G01X1317487Y688403D02*
X1316608Y689077D01*
G01X1318806Y684363D02*
X1317927Y685036D01*
G01X1313091Y686608D02*
X1313970Y685934D01*
G01X1317927Y689526D02*
X1316828Y690199D01*
G01X1319246Y682567D02*
Y683240D01*
G01X1319026Y687056D02*
Y687730D01*
G01X1318147Y682567D02*
Y683240D01*
G01X1317927Y687281D02*
Y687730D01*
G01X1312651D02*
Y687281D01*
G01X1312431Y683240D02*
Y682567D01*
G01X1311552Y687730D02*
Y687056D01*
G01X1311332Y683240D02*
Y682567D01*
G01X1309574Y680995D02*
Y679873D01*
G01X1308475D02*
Y680995D01*
G01X1306716Y690424D02*
Y679873D01*
G01X1305397D02*
Y688628D01*
G01X1304078Y687056D02*
Y688852D01*
G01X1312431Y680771D02*
X1313531Y680097D01*
G01X1301880Y683015D02*
X1297704Y685261D01*
G01X1317927Y685036D02*
X1317487Y685261D01*
G01Y684138D02*
X1316608Y684587D01*
G01X1312651Y685485D02*
X1313091Y685261D01*
G01Y681669D02*
X1313970Y681220D01*
G01X1299242Y685261D02*
X1302320Y683689D01*
G01X1318806Y681444D02*
X1319246Y682567D01*
G01X1311772Y684363D02*
X1311332Y683240D01*
G01X1316608Y689077D02*
X1315729Y689301D01*
G01X1313970Y685934D02*
X1314850Y685710D01*
G01X1316608Y684587D02*
X1315729Y684812D01*
G01X1313970Y681220D02*
X1314850Y680995D01*
G01X1316828Y690199D02*
X1315729Y690424D01*
G01X1313531Y680097D02*
X1314629Y679873D01*
G01X1317487Y686608D02*
X1317927Y687281D01*
G01X1318586Y686158D02*
X1319026Y687056D01*
G01X1311992Y688852D02*
X1311552Y687730D01*
G01X1305397Y690424D02*
X1306716D01*
G01X1315729D02*
X1314850D01*
G01X1315729Y689301D02*
X1314850D01*
G01X1317487Y681669D02*
X1318147Y682567D01*
G01X1313091Y684138D02*
X1312431Y683240D01*
G01X1313091Y688403D02*
X1312651Y687730D01*
G01X1302320Y683689D02*
X1301880Y683015D01*
G01X1314850Y685710D02*
X1315729D01*
G01Y684812D02*
X1314850D01*
G01Y680995D02*
X1315729D01*
G01X1308475D02*
X1309574D01*
G01X1314629Y679873D02*
X1315948D01*
G01X1306716D02*
X1305397D01*
G01X1309574D02*
X1308475D01*
G01X1318147Y680771D02*
X1318806Y681444D01*
G01X1317927Y685485D02*
X1318586Y686158D01*
G01X1312651Y689526D02*
X1311992Y688852D01*
G01X1305397Y688628D02*
X1304078Y687056D01*
G01Y688852D02*
X1305397Y690424D01*
G01X1314850D02*
X1313750Y690199D01*
G01X1315948Y679873D02*
X1317048Y680097D01*
G01X1314850Y689301D02*
X1313970Y689077D01*
G01X1315729Y685710D02*
X1316608Y685934D01*
G01X1314850Y684812D02*
X1313970Y684587D01*
G01X1317048Y680097D02*
X1318147Y680771D01*
G01X1316608Y685934D02*
X1317487Y686608D01*
G01X1312651Y685036D02*
X1311772Y684363D01*
G01X1313970Y689077D02*
X1313091Y688403D01*
G01X1315729Y680995D02*
X1316608Y681220D01*
G01D02*
X1317487Y681669D01*
G01Y685261D02*
X1317927Y685485D01*
G01X1313970Y684587D02*
X1313091Y684138D01*
G01Y685261D02*
X1312651Y685036D01*
G01X1297704Y685261D02*
X1301880Y687506D01*
G01X1313750Y690199D02*
X1312651Y689526D01*
G01X1302320Y686832D02*
X1299242Y685261D01*
G01X1298026Y701545D02*
X1297999Y701475D01*
G01X1298098Y701596D02*
X1298026Y701545D01*
G01X1298196Y701615D02*
X1298098Y701596D01*
G01X1302409Y705804D02*
X1302310Y705785D01*
G01X1302481Y705854D02*
X1302409Y705804D01*
G01X1302507Y705923D02*
X1302481Y705854D01*
G01X1305558Y705804D02*
X1305460Y705785D01*
G01X1305630Y705854D02*
X1305558Y705804D01*
G01X1305657Y705923D02*
X1305630Y705854D01*
G01X1308708Y705804D02*
X1308609Y705785D01*
G01X1308780Y705854D02*
X1308708Y705804D01*
G01X1308806Y705923D02*
X1308780Y705854D01*
G01X1311857Y705804D02*
X1311759Y705785D01*
G01X1311929Y705854D02*
X1311857Y705804D01*
G01X1311956Y705923D02*
X1311929Y705854D01*
G01X1315007Y705804D02*
X1314909Y705785D01*
G01X1315079Y705854D02*
X1315007Y705804D01*
G01X1315105Y705923D02*
X1315079Y705854D01*
G01X1318157Y705804D02*
X1318058Y705785D01*
G01X1318229Y705854D02*
X1318157Y705804D01*
G01X1318255Y705923D02*
X1318229Y705854D01*
G01X1301274D02*
X1301247Y705923D01*
G01X1301346Y705804D02*
X1301274Y705854D01*
G01X1301444Y705785D02*
X1301346Y705804D01*
G01X1304423Y705854D02*
X1304397Y705923D01*
G01X1304495Y705804D02*
X1304423Y705854D01*
G01X1304594Y705785D02*
X1304495Y705804D01*
G01X1307573Y705854D02*
X1307546Y705923D01*
G01X1307645Y705804D02*
X1307573Y705854D01*
G01X1307743Y705785D02*
X1307645Y705804D01*
G01X1310722Y705854D02*
X1310696Y705923D01*
G01X1310794Y705804D02*
X1310722Y705854D01*
G01X1310893Y705785D02*
X1310794Y705804D01*
G01X1313872Y705854D02*
X1313846Y705923D01*
G01X1313944Y705804D02*
X1313872Y705854D01*
G01X1314042Y705785D02*
X1313944Y705804D01*
G01X1317022Y705854D02*
X1316995Y705923D01*
G01X1317094Y705804D02*
X1317022Y705854D01*
G01X1317192Y705785D02*
X1317094Y705804D01*
G01X1299554Y701596D02*
X1299456Y701615D01*
G01X1299626Y701545D02*
X1299554Y701596D01*
G01X1299653Y701475D02*
X1299626Y701545D01*
G01X1316995Y705325D02*
G03X1317192Y705128I197J0D01*
G01X1318058D02*
G03X1318255Y705325I0J197D01*
G01X1313846D02*
G03X1314042Y705128I197J0D01*
G01X1314909D02*
G03X1315105Y705325I-1J197D01*
G01X1310696D02*
G03X1310893Y705128I197J0D01*
G01X1311759D02*
G03X1311956Y705325I0J197D01*
G01X1307546D02*
G03X1307743Y705128I197J0D01*
G01X1308609D02*
G03X1308806Y705325I0J197D01*
G01X1304397D02*
G03X1304594Y705128I197J0D01*
G01X1305460D02*
G03X1305657Y705325I0J197D01*
G01X1301247D02*
G03X1301444Y705128I197J0D01*
G01X1302310D02*
G03X1302507Y705325I0J197D01*
G01X1299653Y702044D02*
G03X1299456Y702241I-197J0D01*
G01X1298196D02*
G03X1297999Y702044I0J-197D01*
G01X1318255Y705326D02*
Y706369D01*
G01X1318058Y705128D02*
Y706172D01*
G01X1317192D02*
Y705128D01*
G01X1316995Y706369D02*
Y705326D01*
G01X1315105D02*
Y706369D01*
G01X1314909Y705128D02*
Y706172D01*
G01X1314042D02*
Y705128D01*
G01X1313846Y706369D02*
Y705326D01*
G01X1311956D02*
Y706369D01*
G01X1311759Y705128D02*
Y706172D01*
G01X1310893D02*
Y705128D01*
G01X1310696Y706369D02*
Y705326D01*
G01X1308806D02*
Y706369D01*
G01X1308609Y705128D02*
Y706172D01*
G01X1307743D02*
Y705128D01*
G01X1307546Y706369D02*
Y705326D01*
G01X1305657D02*
Y706369D01*
G01X1305460Y705128D02*
Y706172D01*
G01X1304594D02*
Y705128D01*
G01X1304397Y706369D02*
Y705326D01*
G01X1302507D02*
Y706369D01*
G01X1302310Y705128D02*
Y706172D01*
G01X1301464Y696920D02*
Y700857D01*
G01X1301444Y706172D02*
Y705128D01*
G01X1301247Y706369D02*
Y705326D01*
G01X1300283Y695739D02*
Y699676D01*
G01X1299653Y700857D02*
Y702043D01*
G01X1299456Y700857D02*
Y702241D01*
G01X1298196Y700857D02*
Y702241D01*
G01X1297999Y702043D02*
Y700857D01*
G01X1323086Y712668D02*
X1299566D01*
G01X1323455Y711290D02*
X1299196D01*
G01X1298511Y708731D02*
X1299566Y712668D01*
G01X1318058Y706172D02*
X1318255D01*
G01X1316995D02*
X1317192D01*
G01X1314909D02*
X1315105D01*
G01X1313846D02*
X1314042D01*
G01X1311759D02*
X1311956D01*
G01X1310696D02*
X1310893D01*
G01X1308609D02*
X1308806D01*
G01X1307546D02*
X1307743D01*
G01X1305460D02*
X1305657D01*
G01X1304397D02*
X1304594D01*
G01X1302310D02*
X1302507D01*
G01X1301247D02*
X1301444D01*
G01X1317192Y705785D02*
X1318058D01*
G01X1314042D02*
X1314909D01*
G01X1310893D02*
X1311759D01*
G01X1307743D02*
X1308609D01*
G01X1304594D02*
X1305460D01*
G01X1301444D02*
X1302310D01*
G01X1317192Y705128D02*
X1318058D01*
G01X1314042D02*
X1314909D01*
G01X1310893D02*
X1311759D01*
G01X1307743D02*
X1308609D01*
G01X1304594D02*
X1305460D01*
G01X1301444D02*
X1302310D01*
G01X1299456Y702241D02*
X1298196D01*
G01X1299456Y701615D02*
X1298196D01*
G01X1321188Y696920D02*
X1301464D01*
G01X1322369Y695739D02*
X1300283D01*
G01X1301464Y696920D02*
X1300283Y695739D01*
G01X1301464Y700857D02*
X1300283Y699676D01*
G01X1319616Y733321D02*
X1319177Y734443D01*
G01X1319836Y728831D02*
X1319397Y729953D01*
G01X1311923Y728157D02*
X1312363Y727035D01*
G01X1312143Y732647D02*
X1312582Y731749D01*
G01X1318517Y733321D02*
X1318078Y733994D01*
G01X1313242Y732871D02*
X1313681Y732198D01*
G01X1302471Y733096D02*
X1302911Y732423D01*
G01X1318737Y728831D02*
X1318078Y729728D01*
G01X1313022Y728157D02*
X1313681Y727259D01*
G01X1319177Y734443D02*
X1318517Y735117D01*
G01X1312582Y731749D02*
X1313242Y731076D01*
G01X1312363Y727035D02*
X1313022Y726361D01*
G01X1318078Y733994D02*
X1317198Y734667D01*
G01X1319397Y729953D02*
X1318517Y730626D01*
G01X1313681Y732198D02*
X1314561Y731525D01*
G01X1318517Y735117D02*
X1317418Y735790D01*
G01X1313022Y726361D02*
X1314121Y725688D01*
G01X1302471Y728606D02*
X1298294Y730851D01*
G01X1318517Y730626D02*
X1318078Y730851D01*
G01Y729728D02*
X1317198Y730178D01*
G01X1313242Y731076D02*
X1313681Y730851D01*
G01Y727259D02*
X1314561Y726810D01*
G01X1299833Y730851D02*
X1302911Y729280D01*
G01X1317198Y734667D02*
X1316319Y734892D01*
G01X1314561Y731525D02*
X1315440Y731300D01*
G01X1317198Y730178D02*
X1316319Y730402D01*
G01X1314561Y726810D02*
X1315440Y726586D01*
G01X1317418Y735790D02*
X1316319Y736014D01*
G01X1314121Y725688D02*
X1315220Y725463D01*
G01X1318737Y728157D02*
Y728831D01*
G01X1318517Y732871D02*
Y733321D01*
G01X1313242D02*
Y732871D01*
G01X1313022Y728831D02*
Y728157D01*
G01X1312143Y733321D02*
Y732647D01*
G01X1311923Y728831D02*
Y728157D01*
G01X1310164Y726586D02*
Y725463D01*
G01X1309065D02*
Y726586D01*
G01X1307307Y736014D02*
Y725463D01*
G01X1305988D02*
Y734219D01*
G01X1304669Y732647D02*
Y734443D01*
G01X1305988Y736014D02*
X1307307D01*
G01X1316319D02*
X1315440D01*
G01X1316319Y734892D02*
X1315440D01*
G01Y731300D02*
X1316319D01*
G01Y730402D02*
X1315440D01*
G01Y726586D02*
X1316319D01*
G01X1309065D02*
X1310164D01*
G01X1315220Y725463D02*
X1316539D01*
G01X1307307D02*
X1305988D01*
G01X1310164D02*
X1309065D01*
G01X1319397Y727035D02*
X1319836Y728157D01*
G01X1312363Y729953D02*
X1311923Y728831D01*
G01X1312582Y734443D02*
X1312143Y733321D01*
G01X1315440Y736014D02*
X1314341Y735790D01*
G01X1316539Y725463D02*
X1317638Y725688D01*
G01X1315440Y734892D02*
X1314561Y734667D01*
G01X1316319Y731300D02*
X1317198Y731525D01*
G01X1315440Y730402D02*
X1314561Y730178D01*
G01X1316319Y726586D02*
X1317198Y726810D01*
G01X1319177Y731749D02*
X1319616Y732647D01*
G01X1318078Y727259D02*
X1318737Y728157D01*
G01X1313681Y729728D02*
X1313022Y728831D01*
G01X1318078Y732198D02*
X1318517Y732871D01*
G01X1313681Y733994D02*
X1313242Y733321D01*
G01X1302911Y729280D02*
X1302471Y728606D01*
G01X1318737Y726361D02*
X1319397Y727035D01*
G01X1318517Y731076D02*
X1319177Y731749D01*
G01X1305988Y734219D02*
X1304669Y732647D01*
G01Y734443D02*
X1305988Y736014D01*
G01X1313242Y735117D02*
X1312582Y734443D01*
G01X1317638Y725688D02*
X1318737Y726361D01*
G01X1317198Y731525D02*
X1318078Y732198D01*
G01X1313242Y730626D02*
X1312363Y729953D01*
G01X1314561Y734667D02*
X1313681Y733994D01*
G01X1317198Y726810D02*
X1318078Y727259D01*
G01Y730851D02*
X1318517Y731076D01*
G01X1314561Y730178D02*
X1313681Y729728D01*
G01Y730851D02*
X1313242Y730626D01*
G01X1298294Y730851D02*
X1302471Y733096D01*
G01X1314341Y735790D02*
X1313242Y735117D01*
G01X1302911Y732423D02*
X1299833Y730851D01*
G01X1296929Y970112D02*
Y952789D01*
G01X1326905Y125793D02*
X1325931Y125072D01*
G01X1327393Y126515D02*
X1326905Y125793D01*
G01X1324957D02*
X1324470Y126515D01*
G01X1325931Y125072D02*
X1324957Y125793D01*
G01X1320572Y127959D02*
X1320085Y126515D01*
G01Y129402D02*
X1320572Y127959D01*
G01X1327880D02*
X1327393Y126515D01*
G01X1327880Y130846D02*
Y127959D01*
G01X1327393Y132289D02*
X1327880Y130846D01*
G01X1326905Y133011D02*
X1327393Y132289D01*
G01X1325931Y133733D02*
X1326905Y133011D01*
G01X1324957D02*
X1325931Y133733D01*
G01X1324470Y132289D02*
X1324957Y133011D01*
G01X1323982Y130846D02*
X1324470Y132289D01*
G01X1323982Y127959D02*
Y130846D01*
G01X1324470Y126515D02*
X1323982Y127959D01*
G01X1332868Y240606D02*
Y239048D01*
G01X1330427D02*
Y249019D01*
G01X1328902Y246838D02*
Y239048D01*
G01X1325546D02*
Y246526D01*
G01X1324020D02*
Y239048D01*
G01X1320664D02*
Y246526D01*
G01X1332868Y239048D02*
X1343853D01*
G01X1328902D02*
X1330427D01*
G01X1324020D02*
X1325546D01*
G01X1332868Y249643D02*
X1333174Y248396D01*
G01X1335309D02*
X1334699Y249643D01*
G01X1333174Y251512D02*
X1332868Y250266D01*
G01X1334699Y249643D02*
Y250266D01*
G01X1332868D02*
Y249643D01*
G01X1328902Y249019D02*
Y248085D01*
G01X1323715Y247150D02*
X1324020Y246526D01*
G01X1341412Y251201D02*
X1342022Y250266D01*
G01X1333174Y248396D02*
X1333784Y247462D01*
G01X1343242Y251512D02*
X1342022Y252759D01*
G01X1325546Y246526D02*
X1325851Y247150D01*
G01X1328902Y248085D02*
X1328292Y248708D01*
G01Y247462D02*
X1328902Y246838D01*
G01X1324325Y247773D02*
X1323410Y248708D01*
G01Y247462D02*
X1323715Y247150D01*
G01X1343853Y240606D02*
X1335309Y248396D01*
G01X1333784Y247462D02*
X1341412Y240606D01*
G01X1334699Y250266D02*
X1335309Y251201D01*
G01X1320664Y246526D02*
X1320969Y247150D01*
G01X1340496Y251824D02*
X1341412Y251201D01*
G01X1342022Y252759D02*
X1340801Y253382D01*
G01X1334394Y252759D02*
X1333174Y251512D01*
G01X1325851Y247150D02*
X1326156Y247462D01*
G01X1325240Y248708D02*
X1324325Y247773D01*
G01X1320969Y247150D02*
X1321274Y247462D01*
G01X1320359Y248708D02*
X1319748Y248085D01*
G01X1322800Y247773D02*
X1323410Y247462D01*
G01X1335309Y251201D02*
X1336225Y251824D01*
G01X1328292Y248708D02*
X1327376Y249019D01*
G01Y247773D02*
X1328292Y247462D01*
G01X1323410Y248708D02*
X1322494Y249019D01*
G01X1338971Y252136D02*
X1340496Y251824D01*
G01X1326156Y247462D02*
X1326766Y247773D01*
G01X1335614Y253382D02*
X1334394Y252759D01*
G01X1321274Y247462D02*
X1321884Y247773D01*
G01X1340801Y253382D02*
X1338666Y253693D01*
G01X1326156Y249019D02*
X1325240Y248708D01*
G01X1321274Y249019D02*
X1320359Y248708D01*
G01X1338666Y253693D02*
X1337445D01*
G01X1337750Y252136D02*
X1338971D01*
G01X1342022Y250266D02*
X1343548D01*
G01X1322494Y249019D02*
X1321274D01*
G01X1327376D02*
X1326156D01*
G01X1330427D02*
X1328902D01*
G01X1326766Y247773D02*
X1327376D01*
G01X1321884D02*
X1322800D01*
G01X1341412Y240606D02*
X1332868D01*
G01X1337445Y253693D02*
X1335614Y253382D01*
G01X1336225Y251824D02*
X1337750Y252136D01*
G01X1334000Y308790D02*
X1334611Y307855D01*
G01X1324542Y307543D02*
X1324847Y306920D01*
G01X1329118Y307855D02*
X1329729Y307232D01*
G01X1324237Y307855D02*
X1324542Y307543D01*
G01X1344679Y301000D02*
X1336136Y308790D01*
G01X1334611Y307855D02*
X1342238Y301000D01*
G01X1333695D02*
Y299441D01*
G01X1331254D02*
Y309413D01*
G01X1329729Y307232D02*
Y299441D01*
G01X1326372D02*
Y306920D01*
G01X1324847D02*
Y299441D01*
G01X1323626Y308167D02*
X1324237Y307855D01*
G01X1321490Y299441D02*
Y306920D01*
G01X1319965D02*
Y299441D01*
G01X1328203Y308167D02*
X1329118Y307855D01*
G01X1320575Y308478D02*
X1319965Y306920D01*
G01X1326372D02*
X1326677Y307543D01*
G01X1321490Y306920D02*
X1321796Y307543D01*
G01X1342238Y301000D02*
X1333695D01*
G01Y299441D02*
X1344679D01*
G01X1329729D02*
X1331254D01*
G01X1324847D02*
X1326372D01*
G01X1319965D02*
X1321490D01*
G01X1326677Y307543D02*
X1326983Y307855D01*
G01X1321796Y307543D02*
X1322101Y307855D01*
G01X1326983D02*
X1327593Y308167D01*
G01X1322101Y307855D02*
X1322711Y308167D01*
G01X1333695Y310036D02*
X1334000Y308790D01*
G01X1336136D02*
X1335526Y310036D01*
G01X1342238Y311595D02*
X1342849Y310660D01*
G01X1329729Y308478D02*
X1329118Y309102D01*
G01X1325152Y308167D02*
X1324237Y309102D01*
G01X1341323Y312218D02*
X1342238Y311595D01*
G01X1335526Y310036D02*
Y310660D01*
G01X1333695D02*
Y310036D01*
G01X1329729Y309413D02*
Y308478D01*
G01X1342849Y313152D02*
X1341628Y313776D01*
G01X1334000Y311906D02*
X1333695Y310660D01*
G01X1329118Y309102D02*
X1328203Y309413D01*
G01X1324237Y309102D02*
X1323321Y309413D01*
G01X1339798Y312529D02*
X1341323Y312218D01*
G01X1341628Y313776D02*
X1339492Y314087D01*
G01X1335526Y310660D02*
X1336136Y311595D01*
G01X1339492Y314087D02*
X1338272D01*
G01X1338577Y312529D02*
X1339798D01*
G01X1323321Y309413D02*
X1322101D01*
G01X1328203D02*
X1326983D01*
G01X1331254D02*
X1329729D01*
G01X1327593Y308167D02*
X1328203D01*
G01X1322711D02*
X1323626D01*
G01X1338272Y314087D02*
X1336441Y313776D01*
G01X1335221Y313152D02*
X1334000Y311906D01*
G01X1326067Y309102D02*
X1325152Y308167D01*
G01X1321185Y309102D02*
X1320575Y308478D01*
G01X1337051Y312218D02*
X1338577Y312529D01*
G01X1336136Y311595D02*
X1337051Y312218D01*
G01X1336441Y313776D02*
X1335221Y313152D01*
G01X1326983Y309413D02*
X1326067Y309102D01*
G01X1322101Y309413D02*
X1321185Y309102D01*
G01X1336188Y610241D02*
X1336627Y609119D01*
G01X1333330Y609568D02*
X1333111Y609119D01*
G01X1336627D02*
Y603731D01*
G01X1335529D02*
Y609119D01*
G01X1333111D02*
Y603731D01*
G01X1332011D02*
Y609119D01*
G01X1329594Y609343D02*
Y603731D01*
G01Y610915D02*
Y610241D01*
G01X1328494Y603731D02*
Y610915D01*
G01X1326736Y609119D02*
Y603731D01*
G01X1325637D02*
Y609119D01*
G01X1323219D02*
Y603731D01*
G01X1322120D02*
Y609119D01*
G01X1319702Y609343D02*
Y603731D01*
G01Y610915D02*
Y610241D01*
G01X1326296D02*
X1326736Y609119D01*
G01X1335529D02*
X1335309Y609568D01*
G01X1332011Y609119D02*
X1331792Y609568D01*
G01X1325637Y609119D02*
X1325417Y609568D01*
G01X1322120Y609119D02*
X1321900Y609568D01*
G01X1323438D02*
X1323219Y609119D01*
G01X1335748Y610690D02*
X1336188Y610241D01*
G01X1335309Y609568D02*
X1335089Y609792D01*
G01X1332231Y610690D02*
X1332891Y610017D01*
G01X1333550Y609792D02*
X1333330Y609568D01*
G01X1332891Y610017D02*
X1333550Y610690D01*
G01X1330033Y609792D02*
X1329594Y609343D01*
G01Y610241D02*
X1330033Y610690D01*
G01X1323659Y609792D02*
X1323438Y609568D01*
G01X1322999Y610017D02*
X1323659Y610690D01*
G01X1320141Y609792D02*
X1319702Y609343D01*
G01Y610241D02*
X1320141Y610690D01*
G01X1331792Y609568D02*
X1331572Y609792D01*
G01X1325857Y610690D02*
X1326296Y610241D01*
G01X1325417Y609568D02*
X1325197Y609792D01*
G01X1322340Y610690D02*
X1322999Y610017D01*
G01X1321900Y609568D02*
X1321680Y609792D01*
G01X1333990Y610017D02*
X1333550Y609792D01*
G01X1324098Y610017D02*
X1323659Y609792D01*
G01X1335089D02*
X1334649Y610017D01*
G01X1331572Y609792D02*
X1331132Y610017D01*
G01X1325197Y609792D02*
X1324757Y610017D01*
G01X1321680Y609792D02*
X1321240Y610017D01*
G01X1333550Y610690D02*
X1334210Y610915D01*
G01X1330692Y610017D02*
X1330033Y609792D01*
G01Y610690D02*
X1330692Y610915D01*
G01X1323659Y610690D02*
X1324318Y610915D01*
G01X1320801Y610017D02*
X1320141Y609792D01*
G01Y610690D02*
X1320801Y610915D01*
G01X1335089D02*
X1335748Y610690D01*
G01X1331572Y610915D02*
X1332231Y610690D01*
G01X1325197Y610915D02*
X1325857Y610690D01*
G01X1321680Y610915D02*
X1322340Y610690D01*
G01X1334210Y610915D02*
X1335089D01*
G01X1330692D02*
X1331572D01*
G01X1328494D02*
X1329594D01*
G01X1324318D02*
X1325197D01*
G01X1320801D02*
X1321680D01*
G01X1321240Y610017D02*
X1320801D01*
G01X1324757D02*
X1324098D01*
G01X1331132D02*
X1330692D01*
G01X1334649D02*
X1333990D01*
G01X1323219Y603731D02*
X1322120D01*
G01X1326736D02*
X1325637D01*
G01X1329594D02*
X1328494D01*
G01X1333111D02*
X1332011D01*
G01X1336627D02*
X1335529D01*
G01X1338026Y635797D02*
X1337999Y635727D01*
G01X1338098Y635848D02*
X1338026Y635797D01*
G01X1338196Y635867D02*
X1338098Y635848D01*
G01X1333026Y635797D02*
X1332999Y635727D01*
G01X1333098Y635848D02*
X1333026Y635797D01*
G01X1333196Y635867D02*
X1333098Y635848D01*
G01X1328026Y635797D02*
X1327999Y635727D01*
G01X1328098Y635848D02*
X1328026Y635797D01*
G01X1328196Y635867D02*
X1328098Y635848D01*
G01X1323026Y635797D02*
X1322999Y635727D01*
G01X1323098Y635848D02*
X1323026Y635797D01*
G01X1323196Y635867D02*
X1323098Y635848D01*
G01X1320171Y640106D02*
X1320145Y640175D01*
G01X1320243Y640056D02*
X1320171Y640106D01*
G01X1320342Y640037D02*
X1320243Y640056D01*
G01X1321306D02*
X1321208Y640037D01*
G01X1321378Y640106D02*
X1321306Y640056D01*
G01X1321405Y640175D02*
X1321378Y640106D01*
G01X1324554Y635848D02*
X1324456Y635867D01*
G01X1324626Y635797D02*
X1324554Y635848D01*
G01X1324653Y635727D02*
X1324626Y635797D01*
G01X1329554Y635848D02*
X1329456Y635867D01*
G01X1329626Y635797D02*
X1329554Y635848D01*
G01X1329653Y635727D02*
X1329626Y635797D01*
G01X1334554Y635848D02*
X1334456Y635867D01*
G01X1334626Y635797D02*
X1334554Y635848D01*
G01X1334653Y635727D02*
X1334626Y635797D01*
G01X1339554Y635848D02*
X1339456Y635867D01*
G01X1339626Y635797D02*
X1339554Y635848D01*
G01X1339653Y635727D02*
X1339626Y635797D01*
G01X1339653Y636296D02*
G03X1339456Y636493I-197J0D01*
G01X1338196D02*
G03X1337999Y636296I0J-197D01*
G01X1324653D02*
G03X1324456Y636493I-197J0D01*
G01X1323196D02*
G03X1322999Y636296I0J-197D01*
G01X1329653D02*
G03X1329456Y636493I-197J0D01*
G01X1328196D02*
G03X1327999Y636296I0J-197D01*
G01X1334653D02*
G03X1334456Y636493I-197J0D01*
G01X1333196D02*
G03X1332999Y636296I0J-197D01*
G01X1320145Y639577D02*
G03X1320342Y639380I197J0D01*
G01X1321208D02*
G03X1321405Y639577I0J197D01*
G01X1324141Y642983D02*
X1323086Y646920D01*
G01X1339653Y635109D02*
Y636295D01*
G01X1339456Y635109D02*
Y636493D01*
G01X1338196Y635109D02*
Y636493D01*
G01X1337999Y636295D02*
Y635109D01*
G01X1334653D02*
Y636295D01*
G01X1334456Y635109D02*
Y636493D01*
G01X1333196Y635109D02*
Y636493D01*
G01X1332999Y636295D02*
Y635109D01*
G01X1329653D02*
Y636295D01*
G01X1329456Y635109D02*
Y636493D01*
G01X1328196Y635109D02*
Y636493D01*
G01X1327999Y636295D02*
Y635109D01*
G01X1324653D02*
Y636295D01*
G01X1324456Y635109D02*
Y636493D01*
G01X1323196Y635109D02*
Y636493D01*
G01X1322999Y636295D02*
Y635109D01*
G01X1322369Y633928D02*
Y629991D01*
G01X1321405Y639578D02*
Y640621D01*
G01X1321208Y639380D02*
Y640424D01*
G01X1321188Y635109D02*
Y631172D01*
G01X1320342Y640424D02*
Y639380D01*
G01X1320145Y640621D02*
Y639578D01*
G01X1321188Y635109D02*
X1322369Y633928D01*
G01X1321188Y631172D02*
X1322369Y629991D01*
G01X1323983Y643573D02*
X1400322D01*
G01X1402566Y642983D02*
X1324141D01*
G01X1321208Y640424D02*
X1321405D01*
G01X1320145D02*
X1320342D01*
G01Y640037D02*
X1321208D01*
G01X1320342Y639380D02*
X1321208D01*
G01X1324456Y636493D02*
X1323196D01*
G01X1329456D02*
X1328196D01*
G01X1334456D02*
X1333196D01*
G01X1339456D02*
X1338196D01*
G01X1324456Y635867D02*
X1323196D01*
G01X1329456D02*
X1328196D01*
G01X1334456D02*
X1333196D01*
G01X1339456D02*
X1338196D01*
G01X1397645Y635109D02*
X1321188D01*
G01X1398826Y633928D02*
X1322369D01*
G01X1338590Y686383D02*
X1339029Y685261D01*
G01X1328698Y686383D02*
X1329137Y685261D01*
G01X1337930D02*
X1337710Y685710D01*
G01X1334413Y685261D02*
X1334193Y685710D01*
G01X1328038Y685261D02*
X1327818Y685710D01*
G01X1324521Y685261D02*
X1324301Y685710D01*
G01X1338150Y686832D02*
X1338590Y686383D01*
G01X1337710Y685710D02*
X1337490Y685934D01*
G01X1334633Y686832D02*
X1335292Y686158D01*
G01X1334193Y685710D02*
X1333974Y685934D01*
G01X1328258Y686832D02*
X1328698Y686383D01*
G01X1327818Y685710D02*
X1327599Y685934D01*
G01X1324741Y686832D02*
X1325401Y686158D01*
G01X1324301Y685710D02*
X1324082Y685934D01*
G01X1339029Y685261D02*
Y679873D01*
G01X1337930D02*
Y685261D01*
G01X1335512D02*
Y679873D01*
G01X1334413D02*
Y685261D01*
G01X1331995Y685485D02*
Y679873D01*
G01Y687056D02*
Y686383D01*
G01X1330896Y679873D02*
Y687056D01*
G01X1329137Y685261D02*
Y679873D01*
G01X1328038D02*
Y685261D01*
G01X1325620D02*
Y679873D01*
G01X1324521D02*
Y685261D01*
G01X1322103Y685485D02*
Y679873D01*
G01Y687056D02*
Y686383D01*
G01X1321004Y679873D02*
Y687056D01*
G01X1337490Y685934D02*
X1337051Y686158D01*
G01X1333974Y685934D02*
X1333534Y686158D01*
G01X1327599Y685934D02*
X1327159Y686158D01*
G01X1324082Y685934D02*
X1323642Y686158D01*
G01X1337490Y687056D02*
X1338150Y686832D01*
G01X1333974Y687056D02*
X1334633Y686832D01*
G01X1327599Y687056D02*
X1328258Y686832D01*
G01X1324082Y687056D02*
X1324741Y686832D01*
G01X1335732Y685710D02*
X1335512Y685261D01*
G01X1325840Y685710D02*
X1325620Y685261D01*
G01X1336611Y687056D02*
X1337490D01*
G01X1333094D02*
X1333974D01*
G01X1330896D02*
X1331995D01*
G01X1326720D02*
X1327599D01*
G01X1323202D02*
X1324082D01*
G01X1321004D02*
X1322103D01*
G01X1335952Y685934D02*
X1335732Y685710D01*
G01X1335292Y686158D02*
X1335952Y686832D01*
G01X1332435Y685934D02*
X1331995Y685485D01*
G01Y686383D02*
X1332435Y686832D01*
G01X1326060Y685934D02*
X1325840Y685710D01*
G01X1323642Y686158D02*
X1323202D01*
G01X1327159D02*
X1326500D01*
G01X1333534D02*
X1333094D01*
G01X1337051D02*
X1336391D01*
G01X1322103Y679873D02*
X1321004D01*
G01X1325620D02*
X1324521D01*
G01X1329137D02*
X1328038D01*
G01X1331995D02*
X1330896D01*
G01X1335512D02*
X1334413D01*
G01X1339029D02*
X1337930D01*
G01X1325401Y686158D02*
X1326060Y686832D01*
G01X1322543Y685934D02*
X1322103Y685485D01*
G01Y686383D02*
X1322543Y686832D01*
G01X1336391Y686158D02*
X1335952Y685934D01*
G01X1326500Y686158D02*
X1326060Y685934D01*
G01X1335952Y686832D02*
X1336611Y687056D01*
G01X1333094Y686158D02*
X1332435Y685934D01*
G01Y686832D02*
X1333094Y687056D01*
G01X1326060Y686832D02*
X1326720Y687056D01*
G01X1323202Y686158D02*
X1322543Y685934D01*
G01Y686832D02*
X1323202Y687056D01*
G01X1338026Y701545D02*
X1337999Y701475D01*
G01X1338098Y701596D02*
X1338026Y701545D01*
G01X1338196Y701615D02*
X1338098Y701596D01*
G01X1333026Y701545D02*
X1332999Y701475D01*
G01X1333098Y701596D02*
X1333026Y701545D01*
G01X1333196Y701615D02*
X1333098Y701596D01*
G01X1328026Y701545D02*
X1327999Y701475D01*
G01X1328098Y701596D02*
X1328026Y701545D01*
G01X1328196Y701615D02*
X1328098Y701596D01*
G01X1323026Y701545D02*
X1322999Y701475D01*
G01X1323098Y701596D02*
X1323026Y701545D01*
G01X1323196Y701615D02*
X1323098Y701596D01*
G01X1321306Y705804D02*
X1321208Y705785D01*
G01X1321378Y705854D02*
X1321306Y705804D01*
G01X1321405Y705923D02*
X1321378Y705854D01*
G01X1320171D02*
X1320145Y705923D01*
G01X1320243Y705804D02*
X1320171Y705854D01*
G01X1320342Y705785D02*
X1320243Y705804D01*
G01X1324554Y701596D02*
X1324456Y701615D01*
G01X1324626Y701545D02*
X1324554Y701596D01*
G01X1324653Y701475D02*
X1324626Y701545D01*
G01X1329554Y701596D02*
X1329456Y701615D01*
G01X1329626Y701545D02*
X1329554Y701596D01*
G01X1329653Y701475D02*
X1329626Y701545D01*
G01X1334554Y701596D02*
X1334456Y701615D01*
G01X1334626Y701545D02*
X1334554Y701596D01*
G01X1334653Y701475D02*
X1334626Y701545D01*
G01X1339554Y701596D02*
X1339456Y701615D01*
G01X1339626Y701545D02*
X1339554Y701596D01*
G01X1339653Y701475D02*
X1339626Y701545D01*
G01X1339653Y702044D02*
G03X1339456Y702241I-197J0D01*
G01X1338196D02*
G03X1337999Y702044I0J-197D01*
G01X1324653D02*
G03X1324456Y702241I-197J0D01*
G01X1323196D02*
G03X1322999Y702044I0J-197D01*
G01X1329653D02*
G03X1329456Y702241I-197J0D01*
G01X1328196D02*
G03X1327999Y702044I0J-197D01*
G01X1334653D02*
G03X1334456Y702241I-197J0D01*
G01X1333196D02*
G03X1332999Y702044I0J-197D01*
G01X1320145Y705325D02*
G03X1320342Y705128I197J0D01*
G01X1321208D02*
G03X1321405Y705325I0J197D01*
G01X1324141Y708731D02*
X1323086Y712668D01*
G01X1321188Y700857D02*
X1322369Y699676D01*
G01X1321188Y696920D02*
X1322369Y695739D01*
G01X1339653Y700857D02*
Y702043D01*
G01X1339456Y700857D02*
Y702241D01*
G01X1338196Y700857D02*
Y702241D01*
G01X1337999Y702043D02*
Y700857D01*
G01X1334653D02*
Y702043D01*
G01X1334456Y700857D02*
Y702241D01*
G01X1333196Y700857D02*
Y702241D01*
G01X1332999Y702043D02*
Y700857D01*
G01X1329653D02*
Y702043D01*
G01X1329456Y700857D02*
Y702241D01*
G01X1328196Y700857D02*
Y702241D01*
G01X1327999Y702043D02*
Y700857D01*
G01X1324653D02*
Y702043D01*
G01X1324456Y700857D02*
Y702241D01*
G01X1323196Y700857D02*
Y702241D01*
G01X1322999Y702043D02*
Y700857D01*
G01X1322369Y699676D02*
Y695739D01*
G01X1321405Y705326D02*
Y706369D01*
G01X1321208Y705128D02*
Y706172D01*
G01X1321188Y700857D02*
Y696920D01*
G01X1320342Y706172D02*
Y705128D01*
G01X1320145Y706369D02*
Y705326D01*
G01X1323983Y709321D02*
X1400322D01*
G01X1402566Y708731D02*
X1324141D01*
G01X1321208Y706172D02*
X1321405D01*
G01X1320145D02*
X1320342D01*
G01Y705785D02*
X1321208D01*
G01X1320342Y705128D02*
X1321208D01*
G01X1324456Y702241D02*
X1323196D01*
G01X1329456D02*
X1328196D01*
G01X1334456D02*
X1333196D01*
G01X1339456D02*
X1338196D01*
G01X1324456Y701615D02*
X1323196D01*
G01X1329456D02*
X1328196D01*
G01X1334456D02*
X1333196D01*
G01X1339456D02*
X1338196D01*
G01X1397645Y700857D02*
X1321188D01*
G01X1398826Y699676D02*
X1322369D01*
G01X1339180Y731974D02*
X1339620Y730851D01*
G01X1338521D02*
X1338301Y731300D01*
G01X1335003Y730851D02*
X1334784Y731300D01*
G01X1338740Y732423D02*
X1339180Y731974D01*
G01X1338301Y731300D02*
X1338081Y731525D01*
G01X1335224Y732423D02*
X1335883Y731749D01*
G01X1334784Y731300D02*
X1334564Y731525D01*
G01X1328849Y732423D02*
X1329288Y731974D01*
G01D02*
X1329728Y730851D01*
G01X1328629D02*
X1328409Y731300D01*
G01X1325112Y730851D02*
X1324892Y731300D01*
G01X1328409D02*
X1328189Y731525D01*
G01X1325332Y732423D02*
X1325991Y731749D01*
G01X1324892Y731300D02*
X1324672Y731525D01*
G01X1338081D02*
X1337641Y731749D01*
G01X1334564Y731525D02*
X1334124Y731749D01*
G01X1328189Y731525D02*
X1327750Y731749D01*
G01X1324672Y731525D02*
X1324233Y731749D01*
G01X1338081Y732647D02*
X1338740Y732423D01*
G01X1334564Y732647D02*
X1335224Y732423D01*
G01X1328189Y732647D02*
X1328849Y732423D01*
G01X1324672Y732647D02*
X1325332Y732423D01*
G01X1339620Y730851D02*
Y725463D01*
G01X1338521D02*
Y730851D01*
G01X1336103D02*
Y725463D01*
G01X1335003D02*
Y730851D01*
G01X1332586Y731076D02*
Y725463D01*
G01Y732647D02*
Y731974D01*
G01X1331487Y725463D02*
Y732647D01*
G01X1329728Y730851D02*
Y725463D01*
G01X1328629D02*
Y730851D01*
G01X1326211D02*
Y725463D01*
G01X1325112D02*
Y730851D01*
G01X1322694Y731076D02*
Y725463D01*
G01Y732647D02*
Y731974D01*
G01X1321595Y725463D02*
Y732647D01*
G01X1319836Y728157D02*
Y728831D01*
G01X1319616Y732647D02*
Y733321D01*
G01X1337202Y732647D02*
X1338081D01*
G01X1333685D02*
X1334564D01*
G01X1331487D02*
X1332586D01*
G01X1327310D02*
X1328189D01*
G01X1323793D02*
X1324672D01*
G01X1321595D02*
X1322694D01*
G01X1324233Y731749D02*
X1323793D01*
G01X1327750D02*
X1327090D01*
G01X1334124D02*
X1333685D01*
G01X1337641D02*
X1336982D01*
G01X1322694Y725463D02*
X1321595D01*
G01X1326211D02*
X1325112D01*
G01X1329728D02*
X1328629D01*
G01X1332586D02*
X1331487D01*
G01X1336103D02*
X1335003D01*
G01X1339620D02*
X1338521D01*
G01X1336322Y731300D02*
X1336103Y730851D01*
G01X1326431Y731300D02*
X1326211Y730851D01*
G01X1336542Y731525D02*
X1336322Y731300D01*
G01X1335883Y731749D02*
X1336542Y732423D01*
G01X1333025Y731525D02*
X1332586Y731076D01*
G01Y731974D02*
X1333025Y732423D01*
G01X1326651Y731525D02*
X1326431Y731300D01*
G01X1325991Y731749D02*
X1326651Y732423D01*
G01X1323133Y731525D02*
X1322694Y731076D01*
G01Y731974D02*
X1323133Y732423D01*
G01X1336982Y731749D02*
X1336542Y731525D01*
G01X1327090Y731749D02*
X1326651Y731525D01*
G01X1336542Y732423D02*
X1337202Y732647D01*
G01X1333685Y731749D02*
X1333025Y731525D01*
G01Y732423D02*
X1333685Y732647D01*
G01X1326651Y732423D02*
X1327310Y732647D01*
G01X1323793Y731749D02*
X1323133Y731525D01*
G01Y732423D02*
X1323793Y732647D01*
G01X1347819Y54332D02*
X1356481D01*
G01X1347819Y46536D02*
X1356481D01*
G01X1351428Y62614D02*
X1352150Y63588D01*
G01X1351428Y61639D02*
Y62614D01*
G01X1352150Y60665D02*
X1351428Y61639D01*
G01X1353594Y59691D02*
X1352150Y60665D01*
G01X1351428Y78204D02*
X1352150Y79179D01*
G01X1350706D02*
X1351428Y78204D01*
G01X1349985Y79666D02*
X1350706Y79179D01*
G01X1349263Y79666D02*
X1349985D01*
G01X1348541Y79179D02*
X1349263Y79666D01*
G01X1347819Y78204D02*
X1348541Y79179D01*
G01X1347819Y77230D02*
Y78204D01*
G01X1348541Y76256D02*
X1347819Y77230D01*
G01X1355759Y76256D02*
X1355037Y75769D01*
G01X1356481Y77230D02*
X1355759Y76256D01*
G01X1356481Y78204D02*
Y77230D01*
G01X1355759Y79179D02*
X1356481Y78204D01*
G01X1355759Y69435D02*
X1356481Y69922D01*
G01Y69435D02*
X1355759D01*
G01X1356481Y69922D02*
Y69435D01*
G01X1354315Y80153D02*
X1355759Y79179D01*
G01X1353594Y80153D02*
X1354315D01*
G01X1352150Y79179D02*
X1353594Y80153D01*
G01X1350706Y63588D02*
X1351428Y62614D01*
G01X1349985Y64076D02*
X1350706Y63588D01*
G01X1349263Y64076D02*
X1349985D01*
G01X1348541Y63588D02*
X1349263Y64076D01*
G01X1347819Y62614D02*
X1348541Y63588D01*
G01X1347819Y61639D02*
Y62614D01*
G01X1348541Y60665D02*
X1347819Y61639D01*
G01X1349263Y60178D02*
X1348541Y60665D01*
G01X1349985Y60178D02*
X1349263D01*
G01X1350706Y60665D02*
X1349985Y60178D01*
G01X1351428Y61639D02*
X1350706Y60665D01*
G01X1356481Y62614D02*
Y61639D01*
G01X1355759Y63588D02*
X1356481Y62614D01*
G01X1355037Y64076D02*
X1355759Y63588D01*
G01X1354315Y64563D02*
X1355037Y64076D01*
G01X1353594Y64563D02*
X1354315D01*
G01X1352150Y63588D02*
X1353594Y64563D01*
G01X1354315Y59691D02*
X1353594D01*
G01X1355759Y60665D02*
X1354315Y59691D01*
G01X1356481Y61639D02*
X1355759Y60665D01*
G01X1351428Y77230D02*
Y78204D01*
G01X1358646Y184126D02*
Y93741D01*
G01X1355759Y84051D02*
X1355037Y83564D01*
G01X1356481Y85025D02*
X1355759Y84051D01*
G01X1356481Y86000D02*
Y85025D01*
G01X1355759Y86974D02*
X1356481Y86000D01*
G01X1355037Y87462D02*
X1355759Y86974D01*
G01X1353594Y87949D02*
X1355037Y87462D01*
G01X1352150D02*
X1353594Y87949D01*
G01X1351428Y86974D02*
X1352150Y87462D01*
G01X1350706Y86000D02*
X1351428Y86974D01*
G01X1350706Y85025D02*
Y86000D01*
G01X1351428Y84051D02*
X1350706Y85025D01*
G01X1347819Y84538D02*
X1351428Y84051D01*
G01X1347819Y87462D02*
Y84538D01*
G01X1364639Y186514D02*
X1364551Y186240D01*
G01X1364724Y186762D02*
X1364639Y186514D01*
G01X1364806Y186986D02*
X1364724Y186762D01*
G01X1364886Y187186D02*
X1364806Y186986D01*
G01X1364964Y187365D02*
X1364886Y187186D01*
G01X1365039Y187524D02*
X1364964Y187365D01*
G01X1367118Y186213D02*
G03X1364551Y190038I-1287J1910D01*
G01X1358646Y188063D02*
G03X1362583Y184126I3937J0D01*
G01X1358646Y188063D02*
G03X1362583Y184126I3937J0D01*
G01X1364551Y186213D02*
Y203418D01*
G01X1358646Y203615D02*
Y188063D01*
G01Y203615D02*
Y188063D01*
G01X1368292Y188260D02*
X1364551Y190819D01*
G01Y192197D02*
X1369945D01*
G01X1368292Y190819D02*
X1364551D01*
G01X1368292Y186213D02*
X1364551D01*
G01X1362583Y184126D02*
X1422229D01*
G01X1362583D02*
X1422229D01*
G01X1358646Y203615D02*
G03X1354709Y207552I-3937J0D01*
G01X1358646Y203615D02*
G03X1354709Y207552I-3937J0D01*
G01X1426166Y203418D02*
X1364551D01*
G01X1369945Y200859D02*
X1364551D01*
G01X1356973Y239048D02*
Y245903D01*
G01X1355142Y253693D02*
Y239048D01*
G01X1343853D02*
Y240606D01*
G01X1355142Y239048D02*
X1356973D01*
G01Y247773D02*
Y253693D01*
G01X1343548Y250266D02*
X1343242Y251512D01*
G01X1346294Y244345D02*
X1346904Y243410D01*
G01Y249643D02*
X1346294Y248708D01*
G01X1352701Y246526D02*
X1346904Y249643D01*
G01X1346294Y248708D02*
X1350565Y246526D01*
G01D02*
X1346294Y244345D01*
G01X1346904Y243410D02*
X1352701Y246526D01*
G01X1356973Y253693D02*
X1355142D01*
G01X1365516Y247773D02*
X1356973D01*
G01Y245903D02*
X1365516D01*
G01X1347120Y304739D02*
X1347731Y303804D01*
G01X1357800Y299441D02*
Y306297D01*
G01X1355969Y314087D02*
Y299441D01*
G01X1344679D02*
Y301000D01*
G01X1353528Y306920D02*
X1347731Y310036D01*
G01X1347120Y309102D02*
X1351392Y306920D01*
G01X1357800Y306297D02*
X1366343D01*
G01X1355969Y299441D02*
X1357800D01*
G01X1351392Y306920D02*
X1347120Y304739D01*
G01X1347731Y303804D02*
X1353528Y306920D01*
G01X1344374Y310660D02*
X1344069Y311906D01*
G01D02*
X1342849Y313152D01*
G01X1357800Y308167D02*
Y314087D01*
G01X1347731Y310036D02*
X1347120Y309102D01*
G01X1357800Y314087D02*
X1355969D01*
G01X1342849Y310660D02*
X1344374D01*
G01X1366343Y308167D02*
X1357800D01*
G01X1359593Y352959D02*
X1359106Y353680D01*
G01X1360567Y352237D02*
X1359593Y352959D01*
G01X1361542D02*
X1360567Y352237D01*
G01X1362029Y353680D02*
X1361542Y352959D01*
G01Y360176D02*
X1362029Y359455D01*
G01X1360567Y360898D02*
X1361542Y360176D01*
G01X1359593D02*
X1360567Y360898D01*
G01X1359106Y359455D02*
X1359593Y360176D01*
G01X1358618Y358011D02*
X1359106Y359455D01*
G01X1358618Y355124D02*
Y358011D01*
G01X1359106Y353680D02*
X1358618Y355124D01*
G01X1362516D02*
X1362029Y353680D01*
G01Y356568D02*
X1362516Y355124D01*
G01X1360567Y357289D02*
X1362029Y356568D01*
G01X1359106D02*
X1360567Y357289D01*
G01X1358618Y355124D02*
X1359106Y356568D01*
G01X1355460Y572038D02*
G03X1359397Y568101I3937J0D01*
G01X1355460Y572038D02*
G03X1359397Y568101I3937J0D01*
G01X1355460Y587589D02*
Y572038D01*
G01Y587589D02*
Y572038D01*
G01X1359397Y568101D02*
X1419042D01*
G01X1359397D02*
X1419042D01*
G01X1355460Y587589D02*
G03X1351523Y591526I-3937J0D01*
G01X1355460Y587589D02*
G03X1351523Y591526I-3937J0D01*
G01X1363026Y635797D02*
X1362999Y635727D01*
G01X1363098Y635848D02*
X1363026Y635797D01*
G01X1363196Y635867D02*
X1363098Y635848D01*
G01X1358026Y635797D02*
X1357999Y635727D01*
G01X1358098Y635848D02*
X1358026Y635797D01*
G01X1358196Y635867D02*
X1358098Y635848D01*
G01X1353026Y635797D02*
X1352999Y635727D01*
G01X1353098Y635848D02*
X1353026Y635797D01*
G01X1353196Y635867D02*
X1353098Y635848D01*
G01X1348026Y635797D02*
X1347999Y635727D01*
G01X1348098Y635848D02*
X1348026Y635797D01*
G01X1348196Y635867D02*
X1348098Y635848D01*
G01X1343026Y635797D02*
X1342999Y635727D01*
G01X1343098Y635848D02*
X1343026Y635797D01*
G01X1343196Y635867D02*
X1343098Y635848D01*
G01X1344554D02*
X1344456Y635867D01*
G01X1344626Y635797D02*
X1344554Y635848D01*
G01X1344653Y635727D02*
X1344626Y635797D01*
G01X1349554Y635848D02*
X1349456Y635867D01*
G01X1349626Y635797D02*
X1349554Y635848D01*
G01X1349653Y635727D02*
X1349626Y635797D01*
G01X1354554Y635848D02*
X1354456Y635867D01*
G01X1354626Y635797D02*
X1354554Y635848D01*
G01X1354653Y635727D02*
X1354626Y635797D01*
G01X1359554Y635848D02*
X1359456Y635867D01*
G01X1359626Y635797D02*
X1359554Y635848D01*
G01X1359653Y635727D02*
X1359626Y635797D01*
G01X1364554Y635848D02*
X1364456Y635867D01*
G01X1364626Y635797D02*
X1364554Y635848D01*
G01X1364653Y635727D02*
X1364626Y635797D01*
G01X1344653Y636296D02*
G03X1344456Y636493I-197J0D01*
G01X1343196D02*
G03X1342999Y636296I0J-197D01*
G01X1349653D02*
G03X1349456Y636493I-197J0D01*
G01X1348196D02*
G03X1347999Y636296I0J-197D01*
G01X1354653D02*
G03X1354456Y636493I-197J0D01*
G01X1353196D02*
G03X1352999Y636296I0J-197D01*
G01X1359653D02*
G03X1359456Y636493I-197J0D01*
G01X1358196D02*
G03X1357999Y636296I0J-197D01*
G01X1364653D02*
G03X1364456Y636493I-197J0D01*
G01X1363196D02*
G03X1362999Y636296I0J-197D01*
G01X1364653Y635109D02*
Y636295D01*
G01X1364456Y635109D02*
Y636493D01*
G01X1363196Y635109D02*
Y636493D01*
G01X1362999Y636295D02*
Y635109D01*
G01X1359653D02*
Y636295D01*
G01X1359456Y635109D02*
Y636493D01*
G01X1358196Y635109D02*
Y636493D01*
G01X1357999Y636295D02*
Y635109D01*
G01X1354653D02*
Y636295D01*
G01X1354456Y635109D02*
Y636493D01*
G01X1353196Y635109D02*
Y636493D01*
G01X1352999Y636295D02*
Y635109D01*
G01X1349653D02*
Y636295D01*
G01X1349456Y635109D02*
Y636493D01*
G01X1348196Y635109D02*
Y636493D01*
G01X1347999Y636295D02*
Y635109D01*
G01X1344653D02*
Y636295D01*
G01X1344456Y635109D02*
Y636493D01*
G01X1343196Y635109D02*
Y636493D01*
G01X1342999Y636295D02*
Y635109D01*
G01X1344456Y636493D02*
X1343196D01*
G01X1349456D02*
X1348196D01*
G01X1354456D02*
X1353196D01*
G01X1359456D02*
X1358196D01*
G01X1364456D02*
X1363196D01*
G01X1344456Y635867D02*
X1343196D01*
G01X1349456D02*
X1348196D01*
G01X1354456D02*
X1353196D01*
G01X1359456D02*
X1358196D01*
G01X1364456D02*
X1363196D01*
G01X1363026Y701545D02*
X1362999Y701475D01*
G01X1363098Y701596D02*
X1363026Y701545D01*
G01X1363196Y701615D02*
X1363098Y701596D01*
G01X1358026Y701545D02*
X1357999Y701475D01*
G01X1358098Y701596D02*
X1358026Y701545D01*
G01X1358196Y701615D02*
X1358098Y701596D01*
G01X1353026Y701545D02*
X1352999Y701475D01*
G01X1353098Y701596D02*
X1353026Y701545D01*
G01X1353196Y701615D02*
X1353098Y701596D01*
G01X1348026Y701545D02*
X1347999Y701475D01*
G01X1348098Y701596D02*
X1348026Y701545D01*
G01X1348196Y701615D02*
X1348098Y701596D01*
G01X1343026Y701545D02*
X1342999Y701475D01*
G01X1343098Y701596D02*
X1343026Y701545D01*
G01X1343196Y701615D02*
X1343098Y701596D01*
G01X1344554D02*
X1344456Y701615D01*
G01X1344626Y701545D02*
X1344554Y701596D01*
G01X1344653Y701475D02*
X1344626Y701545D01*
G01X1349554Y701596D02*
X1349456Y701615D01*
G01X1349626Y701545D02*
X1349554Y701596D01*
G01X1349653Y701475D02*
X1349626Y701545D01*
G01X1354554Y701596D02*
X1354456Y701615D01*
G01X1354626Y701545D02*
X1354554Y701596D01*
G01X1354653Y701475D02*
X1354626Y701545D01*
G01X1359554Y701596D02*
X1359456Y701615D01*
G01X1359626Y701545D02*
X1359554Y701596D01*
G01X1359653Y701475D02*
X1359626Y701545D01*
G01X1364554Y701596D02*
X1364456Y701615D01*
G01X1364626Y701545D02*
X1364554Y701596D01*
G01X1364653Y701475D02*
X1364626Y701545D01*
G01X1344653Y702044D02*
G03X1344456Y702241I-197J0D01*
G01X1343196D02*
G03X1342999Y702044I0J-197D01*
G01X1349653D02*
G03X1349456Y702241I-197J0D01*
G01X1348196D02*
G03X1347999Y702044I0J-197D01*
G01X1354653D02*
G03X1354456Y702241I-197J0D01*
G01X1353196D02*
G03X1352999Y702044I0J-197D01*
G01X1359653D02*
G03X1359456Y702241I-197J0D01*
G01X1358196D02*
G03X1357999Y702044I0J-197D01*
G01X1364653D02*
G03X1364456Y702241I-197J0D01*
G01X1363196D02*
G03X1362999Y702044I0J-197D01*
G01X1364653Y700857D02*
Y702043D01*
G01X1364456Y700857D02*
Y702241D01*
G01X1363196Y700857D02*
Y702241D01*
G01X1362999Y702043D02*
Y700857D01*
G01X1359653D02*
Y702043D01*
G01X1359456Y700857D02*
Y702241D01*
G01X1358196Y700857D02*
Y702241D01*
G01X1357999Y702043D02*
Y700857D01*
G01X1354653D02*
Y702043D01*
G01X1354456Y700857D02*
Y702241D01*
G01X1353196Y700857D02*
Y702241D01*
G01X1352999Y702043D02*
Y700857D01*
G01X1349653D02*
Y702043D01*
G01X1349456Y700857D02*
Y702241D01*
G01X1348196Y700857D02*
Y702241D01*
G01X1347999Y702043D02*
Y700857D01*
G01X1344653D02*
Y702043D01*
G01X1344456Y700857D02*
Y702241D01*
G01X1343196Y700857D02*
Y702241D01*
G01X1342999Y702043D02*
Y700857D01*
G01X1344456Y702241D02*
X1343196D01*
G01X1349456D02*
X1348196D01*
G01X1354456D02*
X1353196D01*
G01X1359456D02*
X1358196D01*
G01X1364456D02*
X1363196D01*
G01X1344456Y701615D02*
X1343196D01*
G01X1349456D02*
X1348196D01*
G01X1354456D02*
X1353196D01*
G01X1359456D02*
X1358196D01*
G01X1364456D02*
X1363196D01*
G01X1366713Y187330D02*
X1366478Y187788D01*
G01X1366923Y186805D02*
X1366713Y187330D01*
G01X1367118Y186213D02*
X1366923Y186805D01*
G01X1365113Y187664D02*
X1365039Y187524D01*
G01X1365184Y187788D02*
X1365113Y187664D01*
G01X1366478Y187788D02*
G03X1365184I-647J335D01*
G01X1386846Y190229D02*
X1387091Y190819D01*
G01X1386894Y189048D02*
Y190819D01*
G01X1385388Y200859D02*
Y190819D01*
G01X1375280D02*
X1375035Y190229D01*
G01X1384335Y200859D02*
Y193575D01*
G01X1383941Y188260D02*
Y186213D01*
G01X1383744Y201449D02*
Y193331D01*
G01X1383351Y190229D02*
Y201449D01*
G01X1382760Y190819D02*
Y200859D01*
G01X1381707Y190819D02*
Y200859D01*
G01X1380792Y188260D02*
Y186213D01*
G01X1380201Y189048D02*
Y190819D01*
G01X1379020Y189048D02*
Y203418D01*
G01X1378902Y197985D02*
Y193890D01*
G01X1376382D02*
Y197985D01*
G01X1376264Y203418D02*
Y189048D01*
G01X1375083Y190819D02*
Y189048D01*
G01X1372524Y200859D02*
Y193575D01*
G01X1371933Y201449D02*
Y193331D01*
G01X1370851Y200859D02*
Y190819D01*
G01X1370063Y188260D02*
Y203418D01*
G01X1369945Y188260D02*
Y203418D01*
G01X1368292Y186213D02*
Y203418D01*
G01X1367504Y200859D02*
Y190819D01*
G01X1365339D02*
Y200859D01*
G01X1387091Y190819D02*
X1384335Y193575D01*
G01X1383744Y193331D02*
X1386846Y190229D01*
G01X1382760Y190819D02*
X1383351Y190229D01*
G01X1375280Y190819D02*
X1372524Y193575D01*
G01X1371933Y193331D02*
X1375035Y190229D01*
G01X1384335Y193575D02*
X1383744Y193331D01*
G01X1372524Y193575D02*
X1371933Y193331D01*
G01X1378902Y193890D02*
X1376382D01*
G01X1370063Y193006D02*
X1368292D01*
G01Y192430D02*
X1370063D01*
G01X1368292Y191728D02*
X1370063D01*
G01Y190819D02*
X1420654D01*
G01X1370063Y190769D02*
X1368292D01*
G01X1386846Y190229D02*
X1395162D01*
G01X1375035D02*
X1383351D01*
G01X1420654Y189048D02*
X1370063D01*
G01X1368292Y188260D02*
X1422426D01*
G01X1366478Y187788D02*
X1365184D01*
G01X1383941Y186213D02*
X1380792D01*
G01X1386894Y200859D02*
Y203418D01*
G01X1377740Y196030D02*
X1377753Y196068D01*
G01X1377679D02*
X1377667Y196030D01*
G01X1380201Y200859D02*
Y203418D01*
G01X1378311Y195268D02*
Y196607D01*
G01X1378122Y195578D02*
Y196168D01*
G01X1378048Y196105D02*
Y195917D01*
G01Y195841D02*
Y195578D01*
G01X1377740Y195992D02*
Y196030D01*
G01X1377667D02*
Y195980D01*
G01X1377568D02*
Y196080D01*
G01X1377494Y195578D02*
Y196068D01*
G01X1377421Y196168D02*
Y195578D01*
G01X1376973Y196607D02*
Y195268D01*
G01X1375083Y203418D02*
Y200859D01*
G01X1367111D02*
Y203418D01*
G01X1377753Y195955D02*
X1377740Y195992D01*
G01X1377667Y195980D02*
X1377679Y195942D01*
G01X1382760Y200859D02*
X1383351Y201449D01*
G01X1376382Y194678D02*
X1376973Y195268D01*
G01X1378902Y197197D02*
X1378311Y196607D01*
G01X1377753Y196068D02*
X1377777Y196093D01*
G01X1377716Y196118D02*
X1377679Y196068D01*
G01X1377765Y196156D02*
X1377716Y196118D01*
G01X1377679Y195942D02*
X1377716Y195892D01*
G01X1377568Y196080D02*
X1377494Y196168D01*
G01Y196068D02*
X1377568Y195980D01*
G01X1377777Y195930D02*
X1377753Y195955D01*
G01X1384335Y200859D02*
X1383744Y201449D01*
G01X1376973Y196607D02*
X1376382Y197197D01*
G01X1378902Y194678D02*
X1378311Y195268D01*
G01X1371933Y201449D02*
X1372524Y200859D01*
G01X1377716Y195892D02*
X1377765Y195854D01*
G01X1377777Y196093D02*
X1377814Y196105D01*
G01Y195917D02*
X1377777Y195930D01*
G01X1377765Y195854D02*
X1377827Y195841D01*
G01X1383351Y201449D02*
X1371933D01*
G01X1395162D02*
X1383744D01*
G01X1370063Y201371D02*
X1368292D01*
G01X1370063Y200859D02*
X1420654D01*
G01X1370063Y200386D02*
X1368292D01*
G01Y199599D02*
X1370063D01*
G01Y198333D02*
X1368292D01*
G01X1376382Y197985D02*
X1378902D01*
G01X1376382Y197709D02*
X1378902D01*
G01X1368292Y197549D02*
X1370063D01*
G01X1378902Y197287D02*
X1376382D01*
G01X1368292Y197278D02*
X1370063D01*
G01X1378902Y197197D02*
X1376382D01*
G01X1378311Y196607D02*
X1376973D01*
G01X1370063Y196494D02*
X1368292D01*
G01X1377494Y196168D02*
X1377421D01*
G01X1378122D02*
X1377827D01*
G01X1377814Y196105D02*
X1378048D01*
G01X1368292Y195977D02*
X1370063D01*
G01X1378048Y195917D02*
X1377814D01*
G01X1377827Y195841D02*
X1378048D01*
G01X1377421Y195578D02*
X1377494D01*
G01X1378048D02*
X1378122D01*
G01X1376973Y195268D02*
X1378311D01*
G01X1376382Y195189D02*
X1378902D01*
G01X1370063D02*
X1368292D01*
G01X1378902Y194768D02*
X1376382D01*
G01X1378902Y194678D02*
X1376382D01*
G01X1368292Y194599D02*
X1370063D01*
G01X1377827Y196168D02*
X1377765Y196156D01*
G01X1367347Y239048D02*
Y253693D01*
G01X1365516Y245903D02*
Y239048D01*
G01D02*
X1367347D01*
G01X1365516Y253693D02*
Y247773D01*
G01X1367347Y253693D02*
X1365516D01*
G01X1376953Y273492D02*
G03X1378922Y275461I0J1969D01*
G01D02*
Y289240D01*
G01D02*
G03X1376953Y291209I-1969J0D01*
G01X1368174Y299441D02*
Y314087D01*
G01X1366343Y306297D02*
Y299441D01*
G01D02*
X1368174D01*
G01X1366343Y314087D02*
Y308167D01*
G01X1368174Y314087D02*
X1366343D01*
G01X1382004Y352237D02*
X1385902D01*
G01X1382492Y354402D02*
X1382004Y352237D01*
G01X1375671Y352959D02*
X1376158Y352237D01*
G01X1375671D02*
Y352959D01*
G01X1376158Y352237D02*
X1375671D01*
G01X1368363Y360898D02*
Y352237D01*
G01X1383466Y355846D02*
X1382492Y354402D01*
G01X1385415Y357289D02*
X1383466Y355846D01*
G01X1385902Y358011D02*
X1385415Y357289D01*
G01X1385902Y359455D02*
Y358011D01*
G01X1385415Y360176D02*
X1385902Y359455D01*
G01X1384440Y360898D02*
X1385415Y360176D01*
G01X1383466Y360898D02*
X1384440D01*
G01X1382492Y360176D02*
X1383466Y360898D01*
G01X1382004Y359455D02*
X1382492Y360176D01*
G01X1383026Y635797D02*
X1382999Y635727D01*
G01X1383098Y635848D02*
X1383026Y635797D01*
G01X1383196Y635867D02*
X1383098Y635848D01*
G01X1378026Y635797D02*
X1377999Y635727D01*
G01X1378098Y635848D02*
X1378026Y635797D01*
G01X1378196Y635867D02*
X1378098Y635848D01*
G01X1373026Y635797D02*
X1372999Y635727D01*
G01X1373098Y635848D02*
X1373026Y635797D01*
G01X1373196Y635867D02*
X1373098Y635848D01*
G01X1368026Y635797D02*
X1367999Y635727D01*
G01X1368098Y635848D02*
X1368026Y635797D01*
G01X1368196Y635867D02*
X1368098Y635848D01*
G01X1369554D02*
X1369456Y635867D01*
G01X1369626Y635797D02*
X1369554Y635848D01*
G01X1369653Y635727D02*
X1369626Y635797D01*
G01X1374554Y635848D02*
X1374456Y635867D01*
G01X1374626Y635797D02*
X1374554Y635848D01*
G01X1374653Y635727D02*
X1374626Y635797D01*
G01X1379554Y635848D02*
X1379456Y635867D01*
G01X1379626Y635797D02*
X1379554Y635848D01*
G01X1379653Y635727D02*
X1379626Y635797D01*
G01X1384554Y635848D02*
X1384456Y635867D01*
G01X1384626Y635797D02*
X1384554Y635848D01*
G01X1384653Y635727D02*
X1384626Y635797D01*
G01X1379653Y636296D02*
G03X1379456Y636493I-197J0D01*
G01X1378196D02*
G03X1377999Y636296I0J-197D01*
G01X1369653D02*
G03X1369456Y636493I-197J0D01*
G01X1368196D02*
G03X1367999Y636296I0J-197D01*
G01X1374653D02*
G03X1374456Y636493I-197J0D01*
G01X1373196D02*
G03X1372999Y636296I0J-197D01*
G01X1384653D02*
G03X1384456Y636493I-197J0D01*
G01X1383196D02*
G03X1382999Y636296I0J-197D01*
G01X1384653Y635109D02*
Y636295D01*
G01X1384456Y635109D02*
Y636493D01*
G01X1383196Y635109D02*
Y636493D01*
G01X1382999Y636295D02*
Y635109D01*
G01X1379653D02*
Y636295D01*
G01X1379456Y635109D02*
Y636493D01*
G01X1378196Y635109D02*
Y636493D01*
G01X1377999Y636295D02*
Y635109D01*
G01X1374653D02*
Y636295D01*
G01X1374456Y635109D02*
Y636493D01*
G01X1373196Y635109D02*
Y636493D01*
G01X1372999Y636295D02*
Y635109D01*
G01X1369653D02*
Y636295D01*
G01X1369456Y635109D02*
Y636493D01*
G01X1368196Y635109D02*
Y636493D01*
G01X1367999Y636295D02*
Y635109D01*
G01X1369456Y636493D02*
X1368196D01*
G01X1374456D02*
X1373196D01*
G01X1379456D02*
X1378196D01*
G01X1384456D02*
X1383196D01*
G01X1369456Y635867D02*
X1368196D01*
G01X1374456D02*
X1373196D01*
G01X1379456D02*
X1378196D01*
G01X1384456D02*
X1383196D01*
G01X1373767Y657467D02*
G03X1375735Y659435I0J1968D01*
G01D02*
Y673215D01*
G01D02*
G03X1373767Y675183I-1968J0D01*
G01X1383026Y701545D02*
X1382999Y701475D01*
G01X1383098Y701596D02*
X1383026Y701545D01*
G01X1383196Y701615D02*
X1383098Y701596D01*
G01X1378026Y701545D02*
X1377999Y701475D01*
G01X1378098Y701596D02*
X1378026Y701545D01*
G01X1378196Y701615D02*
X1378098Y701596D01*
G01X1373026Y701545D02*
X1372999Y701475D01*
G01X1373098Y701596D02*
X1373026Y701545D01*
G01X1373196Y701615D02*
X1373098Y701596D01*
G01X1368026Y701545D02*
X1367999Y701475D01*
G01X1368098Y701596D02*
X1368026Y701545D01*
G01X1368196Y701615D02*
X1368098Y701596D01*
G01X1369554D02*
X1369456Y701615D01*
G01X1369626Y701545D02*
X1369554Y701596D01*
G01X1369653Y701475D02*
X1369626Y701545D01*
G01X1374554Y701596D02*
X1374456Y701615D01*
G01X1374626Y701545D02*
X1374554Y701596D01*
G01X1374653Y701475D02*
X1374626Y701545D01*
G01X1379554Y701596D02*
X1379456Y701615D01*
G01X1379626Y701545D02*
X1379554Y701596D01*
G01X1379653Y701475D02*
X1379626Y701545D01*
G01X1384554Y701596D02*
X1384456Y701615D01*
G01X1384626Y701545D02*
X1384554Y701596D01*
G01X1384653Y701475D02*
X1384626Y701545D01*
G01X1379653Y702044D02*
G03X1379456Y702241I-197J0D01*
G01X1378196D02*
G03X1377999Y702044I0J-197D01*
G01X1369653D02*
G03X1369456Y702241I-197J0D01*
G01X1368196D02*
G03X1367999Y702044I0J-197D01*
G01X1374653D02*
G03X1374456Y702241I-197J0D01*
G01X1373196D02*
G03X1372999Y702044I0J-197D01*
G01X1384653D02*
G03X1384456Y702241I-197J0D01*
G01X1383196D02*
G03X1382999Y702044I0J-197D01*
G01X1384653Y700857D02*
Y702043D01*
G01X1384456Y700857D02*
Y702241D01*
G01X1383196Y700857D02*
Y702241D01*
G01X1382999Y702043D02*
Y700857D01*
G01X1379653D02*
Y702043D01*
G01X1379456Y700857D02*
Y702241D01*
G01X1378196Y700857D02*
Y702241D01*
G01X1377999Y702043D02*
Y700857D01*
G01X1374653D02*
Y702043D01*
G01X1374456Y700857D02*
Y702241D01*
G01X1373196Y700857D02*
Y702241D01*
G01X1372999Y702043D02*
Y700857D01*
G01X1369653D02*
Y702043D01*
G01X1369456Y700857D02*
Y702241D01*
G01X1368196Y700857D02*
Y702241D01*
G01X1367999Y702043D02*
Y700857D01*
G01X1369456Y702241D02*
X1368196D01*
G01X1374456D02*
X1373196D01*
G01X1379456D02*
X1378196D01*
G01X1384456D02*
X1383196D01*
G01X1369456Y701615D02*
X1368196D01*
G01X1374456D02*
X1373196D01*
G01X1379456D02*
X1378196D01*
G01X1384456D02*
X1383196D01*
G01X1409926Y188260D02*
Y186213D01*
G01X1409010Y200859D02*
Y190819D01*
G01X1407957Y200859D02*
Y190819D01*
G01X1407366Y201449D02*
Y190229D01*
G01X1406973D02*
Y201449D01*
G01X1406776Y188260D02*
Y186213D01*
G01X1406382Y190819D02*
Y200859D01*
G01X1405329Y190819D02*
Y200859D01*
G01X1403823Y189048D02*
Y190819D01*
G01X1402642Y189048D02*
Y203418D01*
G01X1402524Y197985D02*
Y193890D01*
G01X1400004D02*
Y197985D01*
G01X1399886Y189048D02*
Y203418D01*
G01X1398705Y189048D02*
Y190819D01*
G01X1397199D02*
Y200859D01*
G01X1396146D02*
Y190819D01*
G01X1395555Y201449D02*
Y190229D01*
G01X1395162D02*
Y201449D01*
G01X1394571Y200859D02*
Y190819D01*
G01X1393518Y200859D02*
Y190819D01*
G01X1392012Y189048D02*
Y190819D01*
G01X1390831Y203418D02*
Y189048D01*
G01X1390713Y197985D02*
Y193890D01*
G01X1388193Y197985D02*
Y193890D01*
G01X1388075Y189048D02*
Y203418D01*
G01X1407366Y190229D02*
X1407957Y190819D01*
G01X1395555Y190229D02*
X1396146Y190819D01*
G01X1406382D02*
X1406973Y190229D01*
G01X1394571Y190819D02*
X1395162Y190229D01*
G01X1390713Y194166D02*
X1388193D01*
G01X1390713Y193890D02*
X1388193D01*
G01X1402524D02*
X1400004D01*
G01X1407366Y190229D02*
X1415682D01*
G01X1395555D02*
X1406973D01*
G01X1409926Y186213D02*
X1406776D01*
G01X1403823Y203418D02*
Y200859D01*
G01X1401933Y195268D02*
Y196607D01*
G01X1400595D02*
Y195268D01*
G01X1400477Y208142D02*
Y203418D01*
G01X1398705D02*
Y200859D01*
G01X1392012D02*
Y203418D01*
G01X1390240Y208142D02*
Y203418D01*
G01X1390122Y195268D02*
Y196607D01*
G01X1388784D02*
Y195268D01*
G01X1406382Y200859D02*
X1406973Y201449D01*
G01X1401933Y196607D02*
X1402524Y197197D01*
G01X1400595Y195268D02*
X1400004Y194678D01*
G01X1394571Y200859D02*
X1395162Y201449D01*
G01X1388784Y195268D02*
X1388193Y194678D01*
G01X1390713Y197197D02*
X1390122Y196607D01*
G01X1407366Y201449D02*
X1407957Y200859D01*
G01X1400595Y196607D02*
X1400004Y197197D01*
G01X1402524Y194678D02*
X1401933Y195268D01*
G01X1395555Y201449D02*
X1396146Y200859D01*
G01X1388193Y197197D02*
X1388784Y196607D01*
G01X1390713Y194678D02*
X1390122Y195268D01*
G01X1400477Y208142D02*
X1390240D01*
G01X1400477Y205130D02*
X1390240D01*
G01X1406973Y201449D02*
X1395555D01*
G01X1418784D02*
X1407366D01*
G01X1400004Y197985D02*
X1402524D01*
G01X1388193D02*
X1390713D01*
G01X1400004Y197709D02*
X1402524D01*
G01Y197287D02*
X1400004D01*
G01X1390713Y197197D02*
X1388193D01*
G01X1402524D02*
X1400004D01*
G01X1390713Y197108D02*
X1388193D01*
G01X1390713Y196686D02*
X1388193D01*
G01X1390122Y196607D02*
X1388784D01*
G01X1401933D02*
X1400595D01*
G01Y195268D02*
X1401933D01*
G01X1388784D02*
X1390122D01*
G01X1400004Y195189D02*
X1402524D01*
G01Y194768D02*
X1400004D01*
G01X1390713Y194678D02*
X1388193D01*
G01X1402524D02*
X1400004D01*
G01X1390713Y194588D02*
X1388193D01*
G01X1414355Y350071D02*
X1399977D01*
G01X1392723Y352959D02*
X1391748Y352237D01*
G01X1393210Y353680D02*
X1392723Y352959D01*
G01X1390774D02*
X1390287Y353680D01*
G01X1391748Y352237D02*
X1390774Y352959D01*
G01X1393697Y355124D02*
X1393210Y353680D01*
G01X1393697Y358011D02*
Y355124D01*
G01X1393210Y359455D02*
X1393697Y358011D01*
G01X1392723Y360176D02*
X1393210Y359455D01*
G01X1391748Y360898D02*
X1392723Y360176D01*
G01X1390774D02*
X1391748Y360898D01*
G01X1390287Y359455D02*
X1390774Y360176D01*
G01X1389800Y358011D02*
X1390287Y359455D01*
G01X1389800Y355124D02*
Y358011D01*
G01X1390287Y353680D02*
X1389800Y355124D01*
G01X1410352Y393269D02*
X1411074Y392295D01*
G01X1409630Y393756D02*
X1410352Y393269D01*
G01X1408909Y393756D02*
X1409630D01*
G01X1408187Y393269D02*
X1408909Y393756D01*
G01X1407465Y392295D02*
X1408187Y393269D01*
G01X1407465Y391320D02*
Y392295D01*
G01X1408187Y390346D02*
X1407465Y391320D01*
G01X1408187Y398141D02*
X1407465Y399115D01*
G01Y384012D02*
X1416126D01*
G01X1410352Y421039D02*
X1408909Y421527D01*
G01X1410352Y415680D02*
X1411074Y416655D01*
G01Y413732D02*
X1410352Y414706D01*
G01X1407465Y414219D02*
X1411074Y413732D01*
G01X1407465Y417142D02*
Y414219D01*
G01X1410352Y401064D02*
X1411074Y400090D01*
G01X1409630Y401551D02*
X1410352Y401064D01*
G01X1408909Y401551D02*
X1409630D01*
G01X1408187Y401064D02*
X1408909Y401551D01*
G01X1407465Y400090D02*
X1408187Y401064D01*
G01X1407465Y399115D02*
Y400090D01*
G01X1408909Y424450D02*
X1410352Y424937D01*
G01X1408187Y423963D02*
X1408909Y424450D01*
G01X1407465Y422988D02*
X1408187Y423963D01*
G01Y422014D02*
X1407465Y422988D01*
G01X1408909Y421527D02*
X1408187Y422014D01*
G01X1403668Y625266D02*
X1400322Y628613D01*
G01X1403668Y625266D02*
X1419416D01*
G01X1393026Y635797D02*
X1392999Y635727D01*
G01X1393098Y635848D02*
X1393026Y635797D01*
G01X1393196Y635867D02*
X1393098Y635848D01*
G01X1388026Y635797D02*
X1387999Y635727D01*
G01X1388098Y635848D02*
X1388026Y635797D01*
G01X1388196Y635867D02*
X1388098Y635848D01*
G01X1389554D02*
X1389456Y635867D01*
G01X1389626Y635797D02*
X1389554Y635848D01*
G01X1389653Y635727D02*
X1389626Y635797D01*
G01X1394554Y635848D02*
X1394456Y635867D01*
G01X1394626Y635797D02*
X1394554Y635848D01*
G01X1394653Y635727D02*
X1394626Y635797D01*
G01X1394653Y636296D02*
G03X1394456Y636493I-197J0D01*
G01X1393196D02*
G03X1392999Y636296I0J-197D01*
G01X1389653D02*
G03X1389456Y636493I-197J0D01*
G01X1388196D02*
G03X1387999Y636296I0J-197D01*
G01X1409731Y632353D02*
G03X1410913Y633534I1J1181D01*
G01Y638652D02*
G03X1409731Y639833I-1181J0D01*
G01X1406227Y637274D02*
Y634912D01*
G01X1404535Y637274D02*
Y634912D01*
G01X1402566Y629203D02*
Y642983D01*
G01X1401188Y639833D02*
Y642983D01*
G01Y629203D02*
Y632353D01*
G01X1398826Y641802D02*
Y633928D01*
G01X1397645Y640621D02*
Y635109D01*
G01X1394653D02*
Y636295D01*
G01X1394456Y635109D02*
Y636493D01*
G01X1393196Y635109D02*
Y636493D01*
G01X1392999Y636295D02*
Y635109D01*
G01X1389653D02*
Y636295D01*
G01X1389456Y635109D02*
Y636493D01*
G01X1388196Y635109D02*
Y636493D01*
G01X1387999Y636295D02*
Y635109D01*
G01X1397645D02*
X1398826Y633928D01*
G01X1402566Y638578D02*
X1404535Y637274D01*
G01X1398826Y641802D02*
X1397645Y640621D01*
G01X1400322Y643573D02*
X1403668Y646920D01*
G01X1410457Y632602D02*
X1406227Y634912D01*
G01X1404535D02*
X1402566Y633608D01*
G01X1406227Y637274D02*
X1410457Y639584D01*
G01X1419416Y646920D02*
X1403668D01*
G01X1401188Y639833D02*
X1409731D01*
G01X1404535Y637274D02*
X1406227D01*
G01X1389456Y636493D02*
X1388196D01*
G01X1394456D02*
X1393196D01*
G01X1389456Y635867D02*
X1388196D01*
G01X1394456D02*
X1393196D01*
G01X1406227Y634912D02*
X1404535D01*
G01X1401188Y632353D02*
X1409731D01*
G01X1403668Y691014D02*
X1400322Y694361D01*
G01X1403668Y691014D02*
X1419416D01*
G01X1393026Y701545D02*
X1392999Y701475D01*
G01X1393098Y701596D02*
X1393026Y701545D01*
G01X1393196Y701615D02*
X1393098Y701596D01*
G01X1388026Y701545D02*
X1387999Y701475D01*
G01X1388098Y701596D02*
X1388026Y701545D01*
G01X1388196Y701615D02*
X1388098Y701596D01*
G01X1389554D02*
X1389456Y701615D01*
G01X1389626Y701545D02*
X1389554Y701596D01*
G01X1389653Y701475D02*
X1389626Y701545D01*
G01X1394554Y701596D02*
X1394456Y701615D01*
G01X1394626Y701545D02*
X1394554Y701596D01*
G01X1394653Y701475D02*
X1394626Y701545D01*
G01X1394653Y702044D02*
G03X1394456Y702241I-197J0D01*
G01X1393196D02*
G03X1392999Y702044I0J-197D01*
G01X1389653D02*
G03X1389456Y702241I-197J0D01*
G01X1388196D02*
G03X1387999Y702044I0J-197D01*
G01X1409731Y698101D02*
G03X1410913Y699282I1J1181D01*
G01Y704400D02*
G03X1409731Y705581I-1181J0D01*
G01X1406227Y703022D02*
Y700660D01*
G01X1404535Y703022D02*
Y700660D01*
G01X1402566Y694951D02*
Y708731D01*
G01X1397645Y700857D02*
X1398826Y699676D01*
G01X1401188Y705581D02*
Y708731D01*
G01Y694951D02*
Y698101D01*
G01X1398826Y707550D02*
Y699676D01*
G01X1397645Y706369D02*
Y700857D01*
G01X1394653D02*
Y702043D01*
G01X1394456Y700857D02*
Y702241D01*
G01X1393196Y700857D02*
Y702241D01*
G01X1392999Y702043D02*
Y700857D01*
G01X1389653D02*
Y702043D01*
G01X1389456Y700857D02*
Y702241D01*
G01X1388196Y700857D02*
Y702241D01*
G01X1387999Y702043D02*
Y700857D01*
G01X1402566Y704326D02*
X1404535Y703022D01*
G01X1410457Y698350D02*
X1406227Y700660D01*
G01X1419416Y712668D02*
X1403668D01*
G01X1398826Y707550D02*
X1397645Y706369D01*
G01X1400322Y709321D02*
X1403668Y712668D01*
G01X1401188Y705581D02*
X1409731D01*
G01X1404535Y703022D02*
X1406227D01*
G01X1389456Y702241D02*
X1388196D01*
G01X1394456D02*
X1393196D01*
G01X1389456Y701615D02*
X1388196D01*
G01X1394456D02*
X1393196D01*
G01X1406227Y700660D02*
X1404535D01*
G01X1401188Y698101D02*
X1409731D01*
G01X1404535Y700660D02*
X1402566Y699356D01*
G01X1406227Y703022D02*
X1410457Y705332D01*
G01X1423278Y52870D02*
X1422557Y52383D01*
G01X1424000Y53844D02*
X1423278Y52870D01*
G01X1424000Y54819D02*
Y53844D01*
G01X1423278Y55793D02*
X1424000Y54819D01*
G01X1421835Y56767D02*
X1423278Y55793D01*
G01X1419670D02*
X1421113Y56767D01*
G01X1418948Y54819D02*
X1419670Y55793D01*
G01X1418226D02*
X1418948Y54819D01*
G01X1417504Y56280D02*
X1418226Y55793D01*
G01X1416783Y56280D02*
X1417504D01*
G01X1416061Y55793D02*
X1416783Y56280D01*
G01X1415339Y54819D02*
X1416061Y55793D01*
G01X1415339Y53844D02*
Y54819D01*
G01X1416061Y52870D02*
X1415339Y53844D01*
G01X1418948D02*
Y54819D01*
G01X1421113Y56767D02*
X1421835D01*
G01X1415339Y46536D02*
X1424000D01*
G01X1423278Y76256D02*
X1422557Y75769D01*
G01X1424000Y77230D02*
X1423278Y76256D01*
G01X1424000Y78204D02*
Y77230D01*
G01X1423278Y79179D02*
X1424000Y78204D01*
G01X1422557Y79666D02*
X1423278Y79179D01*
G01X1421113Y80153D02*
X1422557Y79666D01*
G01X1419670D02*
X1421113Y80153D01*
G01X1418948Y79179D02*
X1419670Y79666D01*
G01X1418226Y78204D02*
X1418948Y79179D01*
G01X1418226Y77230D02*
Y78204D01*
G01X1418948Y76256D02*
X1418226Y77230D01*
G01X1415339Y76743D02*
X1418948Y76256D01*
G01X1415339Y79666D02*
Y76743D01*
G01X1423278Y60665D02*
X1422557Y60178D01*
G01X1424000Y61639D02*
X1423278Y60665D01*
G01X1424000Y62614D02*
Y61639D01*
G01X1423278Y63588D02*
X1424000Y62614D01*
G01X1422557Y64076D02*
X1423278Y63588D01*
G01X1421113Y64563D02*
X1422557Y64076D01*
G01X1419670D02*
X1421113Y64563D01*
G01X1418948Y63588D02*
X1419670Y64076D01*
G01X1418226Y62614D02*
X1418948Y63588D01*
G01X1418226Y61639D02*
Y62614D01*
G01X1418948Y60665D02*
X1418226Y61639D01*
G01X1415339Y61152D02*
X1418948Y60665D01*
G01X1415339Y64076D02*
Y61152D01*
G01X1423278Y69435D02*
X1424000Y69922D01*
G01Y69435D02*
X1423278D01*
G01X1424000Y69922D02*
Y69435D01*
G01X1426166Y109126D02*
Y93741D01*
G01X1423278Y86487D02*
X1424000Y85513D01*
G01X1422557Y86974D02*
X1423278Y86487D01*
G01X1421113Y87462D02*
X1422557Y86974D01*
G01X1418226Y87462D02*
X1421113D01*
G01X1416783Y86974D02*
X1418226Y87462D01*
G01X1416061Y86487D02*
X1416783Y86974D01*
G01X1415339Y85513D02*
X1416061Y86487D01*
G01Y84538D02*
X1415339Y85513D01*
G01X1416783Y84051D02*
X1416061Y84538D01*
G01X1418226Y83564D02*
X1416783Y84051D01*
G01X1421113Y83564D02*
X1418226D01*
G01X1422557Y84051D02*
X1421113Y83564D01*
G01X1423278Y84538D02*
X1422557Y84051D01*
G01X1424000Y85513D02*
X1423278Y84538D01*
G01X1426166Y113063D02*
G03X1430103Y109126I3937J0D01*
G01X1426166Y113063D02*
G03X1430103Y109126I3937J0D01*
G01X1455693Y122906D02*
G03I-11811J0D01*
G01X1426166Y113063D02*
Y180189D01*
G01Y113063D02*
Y180189D01*
G01X1430103Y109126D02*
X1453725D01*
G01X1430103D02*
X1453725D01*
G01X1426166Y184126D02*
X1468139D01*
G01X1425607Y187660D02*
X1425533Y187788D01*
G01X1425682Y187515D02*
X1425607Y187660D01*
G01X1425759Y187352D02*
X1425682Y187515D01*
G01X1425837Y187171D02*
X1425759Y187352D01*
G01X1425916Y186971D02*
X1425837Y187171D01*
G01X1425998Y186750D02*
X1425916Y186971D01*
G01X1426081Y186506D02*
X1425998Y186750D01*
G01X1426166Y186240D02*
X1426081Y186506D01*
G01X1423687Y186493D02*
X1423598Y186213D01*
G01X1423773Y186746D02*
X1423687Y186493D01*
G01X1423857Y186973D02*
X1423773Y186746D01*
G01X1423938Y187177D02*
X1423857Y186973D01*
G01X1424016Y187359D02*
X1423938Y187177D01*
G01X1424093Y187521D02*
X1424016Y187359D01*
G01X1424167Y187663D02*
X1424093Y187521D01*
G01X1424239Y187788D02*
X1424167Y187663D01*
G01X1425533Y187788D02*
G03X1424239I-647J335D01*
G01X1426166Y190038D02*
G03X1423598Y186213I-1280J-1915D01*
G01X1426166Y180189D02*
G03X1422229Y184126I-3937J0D01*
G01X1426166Y180189D02*
G03X1422229Y184126I-3937J0D01*
G01X1426166Y186213D02*
Y203418D01*
G01X1425378Y190819D02*
Y200859D01*
G01X1423213Y190819D02*
Y200859D01*
G01X1422426Y186213D02*
Y203418D01*
G01X1420772Y188260D02*
Y203418D01*
G01X1420654Y188260D02*
Y203418D01*
G01X1419866Y200859D02*
Y190819D01*
G01X1418784Y193331D02*
Y201449D01*
G01X1418193Y200859D02*
Y193575D01*
G01X1415634Y189048D02*
Y190819D01*
G01X1414453Y189048D02*
Y203418D01*
G01X1414335Y197985D02*
Y193890D01*
G01X1411815Y197985D02*
Y193890D01*
G01X1411697Y203418D02*
Y189048D01*
G01X1410516D02*
Y190819D01*
G01X1415437D02*
X1415682Y190229D01*
G01D02*
X1418784Y193331D01*
G01X1418193Y193575D02*
X1415437Y190819D01*
G01X1422426Y188260D02*
X1426166Y190819D01*
G01X1418193Y193575D02*
X1418784Y193331D01*
G01X1414335Y194166D02*
X1411815D01*
G01X1414335Y193890D02*
X1411815D01*
G01X1422426Y193006D02*
X1420654D01*
G01Y192430D02*
X1422426D01*
G01X1426166Y192197D02*
X1420772D01*
G01X1420654Y191728D02*
X1422426D01*
G01Y190819D02*
X1426166D01*
G01X1422426Y190769D02*
X1420654D01*
G01X1425533Y187788D02*
X1424239D01*
G01X1426166Y186213D02*
X1422426D01*
G01X1413213Y196030D02*
X1413226Y196068D01*
G01X1413151D02*
X1413139Y196030D01*
G01X1423607Y200859D02*
Y203418D01*
G01X1415634D02*
Y200859D01*
G01X1413744Y195268D02*
Y196607D01*
G01X1413594Y195578D02*
Y196168D01*
G01X1413521Y196105D02*
Y195917D01*
G01Y195841D02*
Y195578D01*
G01X1413213Y195992D02*
Y196030D01*
G01X1413139D02*
Y195980D01*
G01X1413041Y195754D02*
Y195829D01*
G01X1412746Y195578D02*
Y195754D01*
G01Y196068D02*
Y195829D01*
G01X1412672Y196168D02*
Y195829D01*
G01Y195754D02*
Y195578D01*
G01X1412549Y195829D02*
Y195754D01*
G01X1412406Y196607D02*
Y195268D01*
G01X1410516Y203418D02*
Y200859D01*
G01X1413226Y195955D02*
X1413213Y195992D01*
G01X1413139Y195980D02*
X1413151Y195942D01*
G01X1413188Y196118D02*
X1413151Y196068D01*
G01X1418784Y201449D02*
X1418193Y200859D01*
G01X1412406Y195268D02*
X1411815Y194678D01*
G01X1414335Y197197D02*
X1413744Y196607D01*
G01X1413226Y196068D02*
X1413250Y196093D01*
G01X1413238Y196156D02*
X1413188Y196118D01*
G01X1413151Y195942D02*
X1413188Y195892D01*
G01X1413041Y195829D02*
X1412746Y196168D01*
G01X1412955Y195829D02*
X1412746Y196068D01*
G01X1413250Y195930D02*
X1413226Y195955D01*
G01X1413744Y195268D02*
X1414335Y194678D01*
G01X1412406Y196607D02*
X1411815Y197197D01*
G01X1413188Y195892D02*
X1413238Y195854D01*
G01X1413250Y196093D02*
X1413287Y196105D01*
G01Y195917D02*
X1413250Y195930D01*
G01X1413238Y195854D02*
X1413299Y195841D01*
G01X1420654Y201371D02*
X1422426D01*
G01X1420772Y200859D02*
X1426166D01*
G01X1422426Y200386D02*
X1420654D01*
G01Y199599D02*
X1422426D01*
G01Y198333D02*
X1420654D01*
G01X1411815Y197985D02*
X1414335D01*
G01X1420654Y197549D02*
X1422426D01*
G01X1420654Y197278D02*
X1422426D01*
G01X1414335Y197197D02*
X1411815D01*
G01X1414335Y197108D02*
X1411815D01*
G01X1414335Y196686D02*
X1411815D01*
G01X1413744Y196607D02*
X1412406D01*
G01X1422426Y196494D02*
X1420654D01*
G01X1412746Y196168D02*
X1412672D01*
G01X1413594D02*
X1413299D01*
G01X1413287Y196105D02*
X1413521D01*
G01X1420654Y195977D02*
X1422426D01*
G01X1413521Y195917D02*
X1413287D01*
G01X1413299Y195841D02*
X1413521D01*
G01X1412746Y195829D02*
X1412955D01*
G01X1412672D02*
X1412549D01*
G01Y195754D02*
X1412672D01*
G01X1412746D02*
X1413041D01*
G01X1413521Y195578D02*
X1413594D01*
G01X1412672D02*
X1412746D01*
G01X1412406Y195268D02*
X1413744D01*
G01X1422426Y195189D02*
X1420654D01*
G01X1414335Y194678D02*
X1411815D01*
G01X1420654Y194599D02*
X1422426D01*
G01X1414335Y194588D02*
X1411815D01*
G01X1413299Y196168D02*
X1413238Y196156D01*
G01X1422583Y350071D02*
G03I-4291J0D01*
G01X1455693Y352040D02*
G03I-11811J0D01*
G01X1418292Y354008D02*
Y375784D01*
G01X1413961Y394243D02*
X1415404Y393269D01*
G01X1413239Y394243D02*
X1413961D01*
G01X1412517Y393756D02*
X1413239Y394243D01*
G01X1411796Y393269D02*
X1412517Y393756D01*
G01X1411074Y392295D02*
X1411796Y393269D01*
G01X1415404Y390346D02*
X1414683Y389858D01*
G01X1416126Y391320D02*
X1415404Y390346D01*
G01X1416126Y392295D02*
Y391320D01*
G01X1415404Y393269D02*
X1416126Y392295D01*
G01X1415404Y398141D02*
X1414683Y397654D01*
G01X1416126Y399115D02*
X1415404Y398141D01*
G01X1411074Y391320D02*
Y392295D01*
G01X1413239Y421039D02*
X1410352D01*
G01X1414683Y421527D02*
X1413239Y421039D01*
G01X1415404Y413732D02*
X1414683Y413244D01*
G01X1416126Y414706D02*
X1415404Y413732D01*
G01X1416126Y415680D02*
Y414706D01*
G01X1415404Y416655D02*
X1416126Y415680D01*
G01X1414683Y417142D02*
X1415404Y416655D01*
G01X1413239Y417629D02*
X1414683Y417142D01*
G01X1411796D02*
X1413239Y417629D01*
G01X1411074Y416655D02*
X1411796Y417142D01*
G01X1410352Y414706D02*
Y415680D01*
G01X1415404Y406911D02*
X1416126Y407398D01*
G01Y406911D02*
X1415404D01*
G01X1416126Y407398D02*
Y406911D01*
G01X1413961Y402039D02*
X1415404Y401064D01*
G01X1413239Y402039D02*
X1413961D01*
G01X1412517Y401551D02*
X1413239Y402039D01*
G01X1411796Y401064D02*
X1412517Y401551D01*
G01X1411074Y400090D02*
X1411796Y401064D01*
G01X1416126Y400090D02*
Y399115D01*
G01X1415404Y401064D02*
X1416126Y400090D01*
G01X1411074Y399115D02*
Y400090D01*
G01X1415404Y423963D02*
X1416126Y422988D01*
G01X1414683Y424450D02*
X1415404Y423963D01*
G01X1413239Y424937D02*
X1414683Y424450D01*
G01X1410352Y424937D02*
X1413239D01*
G01X1415404Y422014D02*
X1414683Y421527D01*
G01X1416126Y422988D02*
X1415404Y422014D01*
G01X1422979Y497038D02*
G03X1426916Y493101I3937J0D01*
G01X1422979Y497038D02*
G03X1426916Y493101I3937J0D01*
G01X1451523Y506880D02*
G03I-10827J0D01*
G01X1422979Y497038D02*
Y564164D01*
G01Y497038D02*
Y564164D01*
G01X1426916Y493101D02*
X1450538D01*
G01X1426916D02*
X1450538D01*
G01X1422979Y564164D02*
G03X1419042Y568101I-3937J0D01*
G01X1422979Y564164D02*
G03X1419042Y568101I-3937J0D01*
G01X1419416Y625266D02*
G03X1421385Y627235I0J1969D01*
G01Y644951D02*
G03X1419416Y646920I-1969J0D01*
G01X1421385Y627235D02*
Y644951D01*
G01X1410913Y638652D02*
Y633534D01*
G01X1419416Y691014D02*
G03X1421385Y692983I0J1969D01*
G01D02*
Y710699D01*
G01D02*
G03X1419416Y712668I-1969J0D01*
G01X1410913Y704400D02*
Y699282D01*
G01X1419397Y734046D02*
G03I-4292J0D01*
G01X1448964Y736014D02*
G03I-8268J0D01*
G01X1451523D02*
G03I-10827J0D01*
G01X1444961Y-224061D02*
Y-314191D01*
G01X1453725Y109126D02*
G03X1457662Y113063I0J3937D01*
G01X1453725Y109126D02*
G03X1457662Y113063I0J3937D01*
G01X1450378Y122906D02*
G03I-6496J0D01*
G01X1449788Y149284D02*
G03I-4292J0D01*
G01X1445496Y153221D02*
Y191741D01*
G01X1453725Y149284D02*
X1468932D01*
G01X1441166Y205816D02*
Y210200D01*
G01X1434670Y209226D02*
X1441166Y205816D01*
G01X1443331Y209226D02*
X1434670D01*
G01X1442609Y216534D02*
X1443331Y215560D01*
G01X1441887Y217021D02*
X1442609Y216534D01*
G01X1440444Y217509D02*
X1441887Y217021D01*
G01X1436113D02*
X1437557Y217509D01*
G01X1435391Y216534D02*
X1436113Y217021D01*
G01X1434670Y215560D02*
X1435391Y216534D01*
G01Y214586D02*
X1434670Y215560D01*
G01X1436113Y214098D02*
X1435391Y214586D01*
G01X1437557Y213611D02*
X1436113Y214098D01*
G01X1440444Y213611D02*
X1437557D01*
G01X1441887Y214098D02*
X1440444Y213611D01*
G01X1442609Y214586D02*
X1441887Y214098D01*
G01X1443331Y215560D02*
X1442609Y214586D01*
G01X1434670Y199969D02*
X1443331D01*
G01X1441166Y229202D02*
Y233586D01*
G01X1434670Y232612D02*
X1441166Y229202D01*
G01X1443331Y232612D02*
X1434670D01*
G01X1437557Y217509D02*
X1440444D01*
G01X1442609Y222868D02*
X1443331Y223355D01*
G01Y222868D02*
X1442609D01*
G01X1443331Y223355D02*
Y222868D01*
G01X1434670Y238946D02*
X1443331D01*
G01X1452150Y352040D02*
G03I-8268J0D01*
G01X1443882Y355977D02*
Y375784D01*
G01X1457662Y361882D02*
G03X1453725Y365819I-3937J0D01*
G01X1457662Y361882D02*
G03X1453725Y365819I-3937J0D01*
G01X1441717Y382063D02*
Y385961D01*
G01X1439551Y382550D02*
X1441717Y382063D01*
G01X1438108Y383525D02*
X1439551Y382550D01*
G01X1436664Y385474D02*
X1438108Y383525D01*
G01X1435942Y385961D02*
X1436664Y385474D01*
G01X1434499Y385961D02*
X1435942D01*
G01X1433777Y385474D02*
X1434499Y385961D01*
G01X1433055Y384499D02*
X1433777Y385474D01*
G01X1433055Y383525D02*
Y384499D01*
G01X1433777Y382550D02*
X1433055Y383525D01*
G01X1434499Y382063D02*
X1433777Y382550D01*
G01X1441717Y389858D02*
X1433055Y393756D01*
G01Y389858D02*
X1441717Y393756D01*
G01X1440995Y416167D02*
X1441717Y415193D01*
G01X1440273Y416655D02*
X1440995Y416167D01*
G01X1438829Y417142D02*
X1440273Y416655D01*
G01X1435942Y417142D02*
X1438829D01*
G01X1434499Y416655D02*
X1435942Y417142D01*
G01X1433777Y416167D02*
X1434499Y416655D01*
G01X1433055Y415193D02*
X1433777Y416167D01*
G01Y414219D02*
X1433055Y415193D01*
G01X1434499Y413732D02*
X1433777Y414219D01*
G01X1435942Y413244D02*
X1434499Y413732D01*
G01X1438829Y413244D02*
X1435942D01*
G01X1440273Y413732D02*
X1438829Y413244D01*
G01X1440995Y414219D02*
X1440273Y413732D01*
G01X1441717Y415193D02*
X1440995Y414219D01*
G01X1439551Y405449D02*
Y409834D01*
G01X1433055Y408860D02*
X1439551Y405449D01*
G01X1441717Y408860D02*
X1433055D01*
G01Y399602D02*
X1441717D01*
G01X1440995Y439553D02*
X1441717Y438579D01*
G01X1440273Y440041D02*
X1440995Y439553D01*
G01X1438829Y440528D02*
X1440273Y440041D01*
G01X1435942Y440528D02*
X1438829D01*
G01X1434499Y440041D02*
X1435942Y440528D01*
G01X1433777Y439553D02*
X1434499Y440041D01*
G01X1433055Y438579D02*
X1433777Y439553D01*
G01Y437604D02*
X1433055Y438579D01*
G01X1434499Y437117D02*
X1433777Y437604D01*
G01X1435942Y436630D02*
X1434499Y437117D01*
G01X1438829Y436630D02*
X1435942D01*
G01X1440273Y437117D02*
X1438829Y436630D01*
G01X1440995Y437604D02*
X1440273Y437117D01*
G01X1441717Y438579D02*
X1440995Y437604D01*
G01Y431758D02*
X1441717Y430784D01*
G01X1440273Y432245D02*
X1440995Y431758D01*
G01X1438829Y432732D02*
X1440273Y432245D01*
G01X1435942Y432732D02*
X1438829D01*
G01X1434499Y432245D02*
X1435942Y432732D01*
G01X1433777Y431758D02*
X1434499Y432245D01*
G01X1433055Y430784D02*
X1433777Y431758D01*
G01Y429809D02*
X1433055Y430784D01*
G01X1434499Y429322D02*
X1433777Y429809D01*
G01X1435942Y428835D02*
X1434499Y429322D01*
G01X1438829Y428835D02*
X1435942D01*
G01X1440273Y429322D02*
X1438829Y428835D01*
G01X1440995Y429809D02*
X1440273Y429322D01*
G01X1441717Y430784D02*
X1440995Y429809D01*
G01Y422501D02*
X1441717Y422988D01*
G01Y422501D02*
X1440995D01*
G01X1441717Y422988D02*
Y422501D01*
G01X1450538Y493101D02*
G03X1454476Y497038I1J3937D01*
G01X1450538Y493101D02*
G03X1454476Y497038I1J3937D01*
G01X1447192Y506880D02*
G03I-6496J0D01*
G01X1444667Y499035D02*
X1444626Y498993D01*
G01X1444544Y499077D02*
X1444667Y499202D01*
G01X1444011Y499035D02*
X1443929Y498951D01*
G01Y499119D02*
X1444011Y499202D01*
G01X1442822Y499035D02*
X1442781Y498993D01*
G01X1442699Y499077D02*
X1442822Y499202D01*
G01X1441263Y498072D02*
X1441387Y498197D01*
G01X1442166Y499035D02*
X1442084Y498951D01*
G01Y499119D02*
X1442166Y499202D01*
G01X1440361Y499705D02*
X1440238Y499580D01*
G01X1441140Y498239D02*
X1441304Y498491D01*
G01X1440484Y499537D02*
X1440320Y499286D01*
G01X1439746Y498616D02*
X1439664Y498491D01*
G01X1444626Y498993D02*
X1444585Y498910D01*
G01X1442781Y498993D02*
X1442740Y498910D01*
G01X1441387Y498197D02*
X1441468Y498365D01*
G01X1440238Y499580D02*
X1440156Y499412D01*
G01X1441468Y498365D02*
X1441509Y498491D01*
G01X1440156Y499412D02*
X1440115Y499286D01*
G01X1441509Y498491D02*
X1441550Y498700D01*
G01X1440115Y499286D02*
X1440074Y499077D01*
G01X1441304Y498491D02*
X1441346Y498742D01*
G01X1440320Y499286D02*
X1440279Y499035D01*
G01X1454476Y497038D02*
Y745857D01*
G01Y497038D02*
Y745857D01*
G01X1445241Y498910D02*
Y497904D01*
G01X1445037D02*
Y498910D01*
G01X1444585D02*
Y497904D01*
G01X1444380D02*
Y498910D01*
G01X1443929Y499245D02*
Y499119D01*
G01Y498951D02*
Y497904D01*
G01X1443724D02*
Y499245D01*
G01X1441017Y498156D02*
X1441140Y498239D01*
G01X1440607Y499621D02*
X1440484Y499537D01*
G01X1443396Y498910D02*
Y497904D01*
G01X1443191D02*
Y498910D01*
G01X1442740D02*
Y497904D01*
G01X1442535D02*
Y498910D01*
G01X1442084Y499245D02*
Y499119D01*
G01Y498951D02*
Y497904D01*
G01X1441879D02*
Y499245D01*
G01X1441550Y498700D02*
Y499077D01*
G01X1441346Y498742D02*
Y499035D01*
G01X1440279D02*
Y498742D01*
G01X1440074Y499077D02*
Y498700D01*
G01X1438557Y499873D02*
Y497904D01*
G01X1438311Y499077D02*
Y499873D01*
G01Y497904D02*
Y498826D01*
G01X1437163Y499873D02*
Y499077D01*
G01Y498826D02*
Y497904D01*
G01X1436916D02*
Y499873D01*
G01X1441346Y499035D02*
X1441304Y499286D01*
G01X1440279Y498742D02*
X1440320Y498491D01*
G01X1441550Y499077D02*
X1441509Y499286D01*
G01X1440074Y498700D02*
X1440115Y498491D01*
G01X1444749Y499077D02*
X1444667Y499035D01*
G01X1442904Y499077D02*
X1442822Y499035D01*
G01X1439746Y499202D02*
X1439172Y498910D01*
G01X1438885D02*
X1439664Y499328D01*
G01X1441058Y497946D02*
X1441263Y498072D01*
G01X1440566Y499831D02*
X1440361Y499705D01*
G01X1441509Y499286D02*
X1441468Y499412D01*
G01X1440115Y498491D02*
X1440156Y498365D01*
G01X1445159Y499119D02*
X1445241Y498910D01*
G01X1443314Y499119D02*
X1443396Y498910D01*
G01X1445037D02*
X1444995Y498993D01*
G01X1444380Y498910D02*
X1444339Y498993D01*
G01X1443191Y498910D02*
X1443150Y498993D01*
G01X1442535Y498910D02*
X1442494Y498993D01*
G01X1444667Y499202D02*
X1444790Y499245D01*
G01X1444134Y499077D02*
X1444011Y499035D01*
G01Y499202D02*
X1444134Y499245D01*
G01X1442822Y499202D02*
X1442945Y499245D01*
G01X1442288Y499077D02*
X1442166Y499035D01*
G01Y499202D02*
X1442288Y499245D01*
G01X1441468Y499412D02*
X1441387Y499580D01*
G01X1440156Y498365D02*
X1440238Y498197D01*
G01X1441304Y499286D02*
X1441140Y499537D01*
G01X1440320Y498491D02*
X1440484Y498239D01*
G01X1439664Y499328D02*
X1439746Y499202D01*
G01X1445077D02*
X1445159Y499119D01*
G01X1444995Y498993D02*
X1444954Y499035D01*
G01X1444421Y499202D02*
X1444544Y499077D01*
G01X1444339Y498993D02*
X1444298Y499035D01*
G01X1443232Y499202D02*
X1443314Y499119D01*
G01X1443150Y498993D02*
X1443109Y499035D01*
G01X1442576Y499202D02*
X1442699Y499077D01*
G01X1442494Y498993D02*
X1442453Y499035D01*
G01X1441387Y499580D02*
X1441263Y499705D01*
G01X1440238Y498197D02*
X1440361Y498072D01*
G01X1441140Y499537D02*
X1441017Y499621D01*
G01X1440484Y498239D02*
X1440607Y498156D01*
G01X1441263Y499705D02*
X1441058Y499831D01*
G01X1440361Y498072D02*
X1440566Y497946D01*
G01X1439664Y498491D02*
X1438885Y498910D01*
G01X1444954Y499035D02*
X1444872Y499077D01*
G01X1444298Y499035D02*
X1444216Y499077D01*
G01X1443109Y499035D02*
X1443027Y499077D01*
G01X1442453Y499035D02*
X1442371Y499077D01*
G01X1439172Y498910D02*
X1439746Y498616D01*
G01X1444954Y499245D02*
X1445077Y499202D01*
G01X1444298Y499245D02*
X1444421Y499202D01*
G01X1443109Y499245D02*
X1443232Y499202D01*
G01X1442453Y499245D02*
X1442576Y499202D01*
G01X1441017Y499621D02*
X1440812Y499663D01*
G01X1440607Y498156D02*
X1440812Y498113D01*
G01X1441058Y499831D02*
X1440812Y499873D01*
G01X1440566Y497946D02*
X1440812Y497904D01*
G01X1438311Y499873D02*
X1438557D01*
G01X1436916D02*
X1437163D01*
G01X1443724Y499245D02*
X1443929D01*
G01X1444134D02*
X1444298D01*
G01X1444790D02*
X1444954D01*
G01X1441879D02*
X1442084D01*
G01X1442288D02*
X1442453D01*
G01X1442945D02*
X1443109D01*
G01X1437163Y499077D02*
X1438311D01*
G01X1443027D02*
X1442904D01*
G01X1442371D02*
X1442288D01*
G01X1444872D02*
X1444749D01*
G01X1444216D02*
X1444134D01*
G01X1438311Y498826D02*
X1437163D01*
G01Y497904D02*
X1436916D01*
G01X1438557D02*
X1438311D01*
G01X1442084D02*
X1441879D01*
G01X1442740D02*
X1442535D01*
G01X1443929D02*
X1443724D01*
G01X1444585D02*
X1444380D01*
G01X1443396D02*
X1443191D01*
G01X1445241D02*
X1445037D01*
G01X1440812Y499873D02*
X1440566Y499831D01*
G01X1440812Y497904D02*
X1441058Y497946D01*
G01X1440812Y499663D02*
X1440607Y499621D01*
G01X1440812Y498113D02*
X1441017Y498156D01*
G01X1446601Y533258D02*
G03I-4291J0D01*
G01X1440952Y726870D02*
X1440911Y727121D01*
G01X1439885Y726576D02*
X1439926Y726325D01*
G01X1441157Y726912D02*
X1441116Y727121D01*
G01X1439680Y726535D02*
X1439722Y726325D01*
G01X1441116Y727121D02*
X1441075Y727247D01*
G01X1439722Y726325D02*
X1439763Y726200D01*
G01X1444766Y726954D02*
X1444848Y726744D01*
G01X1442920Y726954D02*
X1443002Y726744D01*
G01X1444643D02*
X1444601Y726828D01*
G01X1443987Y726744D02*
X1443946Y726828D01*
G01X1442797Y726744D02*
X1442756Y726828D01*
G01X1442141Y726744D02*
X1442100Y726828D01*
G01X1441075Y727247D02*
X1440993Y727414D01*
G01X1439763Y726200D02*
X1439844Y726032D01*
G01X1440911Y727121D02*
X1440747Y727372D01*
G01X1439926Y726325D02*
X1440090Y726074D01*
G01X1439270Y727163D02*
X1439352Y727037D01*
G01X1444848Y726744D02*
Y725739D01*
G01X1444643D02*
Y726744D01*
G01X1444192D02*
Y725739D01*
G01X1443987D02*
Y726744D01*
G01X1444684Y727037D02*
X1444766Y726954D01*
G01X1444601Y726828D02*
X1444561Y726870D01*
G01X1444027Y727037D02*
X1444151Y726912D01*
G01X1443946Y726828D02*
X1443905Y726870D01*
G01X1442838Y727037D02*
X1442920Y726954D01*
G01X1442756Y726828D02*
X1442715Y726870D01*
G01X1442182Y727037D02*
X1442305Y726912D01*
G01X1442100Y726828D02*
X1442059Y726870D01*
G01X1440993Y727414D02*
X1440870Y727540D01*
G01X1439844Y726032D02*
X1439968Y725906D01*
G01X1443535Y727079D02*
Y726954D01*
G01Y726786D02*
Y725739D01*
G01X1443330D02*
Y727079D01*
G01X1443002Y726744D02*
Y725739D01*
G01X1442797D02*
Y726744D01*
G01X1442346D02*
Y725739D01*
G01X1442141D02*
Y726744D01*
G01X1441690Y727079D02*
Y726954D01*
G01Y726786D02*
Y725739D01*
G01X1441485D02*
Y727079D01*
G01X1441157Y726535D02*
Y726912D01*
G01X1440952Y726576D02*
Y726870D01*
G01X1439885D02*
Y726576D01*
G01X1439680Y726912D02*
Y726535D01*
G01X1438163Y727707D02*
Y725739D01*
G01X1437917D02*
Y726660D01*
G01Y726912D02*
Y727707D01*
G01X1436769Y726660D02*
Y725739D01*
G01Y727707D02*
Y726912D01*
G01X1436523Y725739D02*
Y727707D01*
G01X1440747Y727372D02*
X1440624Y727456D01*
G01X1440090Y726074D02*
X1440214Y725990D01*
G01X1440870Y727540D02*
X1440664Y727665D01*
G01X1441116Y726325D02*
X1441157Y726535D01*
G01X1439722Y727121D02*
X1439680Y726912D01*
G01X1440911Y726325D02*
X1440952Y726576D01*
G01X1439926Y727121D02*
X1439885Y726870D01*
G01X1439968Y725906D02*
X1440172Y725781D01*
G01X1439270Y726325D02*
X1438491Y726744D01*
G01X1444561Y726870D02*
X1444479Y726912D01*
G01X1443905Y726870D02*
X1443822Y726912D01*
G01X1442715Y726870D02*
X1442633Y726912D01*
G01X1442059Y726870D02*
X1441977Y726912D01*
G01X1438778Y726744D02*
X1439352Y726451D01*
G01X1441075Y726200D02*
X1441116Y726325D01*
G01X1439763Y727247D02*
X1439722Y727121D01*
G01X1444233Y726828D02*
X1444192Y726744D01*
G01X1442387Y726828D02*
X1442346Y726744D01*
G01X1440993Y726032D02*
X1441075Y726200D01*
G01X1439844Y727414D02*
X1439763Y727247D01*
G01X1444561Y727079D02*
X1444684Y727037D01*
G01X1443905Y727079D02*
X1444027Y727037D01*
G01X1442715Y727079D02*
X1442838Y727037D01*
G01X1442059Y727079D02*
X1442182Y727037D01*
G01X1440624Y727456D02*
X1440418Y727498D01*
G01X1440214Y725990D02*
X1440418Y725948D01*
G01X1440664Y727665D02*
X1440418Y727707D01*
G01X1440172Y725781D02*
X1440418Y725739D01*
G01X1440747Y726074D02*
X1440911Y726325D01*
G01X1440090Y727372D02*
X1439926Y727121D01*
G01X1439352Y726451D02*
X1439270Y726325D01*
G01X1437917Y727707D02*
X1438163D01*
G01X1436523D02*
X1436769D01*
G01X1444274Y726870D02*
X1444233Y726828D01*
G01X1444151Y726912D02*
X1444274Y727037D01*
G01X1443617Y726870D02*
X1443535Y726786D01*
G01Y726954D02*
X1443617Y727037D01*
G01X1442428Y726870D02*
X1442387Y726828D01*
G01X1442305Y726912D02*
X1442428Y727037D01*
G01X1440870Y725906D02*
X1440993Y726032D01*
G01X1441772Y726870D02*
X1441690Y726786D01*
G01Y726954D02*
X1441772Y727037D01*
G01X1439968Y727540D02*
X1439844Y727414D01*
G01X1443330Y727079D02*
X1443535D01*
G01X1443740D02*
X1443905D01*
G01X1444397D02*
X1444561D01*
G01X1441895D02*
X1442059D01*
G01X1442551D02*
X1442715D01*
G01X1441485D02*
X1441690D01*
G01X1436769Y726912D02*
X1437917D01*
G01X1442633D02*
X1442510D01*
G01X1441977D02*
X1441895D01*
G01X1444479D02*
X1444355D01*
G01X1443822D02*
X1443740D01*
G01X1437917Y726660D02*
X1436769D01*
G01Y725739D02*
X1436523D01*
G01X1438163D02*
X1437917D01*
G01X1441690D02*
X1441485D01*
G01X1443002D02*
X1442797D01*
G01X1442346D02*
X1442141D01*
G01X1443535D02*
X1443330D01*
G01X1444848D02*
X1444643D01*
G01X1444192D02*
X1443987D01*
G01X1440418Y727707D02*
X1440172Y727665D01*
G01X1440418Y725739D02*
X1440664Y725781D01*
G01X1440418Y727498D02*
X1440214Y727456D01*
G01X1440418Y725948D02*
X1440624Y725990D01*
G01X1440664Y725781D02*
X1440870Y725906D01*
G01X1440172Y727665D02*
X1439968Y727540D01*
G01X1440624Y725990D02*
X1440747Y726074D01*
G01X1440214Y727456D02*
X1440090Y727372D01*
G01X1444355Y726912D02*
X1444274Y726870D01*
G01X1442510Y726912D02*
X1442428Y726870D01*
G01X1439352Y727037D02*
X1438778Y726744D01*
G01X1438491D02*
X1439270Y727163D01*
G01X1444274Y727037D02*
X1444397Y727079D01*
G01X1443740Y726912D02*
X1443617Y726870D01*
G01Y727037D02*
X1443740Y727079D01*
G01X1442428Y727037D02*
X1442551Y727079D01*
G01X1441895Y726912D02*
X1441772Y726870D01*
G01Y727037D02*
X1441895Y727079D01*
G01X1454476Y749794D02*
Y774072D01*
G01Y745857D02*
G03X1450538Y749794I-3937J0D01*
G01X1454476Y745857D02*
G03X1450538Y749794I-3937J0D01*
G01X1443649Y782300D02*
X1452310D01*
G01X1450145Y788147D02*
Y792532D01*
G01X1443649Y791557D02*
X1450145Y788147D01*
G01X1452310Y791557D02*
X1443649D01*
G01X1450145Y800327D02*
X1451588Y799352D01*
G01X1449423Y800327D02*
X1450145D01*
G01X1451588Y805199D02*
X1452310Y805686D01*
G01Y805199D02*
X1451588D01*
G01X1452310Y805686D02*
Y805199D01*
G01X1447979Y799352D02*
X1449423Y800327D01*
G01X1447257Y798378D02*
X1447979Y799352D01*
G01X1446536D02*
X1447257Y798378D01*
G01X1445814Y799839D02*
X1446536Y799352D01*
G01X1445092Y799839D02*
X1445814D01*
G01X1444370Y799352D02*
X1445092Y799839D01*
G01X1443649Y798378D02*
X1444370Y799352D01*
G01X1443649Y797404D02*
Y798378D01*
G01X1444370Y796429D02*
X1443649Y797404D01*
G01X1451588Y796429D02*
X1450866Y795942D01*
G01X1452310Y797404D02*
X1451588Y796429D01*
G01X1452310Y798378D02*
Y797404D01*
G01X1451588Y799352D02*
X1452310Y798378D01*
G01X1447257Y797404D02*
Y798378D01*
G01X1451588Y822251D02*
X1452310Y821276D01*
G01X1450866Y822738D02*
X1451588Y822251D01*
G01X1449423Y823225D02*
X1450866Y822738D01*
G01X1446536Y823225D02*
X1449423D01*
G01X1445092Y822738D02*
X1446536Y823225D01*
G01X1444370Y822251D02*
X1445092Y822738D01*
G01X1443649Y821276D02*
X1444370Y822251D01*
G01Y820302D02*
X1443649Y821276D01*
G01X1445092Y819815D02*
X1444370Y820302D01*
G01X1446536Y819328D02*
X1445092Y819815D01*
G01X1449423Y819328D02*
X1446536D01*
G01X1450866Y819815D02*
X1449423Y819328D01*
G01X1451588Y820302D02*
X1450866Y819815D01*
G01X1452310Y821276D02*
X1451588Y820302D01*
G01Y812020D02*
X1450866Y811533D01*
G01X1452310Y812994D02*
X1451588Y812020D01*
G01X1452310Y813969D02*
Y812994D01*
G01X1451588Y814943D02*
X1452310Y813969D01*
G01X1450866Y815430D02*
X1451588Y814943D01*
G01X1449423Y815917D02*
X1450866Y815430D01*
G01X1447979D02*
X1449423Y815917D01*
G01X1447257Y814943D02*
X1447979Y815430D01*
G01X1446536Y813969D02*
X1447257Y814943D01*
G01X1446536Y812994D02*
Y813969D01*
G01X1447257Y812020D02*
X1446536Y812994D01*
G01X1443649Y812507D02*
X1447257Y812020D01*
G01X1443649Y815430D02*
Y812507D01*
G01X1470157Y-390518D02*
Y-407840D01*
G01X1457662Y113063D02*
Y361882D01*
G01Y113063D02*
Y361882D01*
G01X1477161Y160111D02*
Y151449D01*
G01X1476368Y194954D02*
Y186292D01*
G01X1470157Y970112D02*
Y952789D01*
G01X1492264Y152171D02*
X1492751Y151449D01*
G01X1492264D02*
Y152171D01*
G01X1492751Y151449D02*
X1492264D01*
G01X1485930Y152171D02*
X1484956Y151449D01*
G01X1486418Y152893D02*
X1485930Y152171D01*
G01X1486905Y154337D02*
X1486418Y152893D01*
G01X1486905Y157224D02*
Y154337D01*
G01X1486418Y158667D02*
X1486905Y157224D01*
G01X1485930Y159389D02*
X1486418Y158667D01*
G01X1484956Y160111D02*
X1485930Y159389D01*
G01X1483981D02*
X1484956Y160111D01*
G01X1483494Y158667D02*
X1483981Y159389D01*
G01X1483007Y157224D02*
X1483494Y158667D01*
G01X1483007Y154337D02*
Y157224D01*
G01X1483494Y152893D02*
X1483007Y154337D01*
G01X1483981Y152171D02*
X1483494Y152893D01*
G01X1484956Y151449D02*
X1483981Y152171D01*
G01X1502008Y156502D02*
X1500059Y155058D01*
G01X1501034Y160111D02*
X1502008Y159389D01*
G01X1500059Y160111D02*
X1501034D01*
G01X1499085Y159389D02*
X1500059Y160111D01*
G01X1498598Y158667D02*
X1499085Y159389D01*
G01X1498598Y151449D02*
X1502495D01*
G01X1499085Y153615D02*
X1498598Y151449D01*
G01X1500059Y155058D02*
X1499085Y153615D01*
G01X1491471Y187014D02*
X1491958Y186292D01*
G01X1491471D02*
Y187014D01*
G01X1491958Y186292D02*
X1491471D01*
G01X1500728Y187014D02*
X1499753Y186292D01*
G01X1501215Y187736D02*
X1500728Y187014D01*
G01Y194232D02*
X1501215Y193510D01*
G01X1499753Y194954D02*
X1500728Y194232D01*
G01X1498779D02*
X1499753Y194954D01*
G01X1498292Y193510D02*
X1498779Y194232D01*
G01X1497805Y192066D02*
X1498292Y193510D01*
G01X1497805Y189179D02*
Y192066D01*
G01X1498292Y187736D02*
X1497805Y189179D01*
G01X1498779Y187014D02*
X1498292Y187736D01*
G01X1499753Y186292D02*
X1498779Y187014D01*
G01X1483188D02*
X1482701Y187736D01*
G01X1484163Y186292D02*
X1483188Y187014D01*
G01X1485137D02*
X1484163Y186292D01*
G01X1485624Y187736D02*
X1485137Y187014D01*
G01X1486112Y189179D02*
X1485624Y187736D01*
G01X1486112Y192066D02*
Y189179D01*
G01X1485624Y193510D02*
X1486112Y192066D01*
G01X1485137Y194232D02*
X1485624Y193510D01*
G01X1484163Y194954D02*
X1485137Y194232D01*
G01X1483188D02*
X1484163Y194954D01*
G01X1482701Y193510D02*
X1483188Y194232D01*
G01X1482214Y192066D02*
X1482701Y193510D01*
G01Y190623D02*
X1482214Y192066D01*
G01X1484163Y189901D02*
X1482701Y190623D01*
G01X1485624D02*
X1484163Y189901D01*
G01X1486112Y192066D02*
X1485624Y190623D01*
G01X1509316Y152171D02*
X1508342Y151449D01*
G01X1509803Y152893D02*
X1509316Y152171D01*
G01X1510290Y154337D02*
X1509803Y152893D01*
G01X1510290Y157224D02*
Y154337D01*
G01X1509803Y158667D02*
X1510290Y157224D01*
G01X1509316Y159389D02*
X1509803Y158667D01*
G01X1508342Y160111D02*
X1509316Y159389D01*
G01X1507367D02*
X1508342Y160111D01*
G01X1506880Y158667D02*
X1507367Y159389D01*
G01X1506393Y157224D02*
X1506880Y158667D01*
G01X1506393Y154337D02*
Y157224D01*
G01X1506880Y152893D02*
X1506393Y154337D01*
G01X1507367Y152171D02*
X1506880Y152893D01*
G01X1508342Y151449D02*
X1507367Y152171D01*
G01X1502495Y157224D02*
X1502008Y156502D01*
G01X1502495Y158667D02*
Y157224D01*
G01X1502008Y159389D02*
X1502495Y158667D01*
G01X1506087Y187014D02*
X1505600Y187736D01*
G01X1507061Y186292D02*
X1506087Y187014D01*
G01X1508036Y186292D02*
X1507061D01*
G01X1509010Y187014D02*
X1508036Y186292D01*
G01X1509498Y187736D02*
X1509010Y187014D01*
G01X1509985Y189179D02*
X1509498Y187736D01*
G01Y190623D02*
X1509985Y189179D01*
G01X1509010Y191345D02*
X1509498Y190623D01*
G01X1508036Y192066D02*
X1509010Y191345D01*
G01X1507061Y192066D02*
X1508036D01*
G01X1506087Y191345D02*
X1507061Y192066D01*
G01X1506574Y194954D02*
X1506087Y191345D01*
G01X1501702Y189179D02*
X1501215Y187736D01*
G01X1501702Y192066D02*
Y189179D01*
G01X1501215Y193510D02*
X1501702Y192066D01*
G01X1509498Y194954D02*
X1506574D01*
G01X1673307Y-374770D02*
Y-118985D01*
G01X1689055Y952789D02*
Y-390518D01*
G01Y-210990D02*
X1706377D01*
G01X1689055Y25230D02*
X1706377D01*
G01X1689055Y261450D02*
X1706377D01*
G01X1689055Y497671D02*
X1706377D01*
G01X1689055Y733891D02*
X1706377D01*
G01Y970112D02*
Y-407840D01*
M02*
